FILE_TYPE = EXPANDEDNETLIST;
{ Packager-XL run on 05-Sep-2022 AT 15:23:30 CONSTRAINTS_VIEW_GENERATED}
NET_NAME
'ANALOG_TUNING_IN'
 '@TIMECARD_LIB.TIMECARD(SCH_1):ANALOG_TUNING_IN':
 C_SIGNAL='@timecard_lib.timecard(sch_1):analog_tuning_in';
NODE_NAME     R91 1
 '@TIMECARD_LIB.TIMECARD(SCH_1):PAGE527_I187@PASSIVE.RESISTOR(CHIPS)':
 '1': CDS_PINID='\1\';
NODE_NAME     MAC_PIN1 1
 '@TIMECARD_LIB.TIMECARD(SCH_1):PAGE527_I227@MECH.NUT(CHIPS)':
 '1': CDS_PINID='\1\';
NET_NAME
'ANT1_IN'
 '@TIMECARD_LIB.TIMECARD(SCH_1):ANT1_IN':
 C_SIGNAL='@timecard_lib.timecard(sch_1):ant1_in';
NODE_NAME     U24 AA21
 '@TIMECARD_LIB.TIMECARD(SCH_1):PAGE161_I2@PLD.XC7A200T_2FBG484C_FBG484(CHIPS)':
 'IO_L8N_T1_D12_14': CDS_PINID='IO_L8N_T1_D12_14';
NODE_NAME     R371 2
 '@TIMECARD_LIB.TIMECARD(SCH_1):PAGE12_I258@PASSIVE.RESISTOR(CHIPS)':
 '2': CDS_PINID='\2\';
NODE_NAME     R504 1
 '@TIMECARD_LIB.TIMECARD(SCH_1):PAGE161_I244@PASSIVE.RESISTOR(CHIPS)':
 '1': CDS_PINID='\1\';
NET_NAME
'ANT1_OUT'
 '@TIMECARD_LIB.TIMECARD(SCH_1):ANT1_OUT':
 C_SIGNAL='@timecard_lib.timecard(sch_1):ant1_out';
NODE_NAME     U24 V10
 '@TIMECARD_LIB.TIMECARD(SCH_1):PAGE161_I2@PLD.XC7A200T_2FBG484C_FBG484(CHIPS)':
 'IO_L10P_T1_13': CDS_PINID='IO_L10P_T1_13';
NODE_NAME     R120 1
 '@TIMECARD_LIB.TIMECARD(SCH_1):PAGE12_I265@PASSIVE.RESISTOR(CHIPS)':
 '1': CDS_PINID='\1\';
NET_NAME
'ANT2_IN'
 '@TIMECARD_LIB.TIMECARD(SCH_1):ANT2_IN':
 C_SIGNAL='@timecard_lib.timecard(sch_1):ant2_in';
NODE_NAME     U24 AA20
 '@TIMECARD_LIB.TIMECARD(SCH_1):PAGE161_I2@PLD.XC7A200T_2FBG484C_FBG484(CHIPS)':
 'IO_L8P_T1_D11_14': CDS_PINID='IO_L8P_T1_D11_14';
NODE_NAME     R372 2
 '@TIMECARD_LIB.TIMECARD(SCH_1):PAGE12_I275@PASSIVE.RESISTOR(CHIPS)':
 '2': CDS_PINID='\2\';
NODE_NAME     R503 1
 '@TIMECARD_LIB.TIMECARD(SCH_1):PAGE161_I246@PASSIVE.RESISTOR(CHIPS)':
 '1': CDS_PINID='\1\';
NET_NAME
'ANT2_OUT'
 '@TIMECARD_LIB.TIMECARD(SCH_1):ANT2_OUT':
 C_SIGNAL='@timecard_lib.timecard(sch_1):ant2_out';
NODE_NAME     U24 W10
 '@TIMECARD_LIB.TIMECARD(SCH_1):PAGE161_I2@PLD.XC7A200T_2FBG484C_FBG484(CHIPS)':
 'IO_L10N_T1_13': CDS_PINID='IO_L10N_T1_13';
NODE_NAME     R121 1
 '@TIMECARD_LIB.TIMECARD(SCH_1):PAGE12_I284@PASSIVE.RESISTOR(CHIPS)':
 '1': CDS_PINID='\1\';
NET_NAME
'ANT3_IN'
 '@TIMECARD_LIB.TIMECARD(SCH_1):ANT3_IN':
 C_SIGNAL='@timecard_lib.timecard(sch_1):ant3_in';
NODE_NAME     U24 Y11
 '@TIMECARD_LIB.TIMECARD(SCH_1):PAGE161_I2@PLD.XC7A200T_2FBG484C_FBG484(CHIPS)':
 'IO_L11P_T1_SRCC_13': CDS_PINID='IO_L11P_T1_SRCC_13';
NODE_NAME     R367 2
 '@TIMECARD_LIB.TIMECARD(SCH_1):PAGE12_I209@PASSIVE.RESISTOR(CHIPS)':
 '2': CDS_PINID='\2\';
NODE_NAME     R500 2
 '@TIMECARD_LIB.TIMECARD(SCH_1):PAGE161_I242@PASSIVE.RESISTOR(CHIPS)':
 '2': CDS_PINID='\2\';
NET_NAME
'ANT3_OUT'
 '@TIMECARD_LIB.TIMECARD(SCH_1):ANT3_OUT':
 C_SIGNAL='@timecard_lib.timecard(sch_1):ant3_out';
NODE_NAME     R156 1
 '@TIMECARD_LIB.TIMECARD(SCH_1):PAGE12_I63@PASSIVE.RESISTOR(CHIPS)':
 '1': CDS_PINID='\1\';
NODE_NAME     U24 W11
 '@TIMECARD_LIB.TIMECARD(SCH_1):PAGE161_I2@PLD.XC7A200T_2FBG484C_FBG484(CHIPS)':
 'IO_L12P_T1_MRCC_13': CDS_PINID='IO_L12P_T1_MRCC_13';
NET_NAME
'ANT4_IN'
 '@TIMECARD_LIB.TIMECARD(SCH_1):ANT4_IN':
 C_SIGNAL='@timecard_lib.timecard(sch_1):ant4_in';
NODE_NAME     U24 Y12
 '@TIMECARD_LIB.TIMECARD(SCH_1):PAGE161_I2@PLD.XC7A200T_2FBG484C_FBG484(CHIPS)':
 'IO_L11N_T1_SRCC_13': CDS_PINID='IO_L11N_T1_SRCC_13';
NODE_NAME     R370 2
 '@TIMECARD_LIB.TIMECARD(SCH_1):PAGE12_I229@PASSIVE.RESISTOR(CHIPS)':
 '2': CDS_PINID='\2\';
NODE_NAME     R501 2
 '@TIMECARD_LIB.TIMECARD(SCH_1):PAGE161_I241@PASSIVE.RESISTOR(CHIPS)':
 '2': CDS_PINID='\2\';
NET_NAME
'ANT4_OUT'
 '@TIMECARD_LIB.TIMECARD(SCH_1):ANT4_OUT':
 C_SIGNAL='@timecard_lib.timecard(sch_1):ant4_out';
NODE_NAME     U24 W12
 '@TIMECARD_LIB.TIMECARD(SCH_1):PAGE161_I2@PLD.XC7A200T_2FBG484C_FBG484(CHIPS)':
 'IO_L12N_T1_MRCC_13': CDS_PINID='IO_L12N_T1_MRCC_13';
NODE_NAME     R157 1
 '@TIMECARD_LIB.TIMECARD(SCH_1):PAGE12_I237@PASSIVE.RESISTOR(CHIPS)':
 '1': CDS_PINID='\1\';
NET_NAME
'BF_ANT1_IN'
 '@TIMECARD_LIB.TIMECARD(SCH_1):BF_ANT1_IN':
 C_SIGNAL='@timecard_lib.timecard(sch_1):bf_ant1_in';
NODE_NAME     U15 3
 '@TIMECARD_LIB.TIMECARD(SCH_1):PAGE12_I255@STDLOGIC.74HCT2G125DP_TSSOP8(CHIPS)':
 '2Y': CDS_PINID='\2y\';
NODE_NAME     R371 1
 '@TIMECARD_LIB.TIMECARD(SCH_1):PAGE12_I258@PASSIVE.RESISTOR(CHIPS)':
 '1': CDS_PINID='\1\';
NET_NAME
'BF_ANT2_IN'
 '@TIMECARD_LIB.TIMECARD(SCH_1):BF_ANT2_IN':
 C_SIGNAL='@timecard_lib.timecard(sch_1):bf_ant2_in';
NODE_NAME     U16 3
 '@TIMECARD_LIB.TIMECARD(SCH_1):PAGE12_I273@STDLOGIC.74HCT2G125DP_TSSOP8(CHIPS)':
 '2Y': CDS_PINID='\2y\';
NODE_NAME     R372 1
 '@TIMECARD_LIB.TIMECARD(SCH_1):PAGE12_I275@PASSIVE.RESISTOR(CHIPS)':
 '1': CDS_PINID='\1\';
NET_NAME
'BF_ANT3_IN'
 '@TIMECARD_LIB.TIMECARD(SCH_1):BF_ANT3_IN':
 C_SIGNAL='@timecard_lib.timecard(sch_1):bf_ant3_in';
NODE_NAME     U13 3
 '@TIMECARD_LIB.TIMECARD(SCH_1):PAGE12_I204@STDLOGIC.74HCT2G125DP_TSSOP8(CHIPS)':
 '2Y': CDS_PINID='\2y\';
NODE_NAME     R367 1
 '@TIMECARD_LIB.TIMECARD(SCH_1):PAGE12_I209@PASSIVE.RESISTOR(CHIPS)':
 '1': CDS_PINID='\1\';
NET_NAME
'BF_ANT4_IN'
 '@TIMECARD_LIB.TIMECARD(SCH_1):BF_ANT4_IN':
 C_SIGNAL='@timecard_lib.timecard(sch_1):bf_ant4_in';
NODE_NAME     U14 3
 '@TIMECARD_LIB.TIMECARD(SCH_1):PAGE12_I226@STDLOGIC.74HCT2G125DP_TSSOP8(CHIPS)':
 '2Y': CDS_PINID='\2y\';
NODE_NAME     R370 1
 '@TIMECARD_LIB.TIMECARD(SCH_1):PAGE12_I229@PASSIVE.RESISTOR(CHIPS)':
 '1': CDS_PINID='\1\';
NET_NAME
'BF_ICP10100_I2C_SCL'
 '@TIMECARD_LIB.TIMECARD(SCH_1):BF_ICP10100_I2C_SCL':
 C_SIGNAL='@timecard_lib.timecard(sch_1):bf_icp10100_i2c_scl';
NODE_NAME     R71 2
 '@TIMECARD_LIB.TIMECARD(SCH_1):PAGE8_I5@PASSIVE.RESISTOR(CHIPS)':
 '2': CDS_PINID='\2\';
NODE_NAME     R73 1
 '@TIMECARD_LIB.TIMECARD(SCH_1):PAGE8_I6@PASSIVE.RESISTOR(CHIPS)':
 '1': CDS_PINID='\1\';
NODE_NAME     U32 2
 '@TIMECARD_LIB.TIMECARD(SCH_1):PAGE8_I51@STDLOGIC.PCA9508DP_TSSOP8(CHIPS)':
 'SCLA': CDS_PINID='SCLA';
NODE_NAME     R315 2
 '@TIMECARD_LIB.TIMECARD(SCH_1):PAGE8_I63@PASSIVE.RESISTOR(CHIPS)':
 '2': CDS_PINID='\2\';
NET_NAME
'BF_ICP10100_I2C_SDA'
 '@TIMECARD_LIB.TIMECARD(SCH_1):BF_ICP10100_I2C_SDA':
 C_SIGNAL='@timecard_lib.timecard(sch_1):bf_icp10100_i2c_sda';
NODE_NAME     R70 2
 '@TIMECARD_LIB.TIMECARD(SCH_1):PAGE8_I3@PASSIVE.RESISTOR(CHIPS)':
 '2': CDS_PINID='\2\';
NODE_NAME     R72 1
 '@TIMECARD_LIB.TIMECARD(SCH_1):PAGE8_I7@PASSIVE.RESISTOR(CHIPS)':
 '1': CDS_PINID='\1\';
NODE_NAME     U32 3
 '@TIMECARD_LIB.TIMECARD(SCH_1):PAGE8_I51@STDLOGIC.PCA9508DP_TSSOP8(CHIPS)':
 'SDAA': CDS_PINID='SDAA';
NODE_NAME     R316 2
 '@TIMECARD_LIB.TIMECARD(SCH_1):PAGE8_I64@PASSIVE.RESISTOR(CHIPS)':
 '2': CDS_PINID='\2\';
NET_NAME
'BF_PCIE_PERST_N'
 '@TIMECARD_LIB.TIMECARD(SCH_1):BF_PCIE_PERST_N':
 C_SIGNAL='@timecard_lib.timecard(sch_1):bf_pcie_perst_n';
NODE_NAME     R356 1
 '@TIMECARD_LIB.TIMECARD(SCH_1):PAGE3_I122@PASSIVE.RESISTOR(CHIPS)':
 '1': CDS_PINID='\1\';
NODE_NAME     U3 4
 '@TIMECARD_LIB.TIMECARD(SCH_1):PAGE3_I134@STDLOGIC.74LVC1G07_SC70_5(CHIPS)':
 'Y': CDS_PINID='Y';
NODE_NAME     R57 1
 '@TIMECARD_LIB.TIMECARD(SCH_1):PAGE3_I153@PASSIVE.RESISTOR(CHIPS)':
 '1': CDS_PINID='\1\';
NET_NAME
'BF_SMA1_SIG_IO_CONN'
 '@TIMECARD_LIB.TIMECARD(SCH_1):BF_SMA1_SIG_IO_CONN':
 C_SIGNAL='@timecard_lib.timecard(sch_1):bf_sma1_sig_io_conn';
NODE_NAME     U15 6
 '@TIMECARD_LIB.TIMECARD(SCH_1):PAGE12_I255@STDLOGIC.74HCT2G125DP_TSSOP8(CHIPS)':
 '1Y': CDS_PINID='\1y\';
NODE_NAME     U15 5
 '@TIMECARD_LIB.TIMECARD(SCH_1):PAGE12_I255@STDLOGIC.74HCT2G125DP_TSSOP8(CHIPS)':
 '2A': CDS_PINID='\2a\';
NODE_NAME     R127 1
 '@TIMECARD_LIB.TIMECARD(SCH_1):PAGE12_I257@PASSIVE.RESISTOR(CHIPS)':
 '1': CDS_PINID='\1\';
NODE_NAME     R498 2
 '@TIMECARD_LIB.TIMECARD(SCH_1):PAGE12_I327@PASSIVE.RESISTOR(CHIPS)':
 '2': CDS_PINID='\2\';
NET_NAME
'BF_SMA2_SIG_IO_CONN'
 '@TIMECARD_LIB.TIMECARD(SCH_1):BF_SMA2_SIG_IO_CONN':
 C_SIGNAL='@timecard_lib.timecard(sch_1):bf_sma2_sig_io_conn';
NODE_NAME     U16 6
 '@TIMECARD_LIB.TIMECARD(SCH_1):PAGE12_I273@STDLOGIC.74HCT2G125DP_TSSOP8(CHIPS)':
 '1Y': CDS_PINID='\1y\';
NODE_NAME     U16 5
 '@TIMECARD_LIB.TIMECARD(SCH_1):PAGE12_I273@STDLOGIC.74HCT2G125DP_TSSOP8(CHIPS)':
 '2A': CDS_PINID='\2a\';
NODE_NAME     R126 1
 '@TIMECARD_LIB.TIMECARD(SCH_1):PAGE12_I276@PASSIVE.RESISTOR(CHIPS)':
 '1': CDS_PINID='\1\';
NODE_NAME     R499 2
 '@TIMECARD_LIB.TIMECARD(SCH_1):PAGE12_I331@PASSIVE.RESISTOR(CHIPS)':
 '2': CDS_PINID='\2\';
NET_NAME
'BF_SMA3_SIG_IO_CONN'
 '@TIMECARD_LIB.TIMECARD(SCH_1):BF_SMA3_SIG_IO_CONN':
 C_SIGNAL='@timecard_lib.timecard(sch_1):bf_sma3_sig_io_conn';
NODE_NAME     R122 1
 '@TIMECARD_LIB.TIMECARD(SCH_1):PAGE12_I197@PASSIVE.RESISTOR(CHIPS)':
 '1': CDS_PINID='\1\';
NODE_NAME     U13 6
 '@TIMECARD_LIB.TIMECARD(SCH_1):PAGE12_I204@STDLOGIC.74HCT2G125DP_TSSOP8(CHIPS)':
 '1Y': CDS_PINID='\1y\';
NODE_NAME     U13 5
 '@TIMECARD_LIB.TIMECARD(SCH_1):PAGE12_I204@STDLOGIC.74HCT2G125DP_TSSOP8(CHIPS)':
 '2A': CDS_PINID='\2a\';
NODE_NAME     R496 2
 '@TIMECARD_LIB.TIMECARD(SCH_1):PAGE12_I320@PASSIVE.RESISTOR(CHIPS)':
 '2': CDS_PINID='\2\';
NET_NAME
'BF_SMA4_SIG_IO_CONN'
 '@TIMECARD_LIB.TIMECARD(SCH_1):BF_SMA4_SIG_IO_CONN':
 C_SIGNAL='@timecard_lib.timecard(sch_1):bf_sma4_sig_io_conn';
NODE_NAME     U14 6
 '@TIMECARD_LIB.TIMECARD(SCH_1):PAGE12_I226@STDLOGIC.74HCT2G125DP_TSSOP8(CHIPS)':
 '1Y': CDS_PINID='\1y\';
NODE_NAME     U14 5
 '@TIMECARD_LIB.TIMECARD(SCH_1):PAGE12_I226@STDLOGIC.74HCT2G125DP_TSSOP8(CHIPS)':
 '2A': CDS_PINID='\2a\';
NODE_NAME     R123 1
 '@TIMECARD_LIB.TIMECARD(SCH_1):PAGE12_I228@PASSIVE.RESISTOR(CHIPS)':
 '1': CDS_PINID='\1\';
NODE_NAME     R497 2
 '@TIMECARD_LIB.TIMECARD(SCH_1):PAGE12_I322@PASSIVE.RESISTOR(CHIPS)':
 '2': CDS_PINID='\2\';
NET_NAME
'BNO080_EVN_SCL'
 '@TIMECARD_LIB.TIMECARD(SCH_1):BNO080_EVN_SCL':
 C_SIGNAL='@timecard_lib.timecard(sch_1):bno080_evn_scl';
NODE_NAME     R342 2
 '@TIMECARD_LIB.TIMECARD(SCH_1):PAGE9_I66@PASSIVE.RESISTOR(CHIPS)':
 '2': CDS_PINID='\2\';
NODE_NAME     R363 2
 '@TIMECARD_LIB.TIMECARD(SCH_1):PAGE9_I67@PASSIVE.RESISTOR(CHIPS)':
 '2': CDS_PINID='\2\';
NODE_NAME     TP2 1
 '@TIMECARD_LIB.TIMECARD(SCH_1):PAGE9_I72@CLS.TP_PIONT(CHIPS)':
 '1': CDS_PINID='\1\';
NET_NAME
'BNO080_EVN_SDA'
 '@TIMECARD_LIB.TIMECARD(SCH_1):BNO080_EVN_SDA':
 C_SIGNAL='@timecard_lib.timecard(sch_1):bno080_evn_sda';
NODE_NAME     R330 2
 '@TIMECARD_LIB.TIMECARD(SCH_1):PAGE9_I64@PASSIVE.RESISTOR(CHIPS)':
 '2': CDS_PINID='\2\';
NODE_NAME     R341 2
 '@TIMECARD_LIB.TIMECARD(SCH_1):PAGE9_I65@PASSIVE.RESISTOR(CHIPS)':
 '2': CDS_PINID='\2\';
NODE_NAME     TP1 1
 '@TIMECARD_LIB.TIMECARD(SCH_1):PAGE9_I71@CLS.TP_PIONT(CHIPS)':
 '1': CDS_PINID='\1\';
NET_NAME
'BNO080_I2C_SCL'
 '@TIMECARD_LIB.TIMECARD(SCH_1):BNO080_I2C_SCL':
 C_SIGNAL='@timecard_lib.timecard(sch_1):bno080_i2c_scl';
NODE_NAME     U4 12
 '@TIMECARD_LIB.TIMECARD(SCH_1):PAGE5_I33@INTERFACE.PCA9546APW_TSSOP16(CHIPS)':
 'SC3': CDS_PINID='SC3';
NODE_NAME     R75 2
 '@TIMECARD_LIB.TIMECARD(SCH_1):PAGE9_I7@PASSIVE.RESISTOR(CHIPS)':
 '2': CDS_PINID='\2\';
NODE_NAME     R77 1
 '@TIMECARD_LIB.TIMECARD(SCH_1):PAGE9_I11@PASSIVE.RESISTOR(CHIPS)':
 '1': CDS_PINID='\1\';
NET_NAME
'BNO080_I2C_SDA'
 '@TIMECARD_LIB.TIMECARD(SCH_1):BNO080_I2C_SDA':
 C_SIGNAL='@timecard_lib.timecard(sch_1):bno080_i2c_sda';
NODE_NAME     U4 11
 '@TIMECARD_LIB.TIMECARD(SCH_1):PAGE5_I33@INTERFACE.PCA9546APW_TSSOP16(CHIPS)':
 'SD3': CDS_PINID='SD3';
NODE_NAME     R74 2
 '@TIMECARD_LIB.TIMECARD(SCH_1):PAGE9_I6@PASSIVE.RESISTOR(CHIPS)':
 '2': CDS_PINID='\2\';
NODE_NAME     R76 1
 '@TIMECARD_LIB.TIMECARD(SCH_1):PAGE9_I12@PASSIVE.RESISTOR(CHIPS)':
 '1': CDS_PINID='\1\';
NET_NAME
'BNO080_SA0'
 '@TIMECARD_LIB.TIMECARD(SCH_1):BNO080_SA0':
 C_SIGNAL='@timecard_lib.timecard(sch_1):bno080_sa0';
NODE_NAME     U29 17
 '@TIMECARD_LIB.TIMECARD(SCH_1):PAGE9_I29@LSI.BNO080_LGA_28(CHIPS)':
 'SA0/H_MOSI': CDS_PINID='\sa0/h_mosi\';
NODE_NAME     R290 2
 '@TIMECARD_LIB.TIMECARD(SCH_1):PAGE9_I51@PASSIVE.RESISTOR(CHIPS)':
 '2': CDS_PINID='\2\';
NODE_NAME     R302 1
 '@TIMECARD_LIB.TIMECARD(SCH_1):PAGE9_I52@PASSIVE.RESISTOR(CHIPS)':
 '1': CDS_PINID='\1\';
NET_NAME
'CARD_PRESENT'
 '@TIMECARD_LIB.TIMECARD(SCH_1):CARD_PRESENT':
 C_SIGNAL='@timecard_lib.timecard(sch_1):card_present';
NODE_NAME     R23 1
 '@TIMECARD_LIB.TIMECARD(SCH_1):PAGE3_I15@PASSIVE.RESISTOR(CHIPS)':
 '1': CDS_PINID='\1\';
NODE_NAME     R22 1
 '@TIMECARD_LIB.TIMECARD(SCH_1):PAGE3_I16@PASSIVE.RESISTOR(CHIPS)':
 '1': CDS_PINID='\1\';
NODE_NAME     GF1 A1
 '@TIMECARD_LIB.TIMECARD(SCH_1):PAGE3_I61@CONNECTOR.CONN_64P_GF(CHIPS)':
 'PRSNT1*': CDS_PINID='\prsnt1*\';
NET_NAME
'CCLK_0'
 '@TIMECARD_LIB.TIMECARD(SCH_1):CCLK_0':
 C_SIGNAL='@timecard_lib.timecard(sch_1):cclk_0';
NODE_NAME     U24 L12
 '@TIMECARD_LIB.TIMECARD(SCH_1):PAGE127_I232@PLD.XC7A200T_2FBG484C_FBG484(CHIPS)':
 'CCLK_0': CDS_PINID='CCLK_0';
NODE_NAME     R207 1
 '@TIMECARD_LIB.TIMECARD(SCH_1):PAGE127_I337@PASSIVE.RESISTOR(CHIPS)':
 '1': CDS_PINID='\1\';
NET_NAME
'CFGBVS'
 '@TIMECARD_LIB.TIMECARD(SCH_1):CFGBVS':
 C_SIGNAL='@timecard_lib.timecard(sch_1):cfgbvs';
NODE_NAME     U24 U8
 '@TIMECARD_LIB.TIMECARD(SCH_1):PAGE127_I232@PLD.XC7A200T_2FBG484C_FBG484(CHIPS)':
 'CFGBVS_0': CDS_PINID='CFGBVS_0';
NODE_NAME     R194 2
 '@TIMECARD_LIB.TIMECARD(SCH_1):PAGE127_I329@PASSIVE.RESISTOR(CHIPS)':
 '2': CDS_PINID='\2\';
NET_NAME
'CLK_125M_OE'
 '@TIMECARD_LIB.TIMECARD(SCH_1):CLK_125M_OE':
 C_SIGNAL='@timecard_lib.timecard(sch_1):clk_125m_oe';
NODE_NAME     Y4 1
 '@TIMECARD_LIB.TIMECARD(SCH_1):PAGE522_I145@CLOCK.OSC6P_V2(CHIPS)':
 'OE': CDS_PINID='OE';
NODE_NAME     R236 2
 '@TIMECARD_LIB.TIMECARD(SCH_1):PAGE522_I156@PASSIVE.RESISTOR(CHIPS)':
 '2': CDS_PINID='\2\';
NODE_NAME     TP50 1
 '@TIMECARD_LIB.TIMECARD(SCH_1):PAGE16_I1701@CLS.TP_PIONT(CHIPS)':
 '1': CDS_PINID='\1\';
NET_NAME
'CLK_200M_OE'
 '@TIMECARD_LIB.TIMECARD(SCH_1):CLK_200M_OE':
 C_SIGNAL='@timecard_lib.timecard(sch_1):clk_200m_oe';
NODE_NAME     Y3 1
 '@TIMECARD_LIB.TIMECARD(SCH_1):PAGE522_I144@CLOCK.OSC6P_V2(CHIPS)':
 'OE': CDS_PINID='OE';
NODE_NAME     R235 2
 '@TIMECARD_LIB.TIMECARD(SCH_1):PAGE522_I149@PASSIVE.RESISTOR(CHIPS)':
 '2': CDS_PINID='\2\';
NODE_NAME     TP49 1
 '@TIMECARD_LIB.TIMECARD(SCH_1):PAGE16_I1699@CLS.TP_PIONT(CHIPS)':
 '1': CDS_PINID='\1\';
NET_NAME
'CONN_MICRO_USB_DM'
 '@TIMECARD_LIB.TIMECARD(SCH_1):CONN_MICRO_USB_DM':
 C_SIGNAL='@timecard_lib.timecard(sch_1):conn_micro_usb_dm';
NODE_NAME     J11 2
 '@TIMECARD_LIB.TIMECARD(SCH_1):PAGE527_I2@CONNECTOR.CONN_USB_1X5_G2_GH4_F_RA_SMT(CHIPS)':
 '2': CDS_PINID='\2\';
NODE_NAME     U9 4
 '@TIMECARD_LIB.TIMECARD(SCH_1):PAGE527_I4@OTHER.CL1001485A(CHIPS)':
 '4': CDS_PINID='\4\';
NODE_NAME     U11 6
 '@TIMECARD_LIB.TIMECARD(SCH_1):PAGE527_I108@STDLOGIC.TS3USB3031RMGR_WQFN12(CHIPS)':
 'USB2_N': CDS_PINID='USB2_N';
NET_NAME
'CONN_MICRO_USB_DP'
 '@TIMECARD_LIB.TIMECARD(SCH_1):CONN_MICRO_USB_DP':
 C_SIGNAL='@timecard_lib.timecard(sch_1):conn_micro_usb_dp';
NODE_NAME     J11 3
 '@TIMECARD_LIB.TIMECARD(SCH_1):PAGE527_I2@CONNECTOR.CONN_USB_1X5_G2_GH4_F_RA_SMT(CHIPS)':
 '3': CDS_PINID='\3\';
NODE_NAME     U9 6
 '@TIMECARD_LIB.TIMECARD(SCH_1):PAGE527_I4@OTHER.CL1001485A(CHIPS)':
 '6': CDS_PINID='\6\';
NODE_NAME     U11 5
 '@TIMECARD_LIB.TIMECARD(SCH_1):PAGE527_I108@STDLOGIC.TS3USB3031RMGR_WQFN12(CHIPS)':
 'USB2_P': CDS_PINID='USB2_P';
NET_NAME
'CPU_RX_PCIE_MGT0_TXN'
 '@TIMECARD_LIB.TIMECARD(SCH_1):CPU_RX_PCIE_MGT0_TXN':
 C_SIGNAL='@timecard_lib.timecard(sch_1):cpu_rx_pcie_mgt0_txn';
NODE_NAME     U24 A4
 '@TIMECARD_LIB.TIMECARD(SCH_1):PAGE127_I232@PLD.XC7A200T_2FBG484C_FBG484(CHIPS)':
 'MGTPTXN0_216': CDS_PINID='MGTPTXN0_216';
NODE_NAME     C25 2
 '@TIMECARD_LIB.TIMECARD(SCH_1):PAGE3_I115@PASSIVE.CAPACITOR(CHIPS)':
 '2': CDS_PINID='\2\';
NET_NAME
'CPU_RX_PCIE_MGT0_TXP'
 '@TIMECARD_LIB.TIMECARD(SCH_1):CPU_RX_PCIE_MGT0_TXP':
 C_SIGNAL='@timecard_lib.timecard(sch_1):cpu_rx_pcie_mgt0_txp';
NODE_NAME     C24 2
 '@TIMECARD_LIB.TIMECARD(SCH_1):PAGE3_I35@PASSIVE.CAPACITOR(CHIPS)':
 '2': CDS_PINID='\2\';
NODE_NAME     U24 B4
 '@TIMECARD_LIB.TIMECARD(SCH_1):PAGE127_I232@PLD.XC7A200T_2FBG484C_FBG484(CHIPS)':
 'MGTPTXP0_216': CDS_PINID='MGTPTXP0_216';
NET_NAME
'CPU_RX_PCIE_MGT1_TXN'
 '@TIMECARD_LIB.TIMECARD(SCH_1):CPU_RX_PCIE_MGT1_TXN':
 C_SIGNAL='@timecard_lib.timecard(sch_1):cpu_rx_pcie_mgt1_txn';
NODE_NAME     U24 C5
 '@TIMECARD_LIB.TIMECARD(SCH_1):PAGE127_I232@PLD.XC7A200T_2FBG484C_FBG484(CHIPS)':
 'MGTPTXN1_216': CDS_PINID='MGTPTXN1_216';
NODE_NAME     C27 2
 '@TIMECARD_LIB.TIMECARD(SCH_1):PAGE3_I117@PASSIVE.CAPACITOR(CHIPS)':
 '2': CDS_PINID='\2\';
NET_NAME
'CPU_RX_PCIE_MGT1_TXP'
 '@TIMECARD_LIB.TIMECARD(SCH_1):CPU_RX_PCIE_MGT1_TXP':
 C_SIGNAL='@timecard_lib.timecard(sch_1):cpu_rx_pcie_mgt1_txp';
NODE_NAME     U24 D5
 '@TIMECARD_LIB.TIMECARD(SCH_1):PAGE127_I232@PLD.XC7A200T_2FBG484C_FBG484(CHIPS)':
 'MGTPTXP1_216': CDS_PINID='MGTPTXP1_216';
NODE_NAME     C26 2
 '@TIMECARD_LIB.TIMECARD(SCH_1):PAGE3_I116@PASSIVE.CAPACITOR(CHIPS)':
 '2': CDS_PINID='\2\';
NET_NAME
'CPU_RX_PCIE_MGT2_TXN'
 '@TIMECARD_LIB.TIMECARD(SCH_1):CPU_RX_PCIE_MGT2_TXN':
 C_SIGNAL='@timecard_lib.timecard(sch_1):cpu_rx_pcie_mgt2_txn';
NODE_NAME     U24 A6
 '@TIMECARD_LIB.TIMECARD(SCH_1):PAGE127_I232@PLD.XC7A200T_2FBG484C_FBG484(CHIPS)':
 'MGTPTXN2_216': CDS_PINID='MGTPTXN2_216';
NODE_NAME     C34 2
 '@TIMECARD_LIB.TIMECARD(SCH_1):PAGE3_I119@PASSIVE.CAPACITOR(CHIPS)':
 '2': CDS_PINID='\2\';
NET_NAME
'CPU_RX_PCIE_MGT2_TXP'
 '@TIMECARD_LIB.TIMECARD(SCH_1):CPU_RX_PCIE_MGT2_TXP':
 C_SIGNAL='@timecard_lib.timecard(sch_1):cpu_rx_pcie_mgt2_txp';
NODE_NAME     U24 B6
 '@TIMECARD_LIB.TIMECARD(SCH_1):PAGE127_I232@PLD.XC7A200T_2FBG484C_FBG484(CHIPS)':
 'MGTPTXP2_216': CDS_PINID='MGTPTXP2_216';
NODE_NAME     C28 2
 '@TIMECARD_LIB.TIMECARD(SCH_1):PAGE3_I118@PASSIVE.CAPACITOR(CHIPS)':
 '2': CDS_PINID='\2\';
NET_NAME
'CPU_RX_PCIE_MGT3_TXN'
 '@TIMECARD_LIB.TIMECARD(SCH_1):CPU_RX_PCIE_MGT3_TXN':
 C_SIGNAL='@timecard_lib.timecard(sch_1):cpu_rx_pcie_mgt3_txn';
NODE_NAME     U24 C7
 '@TIMECARD_LIB.TIMECARD(SCH_1):PAGE127_I232@PLD.XC7A200T_2FBG484C_FBG484(CHIPS)':
 'MGTPTXN3_216': CDS_PINID='MGTPTXN3_216';
NODE_NAME     C36 2
 '@TIMECARD_LIB.TIMECARD(SCH_1):PAGE3_I121@PASSIVE.CAPACITOR(CHIPS)':
 '2': CDS_PINID='\2\';
NET_NAME
'CPU_RX_PCIE_MGT3_TXP'
 '@TIMECARD_LIB.TIMECARD(SCH_1):CPU_RX_PCIE_MGT3_TXP':
 C_SIGNAL='@timecard_lib.timecard(sch_1):cpu_rx_pcie_mgt3_txp';
NODE_NAME     U24 D7
 '@TIMECARD_LIB.TIMECARD(SCH_1):PAGE127_I232@PLD.XC7A200T_2FBG484C_FBG484(CHIPS)':
 'MGTPTXP3_216': CDS_PINID='MGTPTXP3_216';
NODE_NAME     C35 2
 '@TIMECARD_LIB.TIMECARD(SCH_1):PAGE3_I120@PASSIVE.CAPACITOR(CHIPS)':
 '2': CDS_PINID='\2\';
NET_NAME
'CPU_TX_PCIE_MGT_0_RXN'
 '@TIMECARD_LIB.TIMECARD(SCH_1):CPU_TX_PCIE_MGT_0_RXN':
 C_SIGNAL='@timecard_lib.timecard(sch_1):cpu_tx_pcie_mgt_0_rxn';
NODE_NAME     GF1 B15
 '@TIMECARD_LIB.TIMECARD(SCH_1):PAGE3_I61@CONNECTOR.CONN_64P_GF(CHIPS)':
 'PETN0': CDS_PINID='PETN0';
NODE_NAME     U24 A8
 '@TIMECARD_LIB.TIMECARD(SCH_1):PAGE127_I232@PLD.XC7A200T_2FBG484C_FBG484(CHIPS)':
 'MGTPRXN0_216': CDS_PINID='MGTPRXN0_216';
NET_NAME
'CPU_TX_PCIE_MGT_0_RXP'
 '@TIMECARD_LIB.TIMECARD(SCH_1):CPU_TX_PCIE_MGT_0_RXP':
 C_SIGNAL='@timecard_lib.timecard(sch_1):cpu_tx_pcie_mgt_0_rxp';
NODE_NAME     GF1 B14
 '@TIMECARD_LIB.TIMECARD(SCH_1):PAGE3_I61@CONNECTOR.CONN_64P_GF(CHIPS)':
 'PETP0': CDS_PINID='PETP0';
NODE_NAME     U24 B8
 '@TIMECARD_LIB.TIMECARD(SCH_1):PAGE127_I232@PLD.XC7A200T_2FBG484C_FBG484(CHIPS)':
 'MGTPRXP0_216': CDS_PINID='MGTPRXP0_216';
NET_NAME
'CPU_TX_PCIE_MGT_1_RXN'
 '@TIMECARD_LIB.TIMECARD(SCH_1):CPU_TX_PCIE_MGT_1_RXN':
 C_SIGNAL='@timecard_lib.timecard(sch_1):cpu_tx_pcie_mgt_1_rxn';
NODE_NAME     GF1 B20
 '@TIMECARD_LIB.TIMECARD(SCH_1):PAGE3_I61@CONNECTOR.CONN_64P_GF(CHIPS)':
 'PETN1': CDS_PINID='PETN1';
NODE_NAME     U24 C11
 '@TIMECARD_LIB.TIMECARD(SCH_1):PAGE127_I232@PLD.XC7A200T_2FBG484C_FBG484(CHIPS)':
 'MGTPRXN1_216': CDS_PINID='MGTPRXN1_216';
NET_NAME
'CPU_TX_PCIE_MGT_1_RXP'
 '@TIMECARD_LIB.TIMECARD(SCH_1):CPU_TX_PCIE_MGT_1_RXP':
 C_SIGNAL='@timecard_lib.timecard(sch_1):cpu_tx_pcie_mgt_1_rxp';
NODE_NAME     GF1 B19
 '@TIMECARD_LIB.TIMECARD(SCH_1):PAGE3_I61@CONNECTOR.CONN_64P_GF(CHIPS)':
 'PETP1': CDS_PINID='PETP1';
NODE_NAME     U24 D11
 '@TIMECARD_LIB.TIMECARD(SCH_1):PAGE127_I232@PLD.XC7A200T_2FBG484C_FBG484(CHIPS)':
 'MGTPRXP1_216': CDS_PINID='MGTPRXP1_216';
NET_NAME
'CPU_TX_PCIE_MGT_2_RXN'
 '@TIMECARD_LIB.TIMECARD(SCH_1):CPU_TX_PCIE_MGT_2_RXN':
 C_SIGNAL='@timecard_lib.timecard(sch_1):cpu_tx_pcie_mgt_2_rxn';
NODE_NAME     GF1 B24
 '@TIMECARD_LIB.TIMECARD(SCH_1):PAGE3_I61@CONNECTOR.CONN_64P_GF(CHIPS)':
 'PETN2': CDS_PINID='PETN2';
NODE_NAME     U24 A10
 '@TIMECARD_LIB.TIMECARD(SCH_1):PAGE127_I232@PLD.XC7A200T_2FBG484C_FBG484(CHIPS)':
 'MGTPRXN2_216': CDS_PINID='MGTPRXN2_216';
NET_NAME
'CPU_TX_PCIE_MGT_2_RXP'
 '@TIMECARD_LIB.TIMECARD(SCH_1):CPU_TX_PCIE_MGT_2_RXP':
 C_SIGNAL='@timecard_lib.timecard(sch_1):cpu_tx_pcie_mgt_2_rxp';
NODE_NAME     GF1 B23
 '@TIMECARD_LIB.TIMECARD(SCH_1):PAGE3_I61@CONNECTOR.CONN_64P_GF(CHIPS)':
 'PETP2': CDS_PINID='PETP2';
NODE_NAME     U24 B10
 '@TIMECARD_LIB.TIMECARD(SCH_1):PAGE127_I232@PLD.XC7A200T_2FBG484C_FBG484(CHIPS)':
 'MGTPRXP2_216': CDS_PINID='MGTPRXP2_216';
NET_NAME
'CPU_TX_PCIE_MGT_3_RXN'
 '@TIMECARD_LIB.TIMECARD(SCH_1):CPU_TX_PCIE_MGT_3_RXN':
 C_SIGNAL='@timecard_lib.timecard(sch_1):cpu_tx_pcie_mgt_3_rxn';
NODE_NAME     GF1 B28
 '@TIMECARD_LIB.TIMECARD(SCH_1):PAGE3_I61@CONNECTOR.CONN_64P_GF(CHIPS)':
 'PETN3': CDS_PINID='PETN3';
NODE_NAME     U24 C9
 '@TIMECARD_LIB.TIMECARD(SCH_1):PAGE127_I232@PLD.XC7A200T_2FBG484C_FBG484(CHIPS)':
 'MGTPRXN3_216': CDS_PINID='MGTPRXN3_216';
NET_NAME
'CPU_TX_PCIE_MGT_3_RXP'
 '@TIMECARD_LIB.TIMECARD(SCH_1):CPU_TX_PCIE_MGT_3_RXP':
 C_SIGNAL='@timecard_lib.timecard(sch_1):cpu_tx_pcie_mgt_3_rxp';
NODE_NAME     GF1 B27
 '@TIMECARD_LIB.TIMECARD(SCH_1):PAGE3_I61@CONNECTOR.CONN_64P_GF(CHIPS)':
 'PETP3': CDS_PINID='PETP3';
NODE_NAME     U24 D9
 '@TIMECARD_LIB.TIMECARD(SCH_1):PAGE127_I232@PLD.XC7A200T_2FBG484C_FBG484(CHIPS)':
 'MGTPRXP3_216': CDS_PINID='MGTPRXP3_216';
NET_NAME
'C_CPU_RX_PCIE_MGT0_TXN'
 '@TIMECARD_LIB.TIMECARD(SCH_1):C_CPU_RX_PCIE_MGT0_TXN':
 C_SIGNAL='@timecard_lib.timecard(sch_1):c_cpu_rx_pcie_mgt0_txn';
NODE_NAME     GF1 A17
 '@TIMECARD_LIB.TIMECARD(SCH_1):PAGE3_I61@CONNECTOR.CONN_64P_GF(CHIPS)':
 'PERN0': CDS_PINID='PERN0';
NODE_NAME     C25 1
 '@TIMECARD_LIB.TIMECARD(SCH_1):PAGE3_I115@PASSIVE.CAPACITOR(CHIPS)':
 '1': CDS_PINID='\1\';
NET_NAME
'C_CPU_RX_PCIE_MGT0_TXP'
 '@TIMECARD_LIB.TIMECARD(SCH_1):C_CPU_RX_PCIE_MGT0_TXP':
 C_SIGNAL='@timecard_lib.timecard(sch_1):c_cpu_rx_pcie_mgt0_txp';
NODE_NAME     C24 1
 '@TIMECARD_LIB.TIMECARD(SCH_1):PAGE3_I35@PASSIVE.CAPACITOR(CHIPS)':
 '1': CDS_PINID='\1\';
NODE_NAME     GF1 A16
 '@TIMECARD_LIB.TIMECARD(SCH_1):PAGE3_I61@CONNECTOR.CONN_64P_GF(CHIPS)':
 'PERP0': CDS_PINID='PERP0';
NET_NAME
'C_CPU_RX_PCIE_MGT1_TXN'
 '@TIMECARD_LIB.TIMECARD(SCH_1):C_CPU_RX_PCIE_MGT1_TXN':
 C_SIGNAL='@timecard_lib.timecard(sch_1):c_cpu_rx_pcie_mgt1_txn';
NODE_NAME     GF1 A22
 '@TIMECARD_LIB.TIMECARD(SCH_1):PAGE3_I61@CONNECTOR.CONN_64P_GF(CHIPS)':
 'PERN1': CDS_PINID='PERN1';
NODE_NAME     C27 1
 '@TIMECARD_LIB.TIMECARD(SCH_1):PAGE3_I117@PASSIVE.CAPACITOR(CHIPS)':
 '1': CDS_PINID='\1\';
NET_NAME
'C_CPU_RX_PCIE_MGT1_TXP'
 '@TIMECARD_LIB.TIMECARD(SCH_1):C_CPU_RX_PCIE_MGT1_TXP':
 C_SIGNAL='@timecard_lib.timecard(sch_1):c_cpu_rx_pcie_mgt1_txp';
NODE_NAME     GF1 A21
 '@TIMECARD_LIB.TIMECARD(SCH_1):PAGE3_I61@CONNECTOR.CONN_64P_GF(CHIPS)':
 'PERP1': CDS_PINID='PERP1';
NODE_NAME     C26 1
 '@TIMECARD_LIB.TIMECARD(SCH_1):PAGE3_I116@PASSIVE.CAPACITOR(CHIPS)':
 '1': CDS_PINID='\1\';
NET_NAME
'C_CPU_RX_PCIE_MGT2_TXN'
 '@TIMECARD_LIB.TIMECARD(SCH_1):C_CPU_RX_PCIE_MGT2_TXN':
 C_SIGNAL='@timecard_lib.timecard(sch_1):c_cpu_rx_pcie_mgt2_txn';
NODE_NAME     GF1 A26
 '@TIMECARD_LIB.TIMECARD(SCH_1):PAGE3_I61@CONNECTOR.CONN_64P_GF(CHIPS)':
 'PERN2': CDS_PINID='PERN2';
NODE_NAME     C34 1
 '@TIMECARD_LIB.TIMECARD(SCH_1):PAGE3_I119@PASSIVE.CAPACITOR(CHIPS)':
 '1': CDS_PINID='\1\';
NET_NAME
'C_CPU_RX_PCIE_MGT2_TXP'
 '@TIMECARD_LIB.TIMECARD(SCH_1):C_CPU_RX_PCIE_MGT2_TXP':
 C_SIGNAL='@timecard_lib.timecard(sch_1):c_cpu_rx_pcie_mgt2_txp';
NODE_NAME     GF1 A25
 '@TIMECARD_LIB.TIMECARD(SCH_1):PAGE3_I61@CONNECTOR.CONN_64P_GF(CHIPS)':
 'PERP2': CDS_PINID='PERP2';
NODE_NAME     C28 1
 '@TIMECARD_LIB.TIMECARD(SCH_1):PAGE3_I118@PASSIVE.CAPACITOR(CHIPS)':
 '1': CDS_PINID='\1\';
NET_NAME
'C_CPU_RX_PCIE_MGT3_TXN'
 '@TIMECARD_LIB.TIMECARD(SCH_1):C_CPU_RX_PCIE_MGT3_TXN':
 C_SIGNAL='@timecard_lib.timecard(sch_1):c_cpu_rx_pcie_mgt3_txn';
NODE_NAME     GF1 A30
 '@TIMECARD_LIB.TIMECARD(SCH_1):PAGE3_I61@CONNECTOR.CONN_64P_GF(CHIPS)':
 'PERN3': CDS_PINID='PERN3';
NODE_NAME     C36 1
 '@TIMECARD_LIB.TIMECARD(SCH_1):PAGE3_I121@PASSIVE.CAPACITOR(CHIPS)':
 '1': CDS_PINID='\1\';
NET_NAME
'C_CPU_RX_PCIE_MGT3_TXP'
 '@TIMECARD_LIB.TIMECARD(SCH_1):C_CPU_RX_PCIE_MGT3_TXP':
 C_SIGNAL='@timecard_lib.timecard(sch_1):c_cpu_rx_pcie_mgt3_txp';
NODE_NAME     GF1 A29
 '@TIMECARD_LIB.TIMECARD(SCH_1):PAGE3_I61@CONNECTOR.CONN_64P_GF(CHIPS)':
 'PERP3': CDS_PINID='PERP3';
NODE_NAME     C35 1
 '@TIMECARD_LIB.TIMECARD(SCH_1):PAGE3_I120@PASSIVE.CAPACITOR(CHIPS)':
 '1': CDS_PINID='\1\';
NET_NAME
'C_PCIEREFCLKN'
 '@TIMECARD_LIB.TIMECARD(SCH_1):C_PCIEREFCLKN':
 C_SIGNAL='@timecard_lib.timecard(sch_1):c_pcierefclkn';
NODE_NAME     C23 1
 '@TIMECARD_LIB.TIMECARD(SCH_1):PAGE3_I37@PASSIVE.CAPACITOR(CHIPS)':
 '1': CDS_PINID='\1\';
NODE_NAME     GF1 A14
 '@TIMECARD_LIB.TIMECARD(SCH_1):PAGE3_I61@CONNECTOR.CONN_64P_GF(CHIPS)':
 'REFCLK_N': CDS_PINID='REFCLK_N';
NET_NAME
'C_PCIEREFCLKP'
 '@TIMECARD_LIB.TIMECARD(SCH_1):C_PCIEREFCLKP':
 C_SIGNAL='@timecard_lib.timecard(sch_1):c_pcierefclkp';
NODE_NAME     C19 1
 '@TIMECARD_LIB.TIMECARD(SCH_1):PAGE3_I36@PASSIVE.CAPACITOR(CHIPS)':
 '1': CDS_PINID='\1\';
NODE_NAME     GF1 A13
 '@TIMECARD_LIB.TIMECARD(SCH_1):PAGE3_I61@CONNECTOR.CONN_64P_GF(CHIPS)':
 'REFCLK_P': CDS_PINID='REFCLK_P';
NET_NAME
'DBG_UART_GPS_RXD'
 '@TIMECARD_LIB.TIMECARD(SCH_1):DBG_UART_GPS_RXD':
 C_SIGNAL='@timecard_lib.timecard(sch_1):dbg_uart_gps_rxd';
NODE_NAME     R113 1
 '@TIMECARD_LIB.TIMECARD(SCH_1):PAGE11_I7@PASSIVE.RESISTOR(CHIPS)':
 '1': CDS_PINID='\1\';
NODE_NAME     J10 4
 '@TIMECARD_LIB.TIMECARD(SCH_1):PAGE524_I173@CONNECTOR.G200_10283_01(CHIPS)':
 '4': CDS_PINID='\4\';
NET_NAME
'DBG_UART_GPS_TXD'
 '@TIMECARD_LIB.TIMECARD(SCH_1):DBG_UART_GPS_TXD':
 C_SIGNAL='@timecard_lib.timecard(sch_1):dbg_uart_gps_txd';
NODE_NAME     R112 1
 '@TIMECARD_LIB.TIMECARD(SCH_1):PAGE11_I8@PASSIVE.RESISTOR(CHIPS)':
 '1': CDS_PINID='\1\';
NODE_NAME     J10 8
 '@TIMECARD_LIB.TIMECARD(SCH_1):PAGE524_I173@CONNECTOR.G200_10283_01(CHIPS)':
 '8': CDS_PINID='\8\';
NET_NAME
'DBG_UART_MAC_RX'
 '@TIMECARD_LIB.TIMECARD(SCH_1):DBG_UART_MAC_RX':
 C_SIGNAL='@timecard_lib.timecard(sch_1):dbg_uart_mac_rx';
NODE_NAME     J10 2
 '@TIMECARD_LIB.TIMECARD(SCH_1):PAGE524_I173@CONNECTOR.G200_10283_01(CHIPS)':
 '2': CDS_PINID='\2\';
NODE_NAME     R81 2
 '@TIMECARD_LIB.TIMECARD(SCH_1):PAGE527_I240@PASSIVE.RESISTOR(CHIPS)':
 '2': CDS_PINID='\2\';
NET_NAME
'DBG_UART_MAC_TX'
 '@TIMECARD_LIB.TIMECARD(SCH_1):DBG_UART_MAC_TX':
 C_SIGNAL='@timecard_lib.timecard(sch_1):dbg_uart_mac_tx';
NODE_NAME     J10 6
 '@TIMECARD_LIB.TIMECARD(SCH_1):PAGE524_I173@CONNECTOR.G200_10283_01(CHIPS)':
 '6': CDS_PINID='\6\';
NODE_NAME     R82 2
 '@TIMECARD_LIB.TIMECARD(SCH_1):PAGE527_I241@PASSIVE.RESISTOR(CHIPS)':
 '2': CDS_PINID='\2\';
NET_NAME
'EEPROM_I2C_SCL'
 '@TIMECARD_LIB.TIMECARD(SCH_1):EEPROM_I2C_SCL':
 C_SIGNAL='@timecard_lib.timecard(sch_1):eeprom_i2c_scl';
NODE_NAME     R184 1
 '@TIMECARD_LIB.TIMECARD(SCH_1):PAGE5_I103@PASSIVE.RESISTOR(CHIPS)':
 '1': CDS_PINID='\1\';
NODE_NAME     U37 12
 '@TIMECARD_LIB.TIMECARD(SCH_1):PAGE524_I448@STDLOGIC.TS3A5018PWR_TSSOP16(CHIPS)':
 'COM4': CDS_PINID='COM4';
NET_NAME
'EEPROM_I2C_SDA'
 '@TIMECARD_LIB.TIMECARD(SCH_1):EEPROM_I2C_SDA':
 C_SIGNAL='@timecard_lib.timecard(sch_1):eeprom_i2c_sda';
NODE_NAME     R183 1
 '@TIMECARD_LIB.TIMECARD(SCH_1):PAGE5_I101@PASSIVE.RESISTOR(CHIPS)':
 '1': CDS_PINID='\1\';
NODE_NAME     U37 9
 '@TIMECARD_LIB.TIMECARD(SCH_1):PAGE524_I448@STDLOGIC.TS3A5018PWR_TSSOP16(CHIPS)':
 'COM3': CDS_PINID='COM3';
NET_NAME
'EEPROM_SCL'
 '@TIMECARD_LIB.TIMECARD(SCH_1):EEPROM_SCL':
 C_SIGNAL='@timecard_lib.timecard(sch_1):eeprom_scl';
NODE_NAME     U7 1
 '@TIMECARD_LIB.TIMECARD(SCH_1):PAGE5_I89@MEMORY.AT24MAC402_SOT23_5(CHIPS)':
 'SCL': CDS_PINID='SCL';
NODE_NAME     R19 2
 '@TIMECARD_LIB.TIMECARD(SCH_1):PAGE5_I95@PASSIVE.RESISTOR(CHIPS)':
 '2': CDS_PINID='\2\';
NODE_NAME     R176 2
 '@TIMECARD_LIB.TIMECARD(SCH_1):PAGE5_I102@PASSIVE.RESISTOR(CHIPS)':
 '2': CDS_PINID='\2\';
NODE_NAME     R184 2
 '@TIMECARD_LIB.TIMECARD(SCH_1):PAGE5_I103@PASSIVE.RESISTOR(CHIPS)':
 '2': CDS_PINID='\2\';
NODE_NAME     R313 2
 '@TIMECARD_LIB.TIMECARD(SCH_1):PAGE5_I111@PASSIVE.RESISTOR(CHIPS)':
 '2': CDS_PINID='\2\';
NODE_NAME     J9 4
 '@TIMECARD_LIB.TIMECARD(SCH_1):PAGE5_I126@CONNECTOR.CONN_HDR_2X2_M_S_SMT(CHIPS)':
 '4': CDS_PINID='\4\';
NODE_NAME     U19 6
 '@TIMECARD_LIB.TIMECARD(SCH_1):PAGE5_I151@MEMORY.24LC16BT_I_ST_TSSOP8(CHIPS)':
 'SCL': CDS_PINID='SCL';
NET_NAME
'EEPROM_SDA'
 '@TIMECARD_LIB.TIMECARD(SCH_1):EEPROM_SDA':
 C_SIGNAL='@timecard_lib.timecard(sch_1):eeprom_sda';
NODE_NAME     R345 1
 '@TIMECARD_LIB.TIMECARD(SCH_1):PAGE5_I90@PASSIVE.RESISTOR(CHIPS)':
 '1': CDS_PINID='\1\';
NODE_NAME     R1991 2
 '@TIMECARD_LIB.TIMECARD(SCH_1):PAGE5_I96@PASSIVE.RESISTOR(CHIPS)':
 '2': CDS_PINID='\2\';
NODE_NAME     R175 2
 '@TIMECARD_LIB.TIMECARD(SCH_1):PAGE5_I100@PASSIVE.RESISTOR(CHIPS)':
 '2': CDS_PINID='\2\';
NODE_NAME     R183 2
 '@TIMECARD_LIB.TIMECARD(SCH_1):PAGE5_I101@PASSIVE.RESISTOR(CHIPS)':
 '2': CDS_PINID='\2\';
NODE_NAME     R312 2
 '@TIMECARD_LIB.TIMECARD(SCH_1):PAGE5_I112@PASSIVE.RESISTOR(CHIPS)':
 '2': CDS_PINID='\2\';
NODE_NAME     J9 2
 '@TIMECARD_LIB.TIMECARD(SCH_1):PAGE5_I126@CONNECTOR.CONN_HDR_2X2_M_S_SMT(CHIPS)':
 '2': CDS_PINID='\2\';
NODE_NAME     R45 1
 '@TIMECARD_LIB.TIMECARD(SCH_1):PAGE5_I162@PASSIVE.RESISTOR(CHIPS)':
 '1': CDS_PINID='\1\';
NET_NAME
'FLASH_CLK'
 '@TIMECARD_LIB.TIMECARD(SCH_1):FLASH_CLK':
 C_SIGNAL='@timecard_lib.timecard(sch_1):flash_clk';
NODE_NAME     U38 4
 '@TIMECARD_LIB.TIMECARD(SCH_1):PAGE524_I400@STDLOGIC.TS3A5018PWR_TSSOP16(CHIPS)':
 'COM1': CDS_PINID='COM1';
NODE_NAME     U23 6
 '@TIMECARD_LIB.TIMECARD(SCH_1):PAGE127_I456@MEMORY.MT25QL128ABA1ESE_SOP8(CHIPS)':
 'C': CDS_PINID='C';
NODE_NAME     R192 1
 '@TIMECARD_LIB.TIMECARD(SCH_1):PAGE127_I470@PASSIVE.RESISTOR(CHIPS)':
 '1': CDS_PINID='\1\';
NET_NAME
'FLASH_CS_N'
 '@TIMECARD_LIB.TIMECARD(SCH_1):FLASH_CS_N':
 C_SIGNAL='@timecard_lib.timecard(sch_1):flash_cs_n';
NODE_NAME     U38 12
 '@TIMECARD_LIB.TIMECARD(SCH_1):PAGE524_I400@STDLOGIC.TS3A5018PWR_TSSOP16(CHIPS)':
 'COM4': CDS_PINID='COM4';
NODE_NAME     U23 1
 '@TIMECARD_LIB.TIMECARD(SCH_1):PAGE127_I456@MEMORY.MT25QL128ABA1ESE_SOP8(CHIPS)':
 'S*': CDS_PINID='\s*\';
NODE_NAME     R191 2
 '@TIMECARD_LIB.TIMECARD(SCH_1):PAGE127_I471@PASSIVE.RESISTOR(CHIPS)':
 '2': CDS_PINID='\2\';
NET_NAME
'FLASH_DQ0_MOSI'
 '@TIMECARD_LIB.TIMECARD(SCH_1):FLASH_DQ0_MOSI':
 C_SIGNAL='@timecard_lib.timecard(sch_1):flash_dq0_mosi';
NODE_NAME     U38 7
 '@TIMECARD_LIB.TIMECARD(SCH_1):PAGE524_I400@STDLOGIC.TS3A5018PWR_TSSOP16(CHIPS)':
 'COM2': CDS_PINID='COM2';
NODE_NAME     R203 2
 '@TIMECARD_LIB.TIMECARD(SCH_1):PAGE127_I467@PASSIVE.RESISTOR(CHIPS)':
 '2': CDS_PINID='\2\';
NET_NAME
'FLASH_DQ1_MISO'
 '@TIMECARD_LIB.TIMECARD(SCH_1):FLASH_DQ1_MISO':
 C_SIGNAL='@timecard_lib.timecard(sch_1):flash_dq1_miso';
NODE_NAME     U38 9
 '@TIMECARD_LIB.TIMECARD(SCH_1):PAGE524_I400@STDLOGIC.TS3A5018PWR_TSSOP16(CHIPS)':
 'COM3': CDS_PINID='COM3';
NODE_NAME     R204 2
 '@TIMECARD_LIB.TIMECARD(SCH_1):PAGE127_I466@PASSIVE.RESISTOR(CHIPS)':
 '2': CDS_PINID='\2\';
NET_NAME
'FLASH_DQ2'
 '@TIMECARD_LIB.TIMECARD(SCH_1):FLASH_DQ2':
 C_SIGNAL='@timecard_lib.timecard(sch_1):flash_dq2';
NODE_NAME     U39 3
 '@TIMECARD_LIB.TIMECARD(SCH_1):PAGE524_I407@INTERFACE.NLASB3157DFT2G_SC88(CHIPS)':
 'B0': CDS_PINID='B0';
NODE_NAME     R464 2
 '@TIMECARD_LIB.TIMECARD(SCH_1):PAGE524_I493@PASSIVE.RESISTOR(CHIPS)':
 '2': CDS_PINID='\2\';
NODE_NAME     R205 2
 '@TIMECARD_LIB.TIMECARD(SCH_1):PAGE127_I468@PASSIVE.RESISTOR(CHIPS)':
 '2': CDS_PINID='\2\';
NET_NAME
'FLASH_DQ3'
 '@TIMECARD_LIB.TIMECARD(SCH_1):FLASH_DQ3':
 C_SIGNAL='@timecard_lib.timecard(sch_1):flash_dq3';
NODE_NAME     U40 3
 '@TIMECARD_LIB.TIMECARD(SCH_1):PAGE524_I408@INTERFACE.NLASB3157DFT2G_SC88(CHIPS)':
 'B0': CDS_PINID='B0';
NODE_NAME     R465 2
 '@TIMECARD_LIB.TIMECARD(SCH_1):PAGE524_I494@PASSIVE.RESISTOR(CHIPS)':
 '2': CDS_PINID='\2\';
NODE_NAME     R206 2
 '@TIMECARD_LIB.TIMECARD(SCH_1):PAGE127_I469@PASSIVE.RESISTOR(CHIPS)':
 '2': CDS_PINID='\2\';
NET_NAME
'FPGA_BRD_REV0'
 '@TIMECARD_LIB.TIMECARD(SCH_1):FPGA_BRD_REV0':
 C_SIGNAL='@timecard_lib.timecard(sch_1):fpga_brd_rev0';
NODE_NAME     R219 2
 '@TIMECARD_LIB.TIMECARD(SCH_1):PAGE127_I392@PASSIVE.RESISTOR(CHIPS)':
 '2': CDS_PINID='\2\';
NODE_NAME     R220 1
 '@TIMECARD_LIB.TIMECARD(SCH_1):PAGE127_I393@PASSIVE.RESISTOR(CHIPS)':
 '1': CDS_PINID='\1\';
NODE_NAME     U24 N20
 '@TIMECARD_LIB.TIMECARD(SCH_1):PAGE162_I228@PLD.XC7A200T_2FBG484C_FBG484(CHIPS)':
 'IO_L18P_T2_A24_15': CDS_PINID='IO_L18P_T2_A24_15';
NET_NAME
'FPGA_BRD_REV1'
 '@TIMECARD_LIB.TIMECARD(SCH_1):FPGA_BRD_REV1':
 C_SIGNAL='@timecard_lib.timecard(sch_1):fpga_brd_rev1';
NODE_NAME     R216 1
 '@TIMECARD_LIB.TIMECARD(SCH_1):PAGE127_I391@PASSIVE.RESISTOR(CHIPS)':
 '1': CDS_PINID='\1\';
NODE_NAME     R215 2
 '@TIMECARD_LIB.TIMECARD(SCH_1):PAGE127_I394@PASSIVE.RESISTOR(CHIPS)':
 '2': CDS_PINID='\2\';
NODE_NAME     U24 N19
 '@TIMECARD_LIB.TIMECARD(SCH_1):PAGE162_I228@PLD.XC7A200T_2FBG484C_FBG484(CHIPS)':
 'IO_L17N_T2_A25_15': CDS_PINID='IO_L17N_T2_A25_15';
NET_NAME
'FPGA_BRD_REV2'
 '@TIMECARD_LIB.TIMECARD(SCH_1):FPGA_BRD_REV2':
 C_SIGNAL='@timecard_lib.timecard(sch_1):fpga_brd_rev2';
NODE_NAME     R213 2
 '@TIMECARD_LIB.TIMECARD(SCH_1):PAGE127_I396@PASSIVE.RESISTOR(CHIPS)':
 '2': CDS_PINID='\2\';
NODE_NAME     R214 1
 '@TIMECARD_LIB.TIMECARD(SCH_1):PAGE127_I397@PASSIVE.RESISTOR(CHIPS)':
 '1': CDS_PINID='\1\';
NODE_NAME     U24 N18
 '@TIMECARD_LIB.TIMECARD(SCH_1):PAGE162_I228@PLD.XC7A200T_2FBG484C_FBG484(CHIPS)':
 'IO_L17P_T2_A26_15': CDS_PINID='IO_L17P_T2_A26_15';
NET_NAME
'FPGA_CFG_INIT_N'
 '@TIMECARD_LIB.TIMECARD(SCH_1):FPGA_CFG_INIT_N':
 C_SIGNAL='@timecard_lib.timecard(sch_1):fpga_cfg_init_n';
NODE_NAME     U24 U12
 '@TIMECARD_LIB.TIMECARD(SCH_1):PAGE127_I232@PLD.XC7A200T_2FBG484C_FBG484(CHIPS)':
 'INIT_0*': CDS_PINID='\init_0*\';
NODE_NAME     R209 1
 '@TIMECARD_LIB.TIMECARD(SCH_1):PAGE127_I339@PASSIVE.RESISTOR(CHIPS)':
 '1': CDS_PINID='\1\';
NODE_NAME     R230 2
 '@TIMECARD_LIB.TIMECARD(SCH_1):PAGE515_I140@PASSIVE.RESISTOR(CHIPS)':
 '2': CDS_PINID='\2\';
NODE_NAME     R143 1
 '@TIMECARD_LIB.TIMECARD(SCH_1):PAGE515_I167@PASSIVE.RESISTOR(CHIPS)':
 '1': CDS_PINID='\1\';
NODE_NAME     R294 2
 '@TIMECARD_LIB.TIMECARD(SCH_1):PAGE516_I45@PASSIVE.RESISTOR(CHIPS)':
 '2': CDS_PINID='\2\';
NODE_NAME     J10 10
 '@TIMECARD_LIB.TIMECARD(SCH_1):PAGE524_I173@CONNECTOR.G200_10283_01(CHIPS)':
 '10': CDS_PINID='\10\';
NODE_NAME     TP46 1
 '@TIMECARD_LIB.TIMECARD(SCH_1):PAGE16_I1684@CLS.TP_PIONT(CHIPS)':
 '1': CDS_PINID='\1\';
NET_NAME
'FPGA_D00_MOSI'
 '@TIMECARD_LIB.TIMECARD(SCH_1):FPGA_D00_MOSI':
 C_SIGNAL='@timecard_lib.timecard(sch_1):fpga_d00_mosi';
NODE_NAME     U24 P22
 '@TIMECARD_LIB.TIMECARD(SCH_1):PAGE161_I2@PLD.XC7A200T_2FBG484C_FBG484(CHIPS)':
 'IO_L1P_T0_D00_MOSI_14': CDS_PINID='IO_L1P_T0_D00_MOSI_14';
NODE_NAME     R234 1
 '@TIMECARD_LIB.TIMECARD(SCH_1):PAGE161_I258@PASSIVE.RESISTOR(CHIPS)':
 '1': CDS_PINID='\1\';
NET_NAME
'FPGA_D01'
 '@TIMECARD_LIB.TIMECARD(SCH_1):FPGA_D01':
 C_SIGNAL='@timecard_lib.timecard(sch_1):fpga_d01';
NODE_NAME     U24 R22
 '@TIMECARD_LIB.TIMECARD(SCH_1):PAGE161_I2@PLD.XC7A200T_2FBG484C_FBG484(CHIPS)':
 'IO_L1N_T0_D01_DIN_14': CDS_PINID='IO_L1N_T0_D01_DIN_14';
NODE_NAME     R238 1
 '@TIMECARD_LIB.TIMECARD(SCH_1):PAGE161_I259@PASSIVE.RESISTOR(CHIPS)':
 '1': CDS_PINID='\1\';
NET_NAME
'FPGA_D02'
 '@TIMECARD_LIB.TIMECARD(SCH_1):FPGA_D02':
 C_SIGNAL='@timecard_lib.timecard(sch_1):fpga_d02';
NODE_NAME     U24 P21
 '@TIMECARD_LIB.TIMECARD(SCH_1):PAGE161_I2@PLD.XC7A200T_2FBG484C_FBG484(CHIPS)':
 'IO_L2P_T0_D02_14': CDS_PINID='IO_L2P_T0_D02_14';
NODE_NAME     R339 1
 '@TIMECARD_LIB.TIMECARD(SCH_1):PAGE161_I261@PASSIVE.RESISTOR(CHIPS)':
 '1': CDS_PINID='\1\';
NET_NAME
'FPGA_D03'
 '@TIMECARD_LIB.TIMECARD(SCH_1):FPGA_D03':
 C_SIGNAL='@timecard_lib.timecard(sch_1):fpga_d03';
NODE_NAME     U24 R21
 '@TIMECARD_LIB.TIMECARD(SCH_1):PAGE161_I2@PLD.XC7A200T_2FBG484C_FBG484(CHIPS)':
 'IO_L2N_T0_D03_14': CDS_PINID='IO_L2N_T0_D03_14';
NODE_NAME     R348 1
 '@TIMECARD_LIB.TIMECARD(SCH_1):PAGE161_I260@PASSIVE.RESISTOR(CHIPS)':
 '1': CDS_PINID='\1\';
NET_NAME
'FPGA_DONE'
 '@TIMECARD_LIB.TIMECARD(SCH_1):FPGA_DONE':
 C_SIGNAL='@timecard_lib.timecard(sch_1):fpga_done';
NODE_NAME     U24 G11
 '@TIMECARD_LIB.TIMECARD(SCH_1):PAGE127_I232@PLD.XC7A200T_2FBG484C_FBG484(CHIPS)':
 'DONE_0': CDS_PINID='DONE_0';
NODE_NAME     R210 1
 '@TIMECARD_LIB.TIMECARD(SCH_1):PAGE127_I338@PASSIVE.RESISTOR(CHIPS)':
 '1': CDS_PINID='\1\';
NODE_NAME     TP44 1
 '@TIMECARD_LIB.TIMECARD(SCH_1):PAGE16_I1689@CLS.TP_PIONT(CHIPS)':
 '1': CDS_PINID='\1\';
NODE_NAME     R208 2
 '@TIMECARD_LIB.TIMECARD(SCH_1):PAGE14_I293@PASSIVE.RESISTOR(CHIPS)':
 '2': CDS_PINID='\2\';
NET_NAME
'FPGA_EEPROM_I2C_SCL'
 '@TIMECARD_LIB.TIMECARD(SCH_1):FPGA_EEPROM_I2C_SCL':
 C_SIGNAL='@timecard_lib.timecard(sch_1):fpga_eeprom_i2c_scl';
NODE_NAME     U24 AB16
 '@TIMECARD_LIB.TIMECARD(SCH_1):PAGE161_I2@PLD.XC7A200T_2FBG484C_FBG484(CHIPS)':
 'IO_L2P_T0_13': CDS_PINID='IO_L2P_T0_13';
NODE_NAME     U37 14
 '@TIMECARD_LIB.TIMECARD(SCH_1):PAGE524_I448@STDLOGIC.TS3A5018PWR_TSSOP16(CHIPS)':
 'NC4': CDS_PINID='NC4';
NODE_NAME     R477 2
 '@TIMECARD_LIB.TIMECARD(SCH_1):PAGE524_I469@PASSIVE.RESISTOR(CHIPS)':
 '2': CDS_PINID='\2\';
NET_NAME
'FPGA_EEPROM_I2C_SDA'
 '@TIMECARD_LIB.TIMECARD(SCH_1):FPGA_EEPROM_I2C_SDA':
 C_SIGNAL='@timecard_lib.timecard(sch_1):fpga_eeprom_i2c_sda';
NODE_NAME     U24 AB17
 '@TIMECARD_LIB.TIMECARD(SCH_1):PAGE161_I2@PLD.XC7A200T_2FBG484C_FBG484(CHIPS)':
 'IO_L2N_T0_13': CDS_PINID='IO_L2N_T0_13';
NODE_NAME     U37 11
 '@TIMECARD_LIB.TIMECARD(SCH_1):PAGE524_I448@STDLOGIC.TS3A5018PWR_TSSOP16(CHIPS)':
 'NC3': CDS_PINID='NC3';
NODE_NAME     R476 2
 '@TIMECARD_LIB.TIMECARD(SCH_1):PAGE524_I468@PASSIVE.RESISTOR(CHIPS)':
 '2': CDS_PINID='\2\';
NET_NAME
'FPGA_FCS_B'
 '@TIMECARD_LIB.TIMECARD(SCH_1):FPGA_FCS_B':
 C_SIGNAL='@timecard_lib.timecard(sch_1):fpga_fcs_b';
NODE_NAME     U24 T19
 '@TIMECARD_LIB.TIMECARD(SCH_1):PAGE161_I2@PLD.XC7A200T_2FBG484C_FBG484(CHIPS)':
 'IO_L6P_T0_FCS_B_14': CDS_PINID='IO_L6P_T0_FCS_B_14';
NODE_NAME     R362 1
 '@TIMECARD_LIB.TIMECARD(SCH_1):PAGE161_I263@PASSIVE.RESISTOR(CHIPS)':
 '1': CDS_PINID='\1\';
NET_NAME
'FPGA_FLASH_CLK'
 '@TIMECARD_LIB.TIMECARD(SCH_1):FPGA_FLASH_CLK':
 C_SIGNAL='@timecard_lib.timecard(sch_1):fpga_flash_clk';
NODE_NAME     R207 2
 '@TIMECARD_LIB.TIMECARD(SCH_1):PAGE127_I337@PASSIVE.RESISTOR(CHIPS)':
 '2': CDS_PINID='\2\';
NODE_NAME     U38 2
 '@TIMECARD_LIB.TIMECARD(SCH_1):PAGE524_I400@STDLOGIC.TS3A5018PWR_TSSOP16(CHIPS)':
 'NC1': CDS_PINID='NC1';
NET_NAME
'FPGA_FLASH_CS_N'
 '@TIMECARD_LIB.TIMECARD(SCH_1):FPGA_FLASH_CS_N':
 C_SIGNAL='@timecard_lib.timecard(sch_1):fpga_flash_cs_n';
NODE_NAME     U38 14
 '@TIMECARD_LIB.TIMECARD(SCH_1):PAGE524_I400@STDLOGIC.TS3A5018PWR_TSSOP16(CHIPS)':
 'NC4': CDS_PINID='NC4';
NODE_NAME     R362 2
 '@TIMECARD_LIB.TIMECARD(SCH_1):PAGE161_I263@PASSIVE.RESISTOR(CHIPS)':
 '2': CDS_PINID='\2\';
NET_NAME
'FPGA_FLASH_DQ0_MOSI'
 '@TIMECARD_LIB.TIMECARD(SCH_1):FPGA_FLASH_DQ0_MOSI':
 C_SIGNAL='@timecard_lib.timecard(sch_1):fpga_flash_dq0_mosi';
NODE_NAME     U38 5
 '@TIMECARD_LIB.TIMECARD(SCH_1):PAGE524_I400@STDLOGIC.TS3A5018PWR_TSSOP16(CHIPS)':
 'NC2': CDS_PINID='NC2';
NODE_NAME     R234 2
 '@TIMECARD_LIB.TIMECARD(SCH_1):PAGE161_I258@PASSIVE.RESISTOR(CHIPS)':
 '2': CDS_PINID='\2\';
NET_NAME
'FPGA_FLASH_DQ1_MISO'
 '@TIMECARD_LIB.TIMECARD(SCH_1):FPGA_FLASH_DQ1_MISO':
 C_SIGNAL='@timecard_lib.timecard(sch_1):fpga_flash_dq1_miso';
NODE_NAME     U38 11
 '@TIMECARD_LIB.TIMECARD(SCH_1):PAGE524_I400@STDLOGIC.TS3A5018PWR_TSSOP16(CHIPS)':
 'NC3': CDS_PINID='NC3';
NODE_NAME     R435 1
 '@TIMECARD_LIB.TIMECARD(SCH_1):PAGE161_I251@PASSIVE.RESISTOR(CHIPS)':
 '1': CDS_PINID='\1\';
NODE_NAME     R238 2
 '@TIMECARD_LIB.TIMECARD(SCH_1):PAGE161_I259@PASSIVE.RESISTOR(CHIPS)':
 '2': CDS_PINID='\2\';
NET_NAME
'FPGA_FLASH_DQ2'
 '@TIMECARD_LIB.TIMECARD(SCH_1):FPGA_FLASH_DQ2':
 C_SIGNAL='@timecard_lib.timecard(sch_1):fpga_flash_dq2';
NODE_NAME     U39 4
 '@TIMECARD_LIB.TIMECARD(SCH_1):PAGE524_I407@INTERFACE.NLASB3157DFT2G_SC88(CHIPS)':
 'A': CDS_PINID='A';
NODE_NAME     R464 1
 '@TIMECARD_LIB.TIMECARD(SCH_1):PAGE524_I493@PASSIVE.RESISTOR(CHIPS)':
 '1': CDS_PINID='\1\';
NODE_NAME     R339 2
 '@TIMECARD_LIB.TIMECARD(SCH_1):PAGE161_I261@PASSIVE.RESISTOR(CHIPS)':
 '2': CDS_PINID='\2\';
NET_NAME
'FPGA_FLASH_DQ3'
 '@TIMECARD_LIB.TIMECARD(SCH_1):FPGA_FLASH_DQ3':
 C_SIGNAL='@timecard_lib.timecard(sch_1):fpga_flash_dq3';
NODE_NAME     U40 4
 '@TIMECARD_LIB.TIMECARD(SCH_1):PAGE524_I408@INTERFACE.NLASB3157DFT2G_SC88(CHIPS)':
 'A': CDS_PINID='A';
NODE_NAME     R465 1
 '@TIMECARD_LIB.TIMECARD(SCH_1):PAGE524_I494@PASSIVE.RESISTOR(CHIPS)':
 '1': CDS_PINID='\1\';
NODE_NAME     R348 2
 '@TIMECARD_LIB.TIMECARD(SCH_1):PAGE161_I260@PASSIVE.RESISTOR(CHIPS)':
 '2': CDS_PINID='\2\';
NET_NAME
'FPGA_IN_BNO080_INT_N'
 '@TIMECARD_LIB.TIMECARD(SCH_1):FPGA_IN_BNO080_INT_N':
 C_SIGNAL='@timecard_lib.timecard(sch_1):fpga_in_bno080_int_n';
NODE_NAME     U24 L14
 '@TIMECARD_LIB.TIMECARD(SCH_1):PAGE162_I228@PLD.XC7A200T_2FBG484C_FBG484(CHIPS)':
 'IO_L22P_T3_A17_15': CDS_PINID='IO_L22P_T3_A17_15';
NODE_NAME     R79 1
 '@TIMECARD_LIB.TIMECARD(SCH_1):PAGE9_I31@PASSIVE.RESISTOR(CHIPS)':
 '1': CDS_PINID='\1\';
NODE_NAME     R289 2
 '@TIMECARD_LIB.TIMECARD(SCH_1):PAGE9_I38@PASSIVE.RESISTOR(CHIPS)':
 '2': CDS_PINID='\2\';
NET_NAME
'FPGA_IN_GPSTP1_OUT'
 '@TIMECARD_LIB.TIMECARD(SCH_1):FPGA_IN_GPSTP1_OUT':
 C_SIGNAL='@timecard_lib.timecard(sch_1):fpga_in_gpstp1_out';
NODE_NAME     R117 2
 '@TIMECARD_LIB.TIMECARD(SCH_1):PAGE11_I20@PASSIVE.RESISTOR(CHIPS)':
 '2': CDS_PINID='\2\';
NODE_NAME     U24 W14
 '@TIMECARD_LIB.TIMECARD(SCH_1):PAGE161_I2@PLD.XC7A200T_2FBG484C_FBG484(CHIPS)':
 'IO_L6P_T0_13': CDS_PINID='IO_L6P_T0_13';
NODE_NAME     R270 2
 '@TIMECARD_LIB.TIMECARD(SCH_1):PAGE161_I140@PASSIVE.RESISTOR(CHIPS)':
 '2': CDS_PINID='\2\';
NET_NAME
'FPGA_IN_GPSTP2_OUT'
 '@TIMECARD_LIB.TIMECARD(SCH_1):FPGA_IN_GPSTP2_OUT':
 C_SIGNAL='@timecard_lib.timecard(sch_1):fpga_in_gpstp2_out';
NODE_NAME     R111 1
 '@TIMECARD_LIB.TIMECARD(SCH_1):PAGE11_I5@PASSIVE.RESISTOR(CHIPS)':
 '1': CDS_PINID='\1\';
NODE_NAME     U24 Y14
 '@TIMECARD_LIB.TIMECARD(SCH_1):PAGE161_I2@PLD.XC7A200T_2FBG484C_FBG484(CHIPS)':
 'IO_L6N_T0_VREF_13': CDS_PINID='IO_L6N_T0_VREF_13';
NODE_NAME     R271 2
 '@TIMECARD_LIB.TIMECARD(SCH_1):PAGE161_I200@PASSIVE.RESISTOR(CHIPS)':
 '2': CDS_PINID='\2\';
NET_NAME
'FPGA_IN_LM75B_INT1_N'
 '@TIMECARD_LIB.TIMECARD(SCH_1):FPGA_IN_LM75B_INT1_N':
 C_SIGNAL='@timecard_lib.timecard(sch_1):fpga_in_lm75b_int1_n';
NODE_NAME     U8 3
 '@TIMECARD_LIB.TIMECARD(SCH_1):PAGE6_I34@INTERFACE.LM75BDP_TSSOP8(CHIPS)':
 'OS': CDS_PINID='OS';
NODE_NAME     R340 2
 '@TIMECARD_LIB.TIMECARD(SCH_1):PAGE6_I41@PASSIVE.RESISTOR(CHIPS)':
 '2': CDS_PINID='\2\';
NODE_NAME     U24 N22
 '@TIMECARD_LIB.TIMECARD(SCH_1):PAGE162_I228@PLD.XC7A200T_2FBG484C_FBG484(CHIPS)':
 'IO_L15P_T2_DQS_15': CDS_PINID='IO_L15P_T2_DQS_15';
NODE_NAME     TP24 1
 '@TIMECARD_LIB.TIMECARD(SCH_1):PAGE16_I1648@CLS.TP_PIONT(CHIPS)':
 '1': CDS_PINID='\1\';
NET_NAME
'FPGA_IN_LM75B_INT2_N'
 '@TIMECARD_LIB.TIMECARD(SCH_1):FPGA_IN_LM75B_INT2_N':
 C_SIGNAL='@timecard_lib.timecard(sch_1):fpga_in_lm75b_int2_n';
NODE_NAME     U24 M22
 '@TIMECARD_LIB.TIMECARD(SCH_1):PAGE162_I228@PLD.XC7A200T_2FBG484C_FBG484(CHIPS)':
 'IO_L15N_T2_DQS_ADV_B_15': CDS_PINID='IO_L15N_T2_DQS_ADV_B_15';
NODE_NAME     U35 3
 '@TIMECARD_LIB.TIMECARD(SCH_1):PAGE6_I59@INTERFACE.LM75BDP_TSSOP8(CHIPS)':
 'OS': CDS_PINID='OS';
NODE_NAME     R422 2
 '@TIMECARD_LIB.TIMECARD(SCH_1):PAGE6_I64@PASSIVE.RESISTOR(CHIPS)':
 '2': CDS_PINID='\2\';
NODE_NAME     TP23 1
 '@TIMECARD_LIB.TIMECARD(SCH_1):PAGE16_I1647@CLS.TP_PIONT(CHIPS)':
 '1': CDS_PINID='\1\';
NET_NAME
'FPGA_IN_LM75B_INT3_N'
 '@TIMECARD_LIB.TIMECARD(SCH_1):FPGA_IN_LM75B_INT3_N':
 C_SIGNAL='@timecard_lib.timecard(sch_1):fpga_in_lm75b_int3_n';
NODE_NAME     U24 M18
 '@TIMECARD_LIB.TIMECARD(SCH_1):PAGE162_I228@PLD.XC7A200T_2FBG484C_FBG484(CHIPS)':
 'IO_L16P_T2_A28_15': CDS_PINID='IO_L16P_T2_A28_15';
NODE_NAME     U36 3
 '@TIMECARD_LIB.TIMECARD(SCH_1):PAGE6_I81@INTERFACE.LM75BDP_TSSOP8(CHIPS)':
 'OS': CDS_PINID='OS';
NODE_NAME     R423 2
 '@TIMECARD_LIB.TIMECARD(SCH_1):PAGE6_I88@PASSIVE.RESISTOR(CHIPS)':
 '2': CDS_PINID='\2\';
NODE_NAME     TP22 1
 '@TIMECARD_LIB.TIMECARD(SCH_1):PAGE16_I1646@CLS.TP_PIONT(CHIPS)':
 '1': CDS_PINID='\1\';
NET_NAME
'FPGA_IN_MAC_10MHZ_OUT'
 '@TIMECARD_LIB.TIMECARD(SCH_1):FPGA_IN_MAC_10MHZ_OUT':
 C_SIGNAL='@timecard_lib.timecard(sch_1):fpga_in_mac_10mhz_out';
NODE_NAME     U24 V13
 '@TIMECARD_LIB.TIMECARD(SCH_1):PAGE161_I2@PLD.XC7A200T_2FBG484C_FBG484(CHIPS)':
 'IO_L13P_T2_MRCC_13': CDS_PINID='IO_L13P_T2_MRCC_13';
NODE_NAME     R92 2
 '@TIMECARD_LIB.TIMECARD(SCH_1):PAGE527_I55@PASSIVE.RESISTOR(CHIPS)':
 '2': CDS_PINID='\2\';
NODE_NAME     R502 2
 '@TIMECARD_LIB.TIMECARD(SCH_1):PAGE161_I247@PASSIVE.RESISTOR(CHIPS)':
 '2': CDS_PINID='\2\';
NET_NAME
'FPGA_IN_MAC_ALARM_OUT_N'
 '@TIMECARD_LIB.TIMECARD(SCH_1):FPGA_IN_MAC_ALARM_OUT_N':
 C_SIGNAL='@timecard_lib.timecard(sch_1):fpga_in_mac_alarm_out_n';
NODE_NAME     U24 AB10
 '@TIMECARD_LIB.TIMECARD(SCH_1):PAGE161_I2@PLD.XC7A200T_2FBG484C_FBG484(CHIPS)':
 'IO_L8N_T1_13': CDS_PINID='IO_L8N_T1_13';
NODE_NAME     R96 2
 '@TIMECARD_LIB.TIMECARD(SCH_1):PAGE527_I23@PASSIVE.RESISTOR(CHIPS)':
 '2': CDS_PINID='\2\';
NODE_NAME     R287 1
 '@TIMECARD_LIB.TIMECARD(SCH_1):PAGE527_I211@PASSIVE.RESISTOR(CHIPS)':
 '1': CDS_PINID='\1\';
NET_NAME
'FPGA_IN_MAC_BITEOUT'
 '@TIMECARD_LIB.TIMECARD(SCH_1):FPGA_IN_MAC_BITE OUT':
 C_SIGNAL='@timecard_lib.timecard(sch_1):\fpga_in_mac_bite out\';
NODE_NAME     U24 AA9
 '@TIMECARD_LIB.TIMECARD(SCH_1):PAGE161_I2@PLD.XC7A200T_2FBG484C_FBG484(CHIPS)':
 'IO_L8P_T1_13': CDS_PINID='IO_L8P_T1_13';
NODE_NAME     R288 2
 '@TIMECARD_LIB.TIMECARD(SCH_1):PAGE161_I201@PASSIVE.RESISTOR(CHIPS)':
 '2': CDS_PINID='\2\';
NODE_NAME     R93 2
 '@TIMECARD_LIB.TIMECARD(SCH_1):PAGE527_I53@PASSIVE.RESISTOR(CHIPS)':
 '2': CDS_PINID='\2\';
NET_NAME
'FPGA_IN_MAC_PPS_OUTN'
 '@TIMECARD_LIB.TIMECARD(SCH_1):FPGA_IN_MAC_PPS_OUTN':
 C_SIGNAL='@timecard_lib.timecard(sch_1):fpga_in_mac_pps_outn';
NODE_NAME     U24 Y1
 '@TIMECARD_LIB.TIMECARD(SCH_1):PAGE163_I1@PLD.XC7A200T_2FBG484C_FBG484(CHIPS)':
 'IO_L5N_T0_34': CDS_PINID='IO_L5N_T0_34';
NODE_NAME     R275 2
 '@TIMECARD_LIB.TIMECARD(SCH_1):PAGE163_I39@PASSIVE.RESISTOR(CHIPS)':
 '2': CDS_PINID='\2\';
NODE_NAME     R88 1
 '@TIMECARD_LIB.TIMECARD(SCH_1):PAGE527_I13@PASSIVE.RESISTOR(CHIPS)':
 '1': CDS_PINID='\1\';
NODE_NAME     R438 1
 '@TIMECARD_LIB.TIMECARD(SCH_1):PAGE163_I132@PASSIVE.RESISTOR(CHIPS)':
 '1': CDS_PINID='\1\';
NODE_NAME     R441 1
 '@TIMECARD_LIB.TIMECARD(SCH_1):PAGE163_I134@PASSIVE.RESISTOR(CHIPS)':
 '1': CDS_PINID='\1\';
NET_NAME
'FPGA_IN_MAC_PPS_OUTP'
 '@TIMECARD_LIB.TIMECARD(SCH_1):FPGA_IN_MAC_PPS_OUTP':
 C_SIGNAL='@timecard_lib.timecard(sch_1):fpga_in_mac_pps_outp';
NODE_NAME     U24 W1
 '@TIMECARD_LIB.TIMECARD(SCH_1):PAGE163_I1@PLD.XC7A200T_2FBG484C_FBG484(CHIPS)':
 'IO_L5P_T0_34': CDS_PINID='IO_L5P_T0_34';
NODE_NAME     R275 1
 '@TIMECARD_LIB.TIMECARD(SCH_1):PAGE163_I39@PASSIVE.RESISTOR(CHIPS)':
 '1': CDS_PINID='\1\';
NODE_NAME     R87 1
 '@TIMECARD_LIB.TIMECARD(SCH_1):PAGE527_I14@PASSIVE.RESISTOR(CHIPS)':
 '1': CDS_PINID='\1\';
NODE_NAME     R439 1
 '@TIMECARD_LIB.TIMECARD(SCH_1):PAGE163_I133@PASSIVE.RESISTOR(CHIPS)':
 '1': CDS_PINID='\1\';
NODE_NAME     R440 1
 '@TIMECARD_LIB.TIMECARD(SCH_1):PAGE163_I135@PASSIVE.RESISTOR(CHIPS)':
 '1': CDS_PINID='\1\';
NET_NAME
'FPGA_IN_MAC_USB_OC_N'
 '@TIMECARD_LIB.TIMECARD(SCH_1):FPGA_IN_MAC_USB_OC_N':
 C_SIGNAL='@timecard_lib.timecard(sch_1):fpga_in_mac_usb_oc_n';
NODE_NAME     U24 M15
 '@TIMECARD_LIB.TIMECARD(SCH_1):PAGE162_I228@PLD.XC7A200T_2FBG484C_FBG484(CHIPS)':
 'IO_L24P_T3_RS1_15': CDS_PINID='IO_L24P_T3_RS1_15';
NODE_NAME     R107 2
 '@TIMECARD_LIB.TIMECARD(SCH_1):PAGE527_I83@PASSIVE.RESISTOR(CHIPS)':
 '2': CDS_PINID='\2\';
NODE_NAME     R267 2
 '@TIMECARD_LIB.TIMECARD(SCH_1):PAGE527_I206@PASSIVE.RESISTOR(CHIPS)':
 '2': CDS_PINID='\2\';
NET_NAME
'FPGA_IN_RST_DLY_N'
 '@TIMECARD_LIB.TIMECARD(SCH_1):FPGA_IN_RST_DLY_N':
 C_SIGNAL='@timecard_lib.timecard(sch_1):fpga_in_rst_dly_n';
NODE_NAME     U24 J20
 '@TIMECARD_LIB.TIMECARD(SCH_1):PAGE162_I228@PLD.XC7A200T_2FBG484C_FBG484(CHIPS)':
 'IO_L11P_T1_SRCC_15': CDS_PINID='IO_L11P_T1_SRCC_15';
NODE_NAME     U34 1
 '@TIMECARD_LIB.TIMECARD(SCH_1):PAGE3_I139@ANALOG.TPS3808G18DBVR_SOT23_6(CHIPS)':
 'RESET*': CDS_PINID='\reset*\';
NODE_NAME     R167 2
 '@TIMECARD_LIB.TIMECARD(SCH_1):PAGE3_I148@PASSIVE.RESISTOR(CHIPS)':
 '2': CDS_PINID='\2\';
NET_NAME
'FPGA_IN_SHT3X_ALERT_N'
 '@TIMECARD_LIB.TIMECARD(SCH_1):FPGA_IN_SHT3X_ALERT_N':
 C_SIGNAL='@timecard_lib.timecard(sch_1):fpga_in_sht3x_alert_n';
NODE_NAME     U24 J19
 '@TIMECARD_LIB.TIMECARD(SCH_1):PAGE162_I228@PLD.XC7A200T_2FBG484C_FBG484(CHIPS)':
 'IO_L12P_T1_MRCC_15': CDS_PINID='IO_L12P_T1_MRCC_15';
NODE_NAME     R299 2
 '@TIMECARD_LIB.TIMECARD(SCH_1):PAGE7_I40@PASSIVE.RESISTOR(CHIPS)':
 '2': CDS_PINID='\2\';
NODE_NAME     R300 2
 '@TIMECARD_LIB.TIMECARD(SCH_1):PAGE7_I41@PASSIVE.RESISTOR(CHIPS)':
 '2': CDS_PINID='\2\';
NET_NAME
'FPGA_IO_0'
 '@TIMECARD_LIB.TIMECARD(SCH_1):FPGA_IO_0':
 C_SIGNAL='@timecard_lib.timecard(sch_1):fpga_io_0';
NODE_NAME     U24 J22
 '@TIMECARD_LIB.TIMECARD(SCH_1):PAGE162_I228@PLD.XC7A200T_2FBG484C_FBG484(CHIPS)':
 'IO_L7P_T1_AD2P_15': CDS_PINID='IO_L7P_T1_AD2P_15';
NODE_NAME     R171 2
 '@TIMECARD_LIB.TIMECARD(SCH_1):PAGE16_I1542@PASSIVE.RESISTOR(CHIPS)':
 '2': CDS_PINID='\2\';
NODE_NAME     R170 2
 '@TIMECARD_LIB.TIMECARD(SCH_1):PAGE16_I1608@PASSIVE.RESISTOR(CHIPS)':
 '2': CDS_PINID='\2\';
NODE_NAME     R434 2
 '@TIMECARD_LIB.TIMECARD(SCH_1):PAGE16_I1721@PASSIVE.RESISTOR(CHIPS)':
 '2': CDS_PINID='\2\';
NET_NAME
'FPGA_IO_1'
 '@TIMECARD_LIB.TIMECARD(SCH_1):FPGA_IO_1':
 C_SIGNAL='@timecard_lib.timecard(sch_1):fpga_io_1';
NODE_NAME     U24 H22
 '@TIMECARD_LIB.TIMECARD(SCH_1):PAGE162_I228@PLD.XC7A200T_2FBG484C_FBG484(CHIPS)':
 'IO_L7N_T1_AD2N_15': CDS_PINID='IO_L7N_T1_AD2N_15';
NODE_NAME     R173 2
 '@TIMECARD_LIB.TIMECARD(SCH_1):PAGE16_I1544@PASSIVE.RESISTOR(CHIPS)':
 '2': CDS_PINID='\2\';
NODE_NAME     R172 2
 '@TIMECARD_LIB.TIMECARD(SCH_1):PAGE16_I1607@PASSIVE.RESISTOR(CHIPS)':
 '2': CDS_PINID='\2\';
NODE_NAME     R433 2
 '@TIMECARD_LIB.TIMECARD(SCH_1):PAGE16_I1720@PASSIVE.RESISTOR(CHIPS)':
 '2': CDS_PINID='\2\';
NET_NAME
'FPGA_IO_2'
 '@TIMECARD_LIB.TIMECARD(SCH_1):FPGA_IO_2':
 C_SIGNAL='@timecard_lib.timecard(sch_1):fpga_io_2';
NODE_NAME     U24 H20
 '@TIMECARD_LIB.TIMECARD(SCH_1):PAGE162_I228@PLD.XC7A200T_2FBG484C_FBG484(CHIPS)':
 'IO_L8P_T1_AD10P_15': CDS_PINID='IO_L8P_T1_AD10P_15';
NODE_NAME     R284 2
 '@TIMECARD_LIB.TIMECARD(SCH_1):PAGE16_I1547@PASSIVE.RESISTOR(CHIPS)':
 '2': CDS_PINID='\2\';
NODE_NAME     R283 2
 '@TIMECARD_LIB.TIMECARD(SCH_1):PAGE16_I1609@PASSIVE.RESISTOR(CHIPS)':
 '2': CDS_PINID='\2\';
NODE_NAME     R432 2
 '@TIMECARD_LIB.TIMECARD(SCH_1):PAGE16_I1719@PASSIVE.RESISTOR(CHIPS)':
 '2': CDS_PINID='\2\';
NET_NAME
'FPGA_IO_3'
 '@TIMECARD_LIB.TIMECARD(SCH_1):FPGA_IO_3':
 C_SIGNAL='@timecard_lib.timecard(sch_1):fpga_io_3';
NODE_NAME     U24 G20
 '@TIMECARD_LIB.TIMECARD(SCH_1):PAGE162_I228@PLD.XC7A200T_2FBG484C_FBG484(CHIPS)':
 'IO_L8N_T1_AD10N_15': CDS_PINID='IO_L8N_T1_AD10N_15';
NODE_NAME     R286 2
 '@TIMECARD_LIB.TIMECARD(SCH_1):PAGE16_I1549@PASSIVE.RESISTOR(CHIPS)':
 '2': CDS_PINID='\2\';
NODE_NAME     R285 2
 '@TIMECARD_LIB.TIMECARD(SCH_1):PAGE16_I1606@PASSIVE.RESISTOR(CHIPS)':
 '2': CDS_PINID='\2\';
NODE_NAME     R431 2
 '@TIMECARD_LIB.TIMECARD(SCH_1):PAGE16_I1718@PASSIVE.RESISTOR(CHIPS)':
 '2': CDS_PINID='\2\';
NET_NAME
'FPGA_IO_4'
 '@TIMECARD_LIB.TIMECARD(SCH_1):FPGA_IO_4':
 C_SIGNAL='@timecard_lib.timecard(sch_1):fpga_io_4';
NODE_NAME     U24 K21
 '@TIMECARD_LIB.TIMECARD(SCH_1):PAGE162_I228@PLD.XC7A200T_2FBG484C_FBG484(CHIPS)':
 'IO_L9P_T1_DQS_AD3P_15': CDS_PINID='IO_L9P_T1_DQS_AD3P_15';
NODE_NAME     R293 2
 '@TIMECARD_LIB.TIMECARD(SCH_1):PAGE16_I1555@PASSIVE.RESISTOR(CHIPS)':
 '2': CDS_PINID='\2\';
NODE_NAME     R292 2
 '@TIMECARD_LIB.TIMECARD(SCH_1):PAGE16_I1605@PASSIVE.RESISTOR(CHIPS)':
 '2': CDS_PINID='\2\';
NODE_NAME     R430 1
 '@TIMECARD_LIB.TIMECARD(SCH_1):PAGE16_I1706@PASSIVE.RESISTOR(CHIPS)':
 '1': CDS_PINID='\1\';
NET_NAME
'FPGA_IO_5'
 '@TIMECARD_LIB.TIMECARD(SCH_1):FPGA_IO_5':
 C_SIGNAL='@timecard_lib.timecard(sch_1):fpga_io_5';
NODE_NAME     U24 K22
 '@TIMECARD_LIB.TIMECARD(SCH_1):PAGE162_I228@PLD.XC7A200T_2FBG484C_FBG484(CHIPS)':
 'IO_L9N_T1_DQS_AD3N_15': CDS_PINID='IO_L9N_T1_DQS_AD3N_15';
NODE_NAME     R309 2
 '@TIMECARD_LIB.TIMECARD(SCH_1):PAGE16_I1557@PASSIVE.RESISTOR(CHIPS)':
 '2': CDS_PINID='\2\';
NODE_NAME     R308 2
 '@TIMECARD_LIB.TIMECARD(SCH_1):PAGE16_I1604@PASSIVE.RESISTOR(CHIPS)':
 '2': CDS_PINID='\2\';
NODE_NAME     R429 1
 '@TIMECARD_LIB.TIMECARD(SCH_1):PAGE16_I1709@PASSIVE.RESISTOR(CHIPS)':
 '1': CDS_PINID='\1\';
NET_NAME
'FPGA_IO_6'
 '@TIMECARD_LIB.TIMECARD(SCH_1):FPGA_IO_6':
 C_SIGNAL='@timecard_lib.timecard(sch_1):fpga_io_6';
NODE_NAME     U24 M21
 '@TIMECARD_LIB.TIMECARD(SCH_1):PAGE162_I228@PLD.XC7A200T_2FBG484C_FBG484(CHIPS)':
 'IO_L10P_T1_AD11P_15': CDS_PINID='IO_L10P_T1_AD11P_15';
NODE_NAME     R326 2
 '@TIMECARD_LIB.TIMECARD(SCH_1):PAGE16_I1552@PASSIVE.RESISTOR(CHIPS)':
 '2': CDS_PINID='\2\';
NODE_NAME     R325 2
 '@TIMECARD_LIB.TIMECARD(SCH_1):PAGE16_I1602@PASSIVE.RESISTOR(CHIPS)':
 '2': CDS_PINID='\2\';
NODE_NAME     R428 1
 '@TIMECARD_LIB.TIMECARD(SCH_1):PAGE16_I1708@PASSIVE.RESISTOR(CHIPS)':
 '1': CDS_PINID='\1\';
NET_NAME
'FPGA_IO_7'
 '@TIMECARD_LIB.TIMECARD(SCH_1):FPGA_IO_7':
 C_SIGNAL='@timecard_lib.timecard(sch_1):fpga_io_7';
NODE_NAME     U24 L21
 '@TIMECARD_LIB.TIMECARD(SCH_1):PAGE162_I228@PLD.XC7A200T_2FBG484C_FBG484(CHIPS)':
 'IO_L10N_T1_AD11N_15': CDS_PINID='IO_L10N_T1_AD11N_15';
NODE_NAME     R328 2
 '@TIMECARD_LIB.TIMECARD(SCH_1):PAGE16_I1550@PASSIVE.RESISTOR(CHIPS)':
 '2': CDS_PINID='\2\';
NODE_NAME     R327 2
 '@TIMECARD_LIB.TIMECARD(SCH_1):PAGE16_I1603@PASSIVE.RESISTOR(CHIPS)':
 '2': CDS_PINID='\2\';
NODE_NAME     R329 1
 '@TIMECARD_LIB.TIMECARD(SCH_1):PAGE16_I1707@PASSIVE.RESISTOR(CHIPS)':
 '1': CDS_PINID='\1\';
NET_NAME
'FPGA_IO_FT_USBDET_RST_N'
 '@TIMECARD_LIB.TIMECARD(SCH_1):FPGA_IO_FT_USBDET_RST_N':
 C_SIGNAL='@timecard_lib.timecard(sch_1):fpga_io_ft_usbdet_rst_n';
NODE_NAME     U24 AA15
 '@TIMECARD_LIB.TIMECARD(SCH_1):PAGE161_I2@PLD.XC7A200T_2FBG484C_FBG484(CHIPS)':
 'IO_L4P_T0_13': CDS_PINID='IO_L4P_T0_13';
NODE_NAME     R443 2
 '@TIMECARD_LIB.TIMECARD(SCH_1):PAGE524_I446@PASSIVE.RESISTOR(CHIPS)':
 '2': CDS_PINID='\2\';
NET_NAME
'FPGA_M0'
 '@TIMECARD_LIB.TIMECARD(SCH_1):FPGA_M0':
 C_SIGNAL='@timecard_lib.timecard(sch_1):fpga_m0';
NODE_NAME     U24 U11
 '@TIMECARD_LIB.TIMECARD(SCH_1):PAGE127_I232@PLD.XC7A200T_2FBG484C_FBG484(CHIPS)':
 'M0_0': CDS_PINID='M0_0';
NODE_NAME     R211 2
 '@TIMECARD_LIB.TIMECARD(SCH_1):PAGE127_I404@PASSIVE.RESISTOR(CHIPS)':
 '2': CDS_PINID='\2\';
NODE_NAME     R212 1
 '@TIMECARD_LIB.TIMECARD(SCH_1):PAGE127_I407@PASSIVE.RESISTOR(CHIPS)':
 '1': CDS_PINID='\1\';
NET_NAME
'FPGA_M1'
 '@TIMECARD_LIB.TIMECARD(SCH_1):FPGA_M1':
 C_SIGNAL='@timecard_lib.timecard(sch_1):fpga_m1';
NODE_NAME     U24 U10
 '@TIMECARD_LIB.TIMECARD(SCH_1):PAGE127_I232@PLD.XC7A200T_2FBG484C_FBG484(CHIPS)':
 'M1_0': CDS_PINID='M1_0';
NODE_NAME     R217 2
 '@TIMECARD_LIB.TIMECARD(SCH_1):PAGE127_I402@PASSIVE.RESISTOR(CHIPS)':
 '2': CDS_PINID='\2\';
NODE_NAME     R218 1
 '@TIMECARD_LIB.TIMECARD(SCH_1):PAGE127_I406@PASSIVE.RESISTOR(CHIPS)':
 '1': CDS_PINID='\1\';
NET_NAME
'FPGA_M2'
 '@TIMECARD_LIB.TIMECARD(SCH_1):FPGA_M2':
 C_SIGNAL='@timecard_lib.timecard(sch_1):fpga_m2';
NODE_NAME     U24 U9
 '@TIMECARD_LIB.TIMECARD(SCH_1):PAGE127_I232@PLD.XC7A200T_2FBG484C_FBG484(CHIPS)':
 'M2_0': CDS_PINID='M2_0';
NODE_NAME     R221 2
 '@TIMECARD_LIB.TIMECARD(SCH_1):PAGE127_I403@PASSIVE.RESISTOR(CHIPS)':
 '2': CDS_PINID='\2\';
NODE_NAME     R222 1
 '@TIMECARD_LIB.TIMECARD(SCH_1):PAGE127_I405@PASSIVE.RESISTOR(CHIPS)':
 '1': CDS_PINID='\1\';
NET_NAME
'FPGA_MGTAVTT'
 '@TIMECARD_LIB.TIMECARD(SCH_1):FPGA_MGTAVTT':
 C_SIGNAL='@timecard_lib.timecard(sch_1):fpga_mgtavtt',
 CDS_GLOBAL_NET='TRUE';
NODE_NAME     R196 1
 '@TIMECARD_LIB.TIMECARD(SCH_1):PAGE127_I332@PASSIVE.RESISTOR(CHIPS)':
 '1': CDS_PINID='\1\';
NODE_NAME     L35 1
 '@TIMECARD_LIB.TIMECARD(SCH_1):PAGE164_I36@PASSIVE.FERRITEBEAD(CHIPS)':
 '1': CDS_PINID='\1\';
NODE_NAME     U24 B11
 '@TIMECARD_LIB.TIMECARD(SCH_1):PAGE164_I138@PLD.XC7A200T_2FBG484C_FBG484(CHIPS)':
 'MGTAVTT_1': CDS_PINID='MGTAVTT_1';
NODE_NAME     U24 B5
 '@TIMECARD_LIB.TIMECARD(SCH_1):PAGE164_I138@PLD.XC7A200T_2FBG484C_FBG484(CHIPS)':
 'MGTAVTT_2': CDS_PINID='MGTAVTT_2';
NODE_NAME     U24 B7
 '@TIMECARD_LIB.TIMECARD(SCH_1):PAGE164_I138@PLD.XC7A200T_2FBG484C_FBG484(CHIPS)':
 'MGTAVTT_3': CDS_PINID='MGTAVTT_3';
NODE_NAME     U24 B9
 '@TIMECARD_LIB.TIMECARD(SCH_1):PAGE164_I138@PLD.XC7A200T_2FBG484C_FBG484(CHIPS)':
 'MGTAVTT_4': CDS_PINID='MGTAVTT_4';
NODE_NAME     U24 C4
 '@TIMECARD_LIB.TIMECARD(SCH_1):PAGE164_I138@PLD.XC7A200T_2FBG484C_FBG484(CHIPS)':
 'MGTAVTT_5': CDS_PINID='MGTAVTT_5';
NODE_NAME     U24 C8
 '@TIMECARD_LIB.TIMECARD(SCH_1):PAGE164_I138@PLD.XC7A200T_2FBG484C_FBG484(CHIPS)':
 'MGTAVTT_6': CDS_PINID='MGTAVTT_6';
NODE_NAME     C117 1
 '@TIMECARD_LIB.TIMECARD(SCH_1):PAGE164_I246@PASSIVE.CAPACITOR(CHIPS)':
 '1': CDS_PINID='\1\';
NODE_NAME     C110 1
 '@TIMECARD_LIB.TIMECARD(SCH_1):PAGE164_I256@PASSIVE.CAPACITOR(CHIPS)':
 '1': CDS_PINID='\1\';
NODE_NAME     C104 1
 '@TIMECARD_LIB.TIMECARD(SCH_1):PAGE164_I257@PASSIVE.CAPACITOR(CHIPS)':
 '1': CDS_PINID='\1\';
NODE_NAME     C217 1
 '@TIMECARD_LIB.TIMECARD(SCH_1):PAGE164_I258@PASSIVE.CAPACITOR(CHIPS)':
 '1': CDS_PINID='\1\';
NODE_NAME     C209 1
 '@TIMECARD_LIB.TIMECARD(SCH_1):PAGE164_I259@PASSIVE.CAPACITOR(CHIPS)':
 '1': CDS_PINID='\1\';
NODE_NAME     C205 1
 '@TIMECARD_LIB.TIMECARD(SCH_1):PAGE164_I260@PASSIVE.CAPACITOR(CHIPS)':
 '1': CDS_PINID='\1\';
NODE_NAME     C125 1
 '@TIMECARD_LIB.TIMECARD(SCH_1):PAGE164_I264@PASSIVE.CAPACITOR(CHIPS)':
 '1': CDS_PINID='\1\';
NET_NAME
'FPGA_MGTRREF'
 '@TIMECARD_LIB.TIMECARD(SCH_1):FPGA_MGTRREF':
 C_SIGNAL='@timecard_lib.timecard(sch_1):fpga_mgtrref';
NODE_NAME     U24 F8
 '@TIMECARD_LIB.TIMECARD(SCH_1):PAGE127_I232@PLD.XC7A200T_2FBG484C_FBG484(CHIPS)':
 'MGTRREF_216': CDS_PINID='MGTRREF_216';
NODE_NAME     R196 2
 '@TIMECARD_LIB.TIMECARD(SCH_1):PAGE127_I332@PASSIVE.RESISTOR(CHIPS)':
 '2': CDS_PINID='\2\';
NODE_NAME     TP47 1
 '@TIMECARD_LIB.TIMECARD(SCH_1):PAGE16_I1693@CLS.TP_PIONT(CHIPS)':
 '1': CDS_PINID='\1\';
NET_NAME
'FPGA_M_RGB_LED_I2C_SCL'
 '@TIMECARD_LIB.TIMECARD(SCH_1):FPGA_M_RGB_LED_I2C_SCL':
 C_SIGNAL='@timecard_lib.timecard(sch_1):fpga_m_rgb_led_i2c_scl';
NODE_NAME     U24 W20
 '@TIMECARD_LIB.TIMECARD(SCH_1):PAGE161_I2@PLD.XC7A200T_2FBG484C_FBG484(CHIPS)':
 'IO_L12N_T1_MRCC_14': CDS_PINID='IO_L12N_T1_MRCC_14';
NODE_NAME     R322 1
 '@TIMECARD_LIB.TIMECARD(SCH_1):PAGE14_I257@PASSIVE.RESISTOR(CHIPS)':
 '1': CDS_PINID='\1\';
NET_NAME
'FPGA_M_RGB_LED_I2C_SDA'
 '@TIMECARD_LIB.TIMECARD(SCH_1):FPGA_M_RGB_LED_I2C_SDA':
 C_SIGNAL='@timecard_lib.timecard(sch_1):fpga_m_rgb_led_i2c_sda';
NODE_NAME     U24 W19
 '@TIMECARD_LIB.TIMECARD(SCH_1):PAGE161_I2@PLD.XC7A200T_2FBG484C_FBG484(CHIPS)':
 'IO_L12P_T1_MRCC_14': CDS_PINID='IO_L12P_T1_MRCC_14';
NODE_NAME     R321 1
 '@TIMECARD_LIB.TIMECARD(SCH_1):PAGE14_I258@PASSIVE.RESISTOR(CHIPS)':
 '1': CDS_PINID='\1\';
NET_NAME
'FPGA_OUT_BNO080_BOOT_N'
 '@TIMECARD_LIB.TIMECARD(SCH_1):FPGA_OUT_BNO080_BOOT_N':
 C_SIGNAL='@timecard_lib.timecard(sch_1):fpga_out_bno080_boot_n';
NODE_NAME     U24 L15
 '@TIMECARD_LIB.TIMECARD(SCH_1):PAGE162_I228@PLD.XC7A200T_2FBG484C_FBG484(CHIPS)':
 'IO_L22N_T3_A16_15': CDS_PINID='IO_L22N_T3_A16_15';
NODE_NAME     R80 1
 '@TIMECARD_LIB.TIMECARD(SCH_1):PAGE9_I32@PASSIVE.RESISTOR(CHIPS)':
 '1': CDS_PINID='\1\';
NET_NAME
'FPGA_OUT_BNO080_RST_N'
 '@TIMECARD_LIB.TIMECARD(SCH_1):FPGA_OUT_BNO080_RST_N':
 C_SIGNAL='@timecard_lib.timecard(sch_1):fpga_out_bno080_rst_n';
NODE_NAME     U24 J17
 '@TIMECARD_LIB.TIMECARD(SCH_1):PAGE162_I228@PLD.XC7A200T_2FBG484C_FBG484(CHIPS)':
 'IO_L21N_T3_DQS_A18_15': CDS_PINID='IO_L21N_T3_DQS_A18_15';
NODE_NAME     R78 2
 '@TIMECARD_LIB.TIMECARD(SCH_1):PAGE9_I41@PASSIVE.RESISTOR(CHIPS)':
 '2': CDS_PINID='\2\';
NET_NAME
'FPGA_OUT_GPS_LED_BLUE_N'
 '@TIMECARD_LIB.TIMECARD(SCH_1):FPGA_OUT_GPS_LED_BLUE_N':
 C_SIGNAL='@timecard_lib.timecard(sch_1):fpga_out_gps_led_blue_n';
NODE_NAME     U24 B20
 '@TIMECARD_LIB.TIMECARD(SCH_1):PAGE162_I228@PLD.XC7A200T_2FBG484C_FBG484(CHIPS)':
 'IO_L16P_T2_16': CDS_PINID='IO_L16P_T2_16';
NODE_NAME     R425 1
 '@TIMECARD_LIB.TIMECARD(SCH_1):PAGE14_I170@PASSIVE.RESISTOR(CHIPS)':
 '1': CDS_PINID='\1\';
NET_NAME
'FPGA_OUT_GPS_LED_GREEN_N'
 '@TIMECARD_LIB.TIMECARD(SCH_1):FPGA_OUT_GPS_LED_GREEN_N':
 C_SIGNAL='@timecard_lib.timecard(sch_1):fpga_out_gps_led_green_n';
NODE_NAME     U24 A20
 '@TIMECARD_LIB.TIMECARD(SCH_1):PAGE162_I228@PLD.XC7A200T_2FBG484C_FBG484(CHIPS)':
 'IO_L16N_T2_16': CDS_PINID='IO_L16N_T2_16';
NODE_NAME     R426 1
 '@TIMECARD_LIB.TIMECARD(SCH_1):PAGE14_I179@PASSIVE.RESISTOR(CHIPS)':
 '1': CDS_PINID='\1\';
NET_NAME
'FPGA_OUT_GPS_LED_RED_N'
 '@TIMECARD_LIB.TIMECARD(SCH_1):FPGA_OUT_GPS_LED_RED_N':
 C_SIGNAL='@timecard_lib.timecard(sch_1):fpga_out_gps_led_red_n';
NODE_NAME     U24 A18
 '@TIMECARD_LIB.TIMECARD(SCH_1):PAGE162_I228@PLD.XC7A200T_2FBG484C_FBG484(CHIPS)':
 'IO_L17P_T2_16': CDS_PINID='IO_L17P_T2_16';
NODE_NAME     R427 1
 '@TIMECARD_LIB.TIMECARD(SCH_1):PAGE14_I188@PASSIVE.RESISTOR(CHIPS)':
 '1': CDS_PINID='\1\';
NET_NAME
'FPGA_OUT_GPS_RST_N'
 '@TIMECARD_LIB.TIMECARD(SCH_1):FPGA_OUT_GPS_RST_N':
 C_SIGNAL='@timecard_lib.timecard(sch_1):fpga_out_gps_rst_n';
NODE_NAME     R116 2
 '@TIMECARD_LIB.TIMECARD(SCH_1):PAGE11_I25@PASSIVE.RESISTOR(CHIPS)':
 '2': CDS_PINID='\2\';
NODE_NAME     U24 Y16
 '@TIMECARD_LIB.TIMECARD(SCH_1):PAGE161_I2@PLD.XC7A200T_2FBG484C_FBG484(CHIPS)':
 'IO_L1P_T0_13': CDS_PINID='IO_L1P_T0_13';
NET_NAME
'FPGA_OUT_I2C_BUFFER_EN'
 '@TIMECARD_LIB.TIMECARD(SCH_1):FPGA_OUT_I2C_BUFFER_EN':
 C_SIGNAL='@timecard_lib.timecard(sch_1):fpga_out_i2c_buffer_en';
NODE_NAME     U24 K16
 '@TIMECARD_LIB.TIMECARD(SCH_1):PAGE162_I228@PLD.XC7A200T_2FBG484C_FBG484(CHIPS)':
 'IO_L23N_T3_FWE_B_15': CDS_PINID='IO_L23N_T3_FWE_B_15';
NODE_NAME     R354 1
 '@TIMECARD_LIB.TIMECARD(SCH_1):PAGE3_I114@PASSIVE.RESISTOR(CHIPS)':
 '1': CDS_PINID='\1\';
NET_NAME
'FPGA_OUT_MACUSBPOWER_EN'
 '@TIMECARD_LIB.TIMECARD(SCH_1):FPGA_OUT_MACUSBPOWER_EN':
 C_SIGNAL='@timecard_lib.timecard(sch_1):fpga_out_macusbpower_en';
NODE_NAME     U24 V15
 '@TIMECARD_LIB.TIMECARD(SCH_1):PAGE161_I2@PLD.XC7A200T_2FBG484C_FBG484(CHIPS)':
 'IO_L14N_T2_SRCC_13': CDS_PINID='IO_L14N_T2_SRCC_13';
NODE_NAME     U10 1
 '@TIMECARD_LIB.TIMECARD(SCH_1):PAGE527_I147@STDLOGIC.CL5003148A(CHIPS)':
 'A': CDS_PINID='A';
NODE_NAME     R99 1
 '@TIMECARD_LIB.TIMECARD(SCH_1):PAGE527_I149@PASSIVE.RESISTOR(CHIPS)':
 '1': CDS_PINID='\1\';
NODE_NAME     R100 1
 '@TIMECARD_LIB.TIMECARD(SCH_1):PAGE527_I155@PASSIVE.RESISTOR(CHIPS)':
 '1': CDS_PINID='\1\';
NET_NAME
'FPGA_OUT_MAC_PPS_IN0N'
 '@TIMECARD_LIB.TIMECARD(SCH_1):FPGA_OUT_MAC_PPS_IN0N':
 C_SIGNAL='@timecard_lib.timecard(sch_1):fpga_out_mac_pps_in0n';
NODE_NAME     U24 AB2
 '@TIMECARD_LIB.TIMECARD(SCH_1):PAGE163_I1@PLD.XC7A200T_2FBG484C_FBG484(CHIPS)':
 'IO_L8N_T1_34': CDS_PINID='IO_L8N_T1_34';
NODE_NAME     R276 2
 '@TIMECARD_LIB.TIMECARD(SCH_1):PAGE163_I38@PASSIVE.RESISTOR(CHIPS)':
 '2': CDS_PINID='\2\';
NODE_NAME     R86 1
 '@TIMECARD_LIB.TIMECARD(SCH_1):PAGE527_I29@PASSIVE.RESISTOR(CHIPS)':
 '1': CDS_PINID='\1\';
NET_NAME
'FPGA_OUT_MAC_PPS_IN0P'
 '@TIMECARD_LIB.TIMECARD(SCH_1):FPGA_OUT_MAC_PPS_IN0P':
 C_SIGNAL='@timecard_lib.timecard(sch_1):fpga_out_mac_pps_in0p';
NODE_NAME     U24 AB3
 '@TIMECARD_LIB.TIMECARD(SCH_1):PAGE163_I1@PLD.XC7A200T_2FBG484C_FBG484(CHIPS)':
 'IO_L8P_T1_34': CDS_PINID='IO_L8P_T1_34';
NODE_NAME     R276 1
 '@TIMECARD_LIB.TIMECARD(SCH_1):PAGE163_I38@PASSIVE.RESISTOR(CHIPS)':
 '1': CDS_PINID='\1\';
NODE_NAME     R85 1
 '@TIMECARD_LIB.TIMECARD(SCH_1):PAGE527_I30@PASSIVE.RESISTOR(CHIPS)':
 '1': CDS_PINID='\1\';
NET_NAME
'FPGA_OUT_MAC_PPS_IN1N'
 '@TIMECARD_LIB.TIMECARD(SCH_1):FPGA_OUT_MAC_PPS_IN1N':
 C_SIGNAL='@timecard_lib.timecard(sch_1):fpga_out_mac_pps_in1n';
NODE_NAME     U24 AB5
 '@TIMECARD_LIB.TIMECARD(SCH_1):PAGE163_I1@PLD.XC7A200T_2FBG484C_FBG484(CHIPS)':
 'IO_L10N_T1_34': CDS_PINID='IO_L10N_T1_34';
NODE_NAME     R277 2
 '@TIMECARD_LIB.TIMECARD(SCH_1):PAGE163_I37@PASSIVE.RESISTOR(CHIPS)':
 '2': CDS_PINID='\2\';
NODE_NAME     R84 1
 '@TIMECARD_LIB.TIMECARD(SCH_1):PAGE527_I31@PASSIVE.RESISTOR(CHIPS)':
 '1': CDS_PINID='\1\';
NET_NAME
'FPGA_OUT_MAC_PPS_IN1P'
 '@TIMECARD_LIB.TIMECARD(SCH_1):FPGA_OUT_MAC_PPS_IN1P':
 C_SIGNAL='@timecard_lib.timecard(sch_1):fpga_out_mac_pps_in1p';
NODE_NAME     U24 AA5
 '@TIMECARD_LIB.TIMECARD(SCH_1):PAGE163_I1@PLD.XC7A200T_2FBG484C_FBG484(CHIPS)':
 'IO_L10P_T1_34': CDS_PINID='IO_L10P_T1_34';
NODE_NAME     R277 1
 '@TIMECARD_LIB.TIMECARD(SCH_1):PAGE163_I37@PASSIVE.RESISTOR(CHIPS)':
 '1': CDS_PINID='\1\';
NODE_NAME     R83 1
 '@TIMECARD_LIB.TIMECARD(SCH_1):PAGE527_I32@PASSIVE.RESISTOR(CHIPS)':
 '1': CDS_PINID='\1\';
NET_NAME
'FPGA_OUT_MUX1_SEL'
 '@TIMECARD_LIB.TIMECARD(SCH_1):FPGA_OUT_MUX1_SEL':
 C_SIGNAL='@timecard_lib.timecard(sch_1):fpga_out_mux1_sel';
NODE_NAME     U24 H13
 '@TIMECARD_LIB.TIMECARD(SCH_1):PAGE162_I228@PLD.XC7A200T_2FBG484C_FBG484(CHIPS)':
 'IO_L1P_T0_AD0P_15': CDS_PINID='IO_L1P_T0_AD0P_15';
NODE_NAME     R448 2
 '@TIMECARD_LIB.TIMECARD(SCH_1):PAGE524_I423@PASSIVE.RESISTOR(CHIPS)':
 '2': CDS_PINID='\2\';
NET_NAME
'FPGA_OUT_MUX2_SEL'
 '@TIMECARD_LIB.TIMECARD(SCH_1):FPGA_OUT_MUX2_SEL':
 C_SIGNAL='@timecard_lib.timecard(sch_1):fpga_out_mux2_sel';
NODE_NAME     U24 G13
 '@TIMECARD_LIB.TIMECARD(SCH_1):PAGE162_I228@PLD.XC7A200T_2FBG484C_FBG484(CHIPS)':
 'IO_L1N_T0_AD0N_15': CDS_PINID='IO_L1N_T0_AD0N_15';
NODE_NAME     R461 1
 '@TIMECARD_LIB.TIMECARD(SCH_1):PAGE524_I411@PASSIVE.RESISTOR(CHIPS)':
 '1': CDS_PINID='\1\';
NET_NAME
'FPGA_OUT_MUX3_SEL'
 '@TIMECARD_LIB.TIMECARD(SCH_1):FPGA_OUT_MUX3_SEL':
 C_SIGNAL='@timecard_lib.timecard(sch_1):fpga_out_mux3_sel';
NODE_NAME     U24 G15
 '@TIMECARD_LIB.TIMECARD(SCH_1):PAGE162_I228@PLD.XC7A200T_2FBG484C_FBG484(CHIPS)':
 'IO_L2P_T0_AD8P_15': CDS_PINID='IO_L2P_T0_AD8P_15';
NODE_NAME     R485 1
 '@TIMECARD_LIB.TIMECARD(SCH_1):PAGE524_I459@PASSIVE.RESISTOR(CHIPS)':
 '1': CDS_PINID='\1\';
NET_NAME
'FPGA_OUT_PCA9546_RST_N'
 '@TIMECARD_LIB.TIMECARD(SCH_1):FPGA_OUT_PCA9546_RST_N':
 C_SIGNAL='@timecard_lib.timecard(sch_1):fpga_out_pca9546_rst_n';
NODE_NAME     U24 U16
 '@TIMECARD_LIB.TIMECARD(SCH_1):PAGE161_I2@PLD.XC7A200T_2FBG484C_FBG484(CHIPS)':
 'IO_L17N_T2_13': CDS_PINID='IO_L17N_T2_13';
NODE_NAME     R60 1
 '@TIMECARD_LIB.TIMECARD(SCH_1):PAGE5_I125@PASSIVE.RESISTOR(CHIPS)':
 '1': CDS_PINID='\1\';
NET_NAME
'FPGA_OUT_RGB_LED_SHUTDOWN_N'
 '@TIMECARD_LIB.TIMECARD(SCH_1):FPGA_OUT_RGB_LED_SHUTDOWN_N':
 C_SIGNAL='@timecard_lib.timecard(sch_1):fpga_out_rgb_led_shutdown_n';
NODE_NAME     U24 Y18
 '@TIMECARD_LIB.TIMECARD(SCH_1):PAGE161_I2@PLD.XC7A200T_2FBG484C_FBG484(CHIPS)':
 'IO_L13P_T2_MRCC_14': CDS_PINID='IO_L13P_T2_MRCC_14';
NODE_NAME     R319 1
 '@TIMECARD_LIB.TIMECARD(SCH_1):PAGE14_I249@PASSIVE.RESISTOR(CHIPS)':
 '1': CDS_PINID='\1\';
NET_NAME
'FPGA_OUT_SEC_EEPROM_WP'
 '@TIMECARD_LIB.TIMECARD(SCH_1):FPGA_OUT_SEC_EEPROM_WP':
 C_SIGNAL='@timecard_lib.timecard(sch_1):fpga_out_sec_eeprom_wp';
NODE_NAME     U24 AB13
 '@TIMECARD_LIB.TIMECARD(SCH_1):PAGE161_I2@PLD.XC7A200T_2FBG484C_FBG484(CHIPS)':
 'IO_L3N_T0_DQS_13': CDS_PINID='IO_L3N_T0_DQS_13';
NODE_NAME     R2 1
 '@TIMECARD_LIB.TIMECARD(SCH_1):PAGE5_I173@PASSIVE.RESISTOR(CHIPS)':
 '1': CDS_PINID='\1\';
NET_NAME
'FPGA_OUT_SHT3X_RST_N'
 '@TIMECARD_LIB.TIMECARD(SCH_1):FPGA_OUT_SHT3X_RST_N':
 C_SIGNAL='@timecard_lib.timecard(sch_1):fpga_out_sht3x_rst_n';
NODE_NAME     U24 H19
 '@TIMECARD_LIB.TIMECARD(SCH_1):PAGE162_I228@PLD.XC7A200T_2FBG484C_FBG484(CHIPS)':
 'IO_L12N_T1_MRCC_15': CDS_PINID='IO_L12N_T1_MRCC_15';
NODE_NAME     R298 2
 '@TIMECARD_LIB.TIMECARD(SCH_1):PAGE7_I33@PASSIVE.RESISTOR(CHIPS)':
 '2': CDS_PINID='\2\';
NET_NAME
'FPGA_OUT_SMA1_LED_BLUE_N'
 '@TIMECARD_LIB.TIMECARD(SCH_1):FPGA_OUT_SMA1_LED_BLUE_N':
 C_SIGNAL='@timecard_lib.timecard(sch_1):fpga_out_sma1_led_blue_n';
NODE_NAME     U24 F13
 '@TIMECARD_LIB.TIMECARD(SCH_1):PAGE162_I228@PLD.XC7A200T_2FBG484C_FBG484(CHIPS)':
 'IO_L1P_T0_16': CDS_PINID='IO_L1P_T0_16';
NODE_NAME     R124 1
 '@TIMECARD_LIB.TIMECARD(SCH_1):PAGE14_I160@PASSIVE.RESISTOR(CHIPS)':
 '1': CDS_PINID='\1\';
NET_NAME
'FPGA_OUT_SMA1_LED_GREEN_N'
 '@TIMECARD_LIB.TIMECARD(SCH_1):FPGA_OUT_SMA1_LED_GREEN_N':
 C_SIGNAL='@timecard_lib.timecard(sch_1):fpga_out_sma1_led_green_n';
NODE_NAME     U24 F14
 '@TIMECARD_LIB.TIMECARD(SCH_1):PAGE162_I228@PLD.XC7A200T_2FBG484C_FBG484(CHIPS)':
 'IO_L1N_T0_16': CDS_PINID='IO_L1N_T0_16';
NODE_NAME     R125 1
 '@TIMECARD_LIB.TIMECARD(SCH_1):PAGE14_I161@PASSIVE.RESISTOR(CHIPS)':
 '1': CDS_PINID='\1\';
NET_NAME
'FPGA_OUT_SMA1_LED_RED_N'
 '@TIMECARD_LIB.TIMECARD(SCH_1):FPGA_OUT_SMA1_LED_RED_N':
 C_SIGNAL='@timecard_lib.timecard(sch_1):fpga_out_sma1_led_red_n';
NODE_NAME     U24 F16
 '@TIMECARD_LIB.TIMECARD(SCH_1):PAGE162_I228@PLD.XC7A200T_2FBG484C_FBG484(CHIPS)':
 'IO_L2P_T0_16': CDS_PINID='IO_L2P_T0_16';
NODE_NAME     R272 1
 '@TIMECARD_LIB.TIMECARD(SCH_1):PAGE14_I163@PASSIVE.RESISTOR(CHIPS)':
 '1': CDS_PINID='\1\';
NET_NAME
'FPGA_OUT_SMA2_LED_BLUE_N'
 '@TIMECARD_LIB.TIMECARD(SCH_1):FPGA_OUT_SMA2_LED_BLUE_N':
 C_SIGNAL='@timecard_lib.timecard(sch_1):fpga_out_sma2_led_blue_n';
NODE_NAME     U24 C14
 '@TIMECARD_LIB.TIMECARD(SCH_1):PAGE162_I228@PLD.XC7A200T_2FBG484C_FBG484(CHIPS)':
 'IO_L3P_T0_DQS_16': CDS_PINID='IO_L3P_T0_DQS_16';
NODE_NAME     R273 1
 '@TIMECARD_LIB.TIMECARD(SCH_1):PAGE14_I165@PASSIVE.RESISTOR(CHIPS)':
 '1': CDS_PINID='\1\';
NET_NAME
'FPGA_OUT_SMA2_LED_GREEN_N'
 '@TIMECARD_LIB.TIMECARD(SCH_1):FPGA_OUT_SMA2_LED_GREEN_N':
 C_SIGNAL='@timecard_lib.timecard(sch_1):fpga_out_sma2_led_green_n';
NODE_NAME     U24 C15
 '@TIMECARD_LIB.TIMECARD(SCH_1):PAGE162_I228@PLD.XC7A200T_2FBG484C_FBG484(CHIPS)':
 'IO_L3N_T0_DQS_16': CDS_PINID='IO_L3N_T0_DQS_16';
NODE_NAME     R274 1
 '@TIMECARD_LIB.TIMECARD(SCH_1):PAGE14_I171@PASSIVE.RESISTOR(CHIPS)':
 '1': CDS_PINID='\1\';
NET_NAME
'FPGA_OUT_SMA2_LED_RED_N'
 '@TIMECARD_LIB.TIMECARD(SCH_1):FPGA_OUT_SMA2_LED_RED_N':
 C_SIGNAL='@timecard_lib.timecard(sch_1):fpga_out_sma2_led_red_n';
NODE_NAME     U24 E13
 '@TIMECARD_LIB.TIMECARD(SCH_1):PAGE162_I228@PLD.XC7A200T_2FBG484C_FBG484(CHIPS)':
 'IO_L4P_T0_16': CDS_PINID='IO_L4P_T0_16';
NODE_NAME     R373 1
 '@TIMECARD_LIB.TIMECARD(SCH_1):PAGE14_I181@PASSIVE.RESISTOR(CHIPS)':
 '1': CDS_PINID='\1\';
NET_NAME
'FPGA_OUT_SMA3_LED_BLUE_N'
 '@TIMECARD_LIB.TIMECARD(SCH_1):FPGA_OUT_SMA3_LED_BLUE_N':
 C_SIGNAL='@timecard_lib.timecard(sch_1):fpga_out_sma3_led_blue_n';
NODE_NAME     U24 D17
 '@TIMECARD_LIB.TIMECARD(SCH_1):PAGE162_I228@PLD.XC7A200T_2FBG484C_FBG484(CHIPS)':
 'IO_L12P_T1_MRCC_16': CDS_PINID='IO_L12P_T1_MRCC_16';
NODE_NAME     R374 1
 '@TIMECARD_LIB.TIMECARD(SCH_1):PAGE14_I168@PASSIVE.RESISTOR(CHIPS)':
 '1': CDS_PINID='\1\';
NET_NAME
'FPGA_OUT_SMA3_LED_GREEN_N'
 '@TIMECARD_LIB.TIMECARD(SCH_1):FPGA_OUT_SMA3_LED_GREEN_N':
 C_SIGNAL='@timecard_lib.timecard(sch_1):fpga_out_sma3_led_green_n';
NODE_NAME     U24 C17
 '@TIMECARD_LIB.TIMECARD(SCH_1):PAGE162_I228@PLD.XC7A200T_2FBG484C_FBG484(CHIPS)':
 'IO_L12N_T1_MRCC_16': CDS_PINID='IO_L12N_T1_MRCC_16';
NODE_NAME     R375 1
 '@TIMECARD_LIB.TIMECARD(SCH_1):PAGE14_I174@PASSIVE.RESISTOR(CHIPS)':
 '1': CDS_PINID='\1\';
NET_NAME
'FPGA_OUT_SMA3_LED_RED_N'
 '@TIMECARD_LIB.TIMECARD(SCH_1):FPGA_OUT_SMA3_LED_RED_N':
 C_SIGNAL='@timecard_lib.timecard(sch_1):fpga_out_sma3_led_red_n';
NODE_NAME     U24 C18
 '@TIMECARD_LIB.TIMECARD(SCH_1):PAGE162_I228@PLD.XC7A200T_2FBG484C_FBG484(CHIPS)':
 'IO_L13P_T2_MRCC_16': CDS_PINID='IO_L13P_T2_MRCC_16';
NODE_NAME     R376 1
 '@TIMECARD_LIB.TIMECARD(SCH_1):PAGE14_I184@PASSIVE.RESISTOR(CHIPS)':
 '1': CDS_PINID='\1\';
NET_NAME
'FPGA_OUT_SMA4_LED_BLUE_N'
 '@TIMECARD_LIB.TIMECARD(SCH_1):FPGA_OUT_SMA4_LED_BLUE_N':
 C_SIGNAL='@timecard_lib.timecard(sch_1):fpga_out_sma4_led_blue_n';
NODE_NAME     U24 E19
 '@TIMECARD_LIB.TIMECARD(SCH_1):PAGE162_I228@PLD.XC7A200T_2FBG484C_FBG484(CHIPS)':
 'IO_L14P_T2_SRCC_16': CDS_PINID='IO_L14P_T2_SRCC_16';
NODE_NAME     R400 1
 '@TIMECARD_LIB.TIMECARD(SCH_1):PAGE14_I177@PASSIVE.RESISTOR(CHIPS)':
 '1': CDS_PINID='\1\';
NET_NAME
'FPGA_OUT_SMA4_LED_GREEN_N'
 '@TIMECARD_LIB.TIMECARD(SCH_1):FPGA_OUT_SMA4_LED_GREEN_N':
 C_SIGNAL='@timecard_lib.timecard(sch_1):fpga_out_sma4_led_green_n';
NODE_NAME     U24 D19
 '@TIMECARD_LIB.TIMECARD(SCH_1):PAGE162_I228@PLD.XC7A200T_2FBG484C_FBG484(CHIPS)':
 'IO_L14N_T2_SRCC_16': CDS_PINID='IO_L14N_T2_SRCC_16';
NODE_NAME     R401 1
 '@TIMECARD_LIB.TIMECARD(SCH_1):PAGE14_I176@PASSIVE.RESISTOR(CHIPS)':
 '1': CDS_PINID='\1\';
NET_NAME
'FPGA_OUT_SMA4_LED_RED_N'
 '@TIMECARD_LIB.TIMECARD(SCH_1):FPGA_OUT_SMA4_LED_RED_N':
 C_SIGNAL='@timecard_lib.timecard(sch_1):fpga_out_sma4_led_red_n';
NODE_NAME     U24 F18
 '@TIMECARD_LIB.TIMECARD(SCH_1):PAGE162_I228@PLD.XC7A200T_2FBG484C_FBG484(CHIPS)':
 'IO_L15P_T2_DQS_16': CDS_PINID='IO_L15P_T2_DQS_16';
NODE_NAME     R424 1
 '@TIMECARD_LIB.TIMECARD(SCH_1):PAGE14_I186@PASSIVE.RESISTOR(CHIPS)':
 '1': CDS_PINID='\1\';
NET_NAME
'FPGA_OUT_SN_EEPROM_WP'
 '@TIMECARD_LIB.TIMECARD(SCH_1):FPGA_OUT_SN_EEPROM_WP':
 C_SIGNAL='@timecard_lib.timecard(sch_1):fpga_out_sn_eeprom_wp';
NODE_NAME     U24 AA13
 '@TIMECARD_LIB.TIMECARD(SCH_1):PAGE161_I2@PLD.XC7A200T_2FBG484C_FBG484(CHIPS)':
 'IO_L3P_T0_DQS_13': CDS_PINID='IO_L3P_T0_DQS_13';
NODE_NAME     R1 1
 '@TIMECARD_LIB.TIMECARD(SCH_1):PAGE5_I130@PASSIVE.RESISTOR(CHIPS)':
 '1': CDS_PINID='\1\';
NET_NAME
'FPGA_PCA9546_I2C_SCL'
 '@TIMECARD_LIB.TIMECARD(SCH_1):FPGA_PCA9546_I2C_SCL':
 C_SIGNAL='@timecard_lib.timecard(sch_1):fpga_pca9546_i2c_scl';
NODE_NAME     U24 N17
 '@TIMECARD_LIB.TIMECARD(SCH_1):PAGE161_I2@PLD.XC7A200T_2FBG484C_FBG484(CHIPS)':
 'IO_L21P_T3_DQS_14': CDS_PINID='IO_L21P_T3_DQS_14';
NODE_NAME     U37 5
 '@TIMECARD_LIB.TIMECARD(SCH_1):PAGE524_I448@STDLOGIC.TS3A5018PWR_TSSOP16(CHIPS)':
 'NC2': CDS_PINID='NC2';
NODE_NAME     R475 2
 '@TIMECARD_LIB.TIMECARD(SCH_1):PAGE524_I467@PASSIVE.RESISTOR(CHIPS)':
 '2': CDS_PINID='\2\';
NET_NAME
'FPGA_PCA9546_I2C_SDA'
 '@TIMECARD_LIB.TIMECARD(SCH_1):FPGA_PCA9546_I2C_SDA':
 C_SIGNAL='@timecard_lib.timecard(sch_1):fpga_pca9546_i2c_sda';
NODE_NAME     U24 T16
 '@TIMECARD_LIB.TIMECARD(SCH_1):PAGE161_I2@PLD.XC7A200T_2FBG484C_FBG484(CHIPS)':
 'IO_L17P_T2_13': CDS_PINID='IO_L17P_T2_13';
NODE_NAME     U37 2
 '@TIMECARD_LIB.TIMECARD(SCH_1):PAGE524_I448@STDLOGIC.TS3A5018PWR_TSSOP16(CHIPS)':
 'NC1': CDS_PINID='NC1';
NODE_NAME     R474 2
 '@TIMECARD_LIB.TIMECARD(SCH_1):PAGE524_I466@PASSIVE.RESISTOR(CHIPS)':
 '2': CDS_PINID='\2\';
NET_NAME
'FPGA_PROGRAM_N'
 '@TIMECARD_LIB.TIMECARD(SCH_1):FPGA_PROGRAM_N':
 C_SIGNAL='@timecard_lib.timecard(sch_1):fpga_program_n';
NODE_NAME     U24 N12
 '@TIMECARD_LIB.TIMECARD(SCH_1):PAGE127_I232@PLD.XC7A200T_2FBG484C_FBG484(CHIPS)':
 'PROGRAM_0*': CDS_PINID='\program_0*\';
NODE_NAME     R193 2
 '@TIMECARD_LIB.TIMECARD(SCH_1):PAGE127_I330@PASSIVE.RESISTOR(CHIPS)':
 '2': CDS_PINID='\2\';
NODE_NAME     R356 2
 '@TIMECARD_LIB.TIMECARD(SCH_1):PAGE3_I122@PASSIVE.RESISTOR(CHIPS)':
 '2': CDS_PINID='\2\';
NODE_NAME     TP45 1
 '@TIMECARD_LIB.TIMECARD(SCH_1):PAGE16_I1690@CLS.TP_PIONT(CHIPS)':
 '1': CDS_PINID='\1\';
NET_NAME
'FPGA_TCK'
 '@TIMECARD_LIB.TIMECARD(SCH_1):FPGA_TCK':
 C_SIGNAL='@timecard_lib.timecard(sch_1):fpga_tck';
NODE_NAME     R28 2
 '@TIMECARD_LIB.TIMECARD(SCH_1):PAGE3_I54@PASSIVE.RESISTOR(CHIPS)':
 '2': CDS_PINID='\2\';
NODE_NAME     U24 V12
 '@TIMECARD_LIB.TIMECARD(SCH_1):PAGE127_I232@PLD.XC7A200T_2FBG484C_FBG484(CHIPS)':
 'TCK_0': CDS_PINID='TCK_0';
NODE_NAME     R134 2
 '@TIMECARD_LIB.TIMECARD(SCH_1):PAGE127_I436@PASSIVE.RESISTOR(CHIPS)':
 '2': CDS_PINID='\2\';
NODE_NAME     R402 1
 '@TIMECARD_LIB.TIMECARD(SCH_1):PAGE127_I440@PASSIVE.RESISTOR(CHIPS)':
 '1': CDS_PINID='\1\';
NET_NAME
'FPGA_TDI'
 '@TIMECARD_LIB.TIMECARD(SCH_1):FPGA_TDI':
 C_SIGNAL='@timecard_lib.timecard(sch_1):fpga_tdi';
NODE_NAME     R41 2
 '@TIMECARD_LIB.TIMECARD(SCH_1):PAGE3_I53@PASSIVE.RESISTOR(CHIPS)':
 '2': CDS_PINID='\2\';
NODE_NAME     U24 R13
 '@TIMECARD_LIB.TIMECARD(SCH_1):PAGE127_I232@PLD.XC7A200T_2FBG484C_FBG484(CHIPS)':
 'TDI_0': CDS_PINID='TDI_0';
NODE_NAME     R405 2
 '@TIMECARD_LIB.TIMECARD(SCH_1):PAGE127_I432@PASSIVE.RESISTOR(CHIPS)':
 '2': CDS_PINID='\2\';
NODE_NAME     R137 2
 '@TIMECARD_LIB.TIMECARD(SCH_1):PAGE127_I439@PASSIVE.RESISTOR(CHIPS)':
 '2': CDS_PINID='\2\';
NET_NAME
'FPGA_TDO'
 '@TIMECARD_LIB.TIMECARD(SCH_1):FPGA_TDO':
 C_SIGNAL='@timecard_lib.timecard(sch_1):fpga_tdo';
NODE_NAME     R42 2
 '@TIMECARD_LIB.TIMECARD(SCH_1):PAGE3_I52@PASSIVE.RESISTOR(CHIPS)':
 '2': CDS_PINID='\2\';
NODE_NAME     R195 1
 '@TIMECARD_LIB.TIMECARD(SCH_1):PAGE127_I331@PASSIVE.RESISTOR(CHIPS)':
 '1': CDS_PINID='\1\';
NODE_NAME     R403 2
 '@TIMECARD_LIB.TIMECARD(SCH_1):PAGE127_I435@PASSIVE.RESISTOR(CHIPS)':
 '2': CDS_PINID='\2\';
NODE_NAME     R135 2
 '@TIMECARD_LIB.TIMECARD(SCH_1):PAGE127_I438@PASSIVE.RESISTOR(CHIPS)':
 '2': CDS_PINID='\2\';
NET_NAME
'FPGA_TMS'
 '@TIMECARD_LIB.TIMECARD(SCH_1):FPGA_TMS':
 C_SIGNAL='@timecard_lib.timecard(sch_1):fpga_tms';
NODE_NAME     R43 2
 '@TIMECARD_LIB.TIMECARD(SCH_1):PAGE3_I51@PASSIVE.RESISTOR(CHIPS)':
 '2': CDS_PINID='\2\';
NODE_NAME     U24 T13
 '@TIMECARD_LIB.TIMECARD(SCH_1):PAGE127_I232@PLD.XC7A200T_2FBG484C_FBG484(CHIPS)':
 'TMS_0': CDS_PINID='TMS_0';
NODE_NAME     R404 2
 '@TIMECARD_LIB.TIMECARD(SCH_1):PAGE127_I434@PASSIVE.RESISTOR(CHIPS)':
 '2': CDS_PINID='\2\';
NODE_NAME     R136 2
 '@TIMECARD_LIB.TIMECARD(SCH_1):PAGE127_I437@PASSIVE.RESISTOR(CHIPS)':
 '2': CDS_PINID='\2\';
NET_NAME
'FPGA_USR_LED0'
 '@TIMECARD_LIB.TIMECARD(SCH_1):FPGA_USR_LED0':
 C_SIGNAL='@timecard_lib.timecard(sch_1):fpga_usr_led0';
NODE_NAME     U24 A14
 '@TIMECARD_LIB.TIMECARD(SCH_1):PAGE162_I228@PLD.XC7A200T_2FBG484C_FBG484(CHIPS)':
 'IO_L10N_T1_16': CDS_PINID='IO_L10N_T1_16';
NODE_NAME     DS11 C
 '@TIMECARD_LIB.TIMECARD(SCH_1):PAGE14_I139@DISCRETE.OPTICAL(CHIPS)':
 'C': CDS_PINID='C';
NET_NAME
'FPGA_USR_LED1'
 '@TIMECARD_LIB.TIMECARD(SCH_1):FPGA_USR_LED1':
 C_SIGNAL='@timecard_lib.timecard(sch_1):fpga_usr_led1';
NODE_NAME     U24 A13
 '@TIMECARD_LIB.TIMECARD(SCH_1):PAGE162_I228@PLD.XC7A200T_2FBG484C_FBG484(CHIPS)':
 'IO_L10P_T1_16': CDS_PINID='IO_L10P_T1_16';
NODE_NAME     DS10 C
 '@TIMECARD_LIB.TIMECARD(SCH_1):PAGE14_I138@DISCRETE.OPTICAL(CHIPS)':
 'C': CDS_PINID='C';
NET_NAME
'FT4232_CHD_RX'
 '@TIMECARD_LIB.TIMECARD(SCH_1):FT4232_CHD_RX':
 C_SIGNAL='@timecard_lib.timecard(sch_1):ft4232_chd_rx';
NODE_NAME     J10 5
 '@TIMECARD_LIB.TIMECARD(SCH_1):PAGE524_I173@CONNECTOR.G200_10283_01(CHIPS)':
 '5': CDS_PINID='\5\';
NODE_NAME     J10 7
 '@TIMECARD_LIB.TIMECARD(SCH_1):PAGE524_I173@CONNECTOR.G200_10283_01(CHIPS)':
 '7': CDS_PINID='\7\';
NODE_NAME     R132 2
 '@TIMECARD_LIB.TIMECARD(SCH_1):PAGE524_I188@PASSIVE.RESISTOR(CHIPS)':
 '2': CDS_PINID='\2\';
NET_NAME
'FT4232_CHD_TX'
 '@TIMECARD_LIB.TIMECARD(SCH_1):FT4232_CHD_TX':
 C_SIGNAL='@timecard_lib.timecard(sch_1):ft4232_chd_tx';
NODE_NAME     J10 1
 '@TIMECARD_LIB.TIMECARD(SCH_1):PAGE524_I173@CONNECTOR.G200_10283_01(CHIPS)':
 '1': CDS_PINID='\1\';
NODE_NAME     J10 3
 '@TIMECARD_LIB.TIMECARD(SCH_1):PAGE524_I173@CONNECTOR.G200_10283_01(CHIPS)':
 '3': CDS_PINID='\3\';
NODE_NAME     R131 2
 '@TIMECARD_LIB.TIMECARD(SCH_1):PAGE524_I187@PASSIVE.RESISTOR(CHIPS)':
 '2': CDS_PINID='\2\';
NET_NAME
'FT4232_FPGA_TCK'
 '@TIMECARD_LIB.TIMECARD(SCH_1):FT4232_FPGA_TCK':
 C_SIGNAL='@timecard_lib.timecard(sch_1):ft4232_fpga_tck';
NODE_NAME     J14 1
 '@TIMECARD_LIB.TIMECARD(SCH_1):PAGE127_I427@CONNECTOR.G200_10283_01(CHIPS)':
 '1': CDS_PINID='\1\';
NODE_NAME     R134 1
 '@TIMECARD_LIB.TIMECARD(SCH_1):PAGE127_I436@PASSIVE.RESISTOR(CHIPS)':
 '1': CDS_PINID='\1\';
NODE_NAME     CR7 2
 '@TIMECARD_LIB.TIMECARD(SCH_1):PAGE127_I442@DISCRETE.DIODE_4_V1(CHIPS)':
 'IO1': CDS_PINID='IO1';
NODE_NAME     U30 2
 '@TIMECARD_LIB.TIMECARD(SCH_1):PAGE524_I425@STDLOGIC.TS3A5018PWR_TSSOP16(CHIPS)':
 'NC1': CDS_PINID='NC1';
NET_NAME
'FT4232_FPGA_TDI'
 '@TIMECARD_LIB.TIMECARD(SCH_1):FT4232_FPGA_TDI':
 C_SIGNAL='@timecard_lib.timecard(sch_1):ft4232_fpga_tdi';
NODE_NAME     J14 9
 '@TIMECARD_LIB.TIMECARD(SCH_1):PAGE127_I427@CONNECTOR.G200_10283_01(CHIPS)':
 '9': CDS_PINID='\9\';
NODE_NAME     R137 1
 '@TIMECARD_LIB.TIMECARD(SCH_1):PAGE127_I439@PASSIVE.RESISTOR(CHIPS)':
 '1': CDS_PINID='\1\';
NODE_NAME     CR6 3
 '@TIMECARD_LIB.TIMECARD(SCH_1):PAGE127_I443@DISCRETE.DIODE_4_V1(CHIPS)':
 'IO2': CDS_PINID='IO2';
NODE_NAME     U30 5
 '@TIMECARD_LIB.TIMECARD(SCH_1):PAGE524_I425@STDLOGIC.TS3A5018PWR_TSSOP16(CHIPS)':
 'NC2': CDS_PINID='NC2';
NET_NAME
'FT4232_FPGA_TDO'
 '@TIMECARD_LIB.TIMECARD(SCH_1):FT4232_FPGA_TDO':
 C_SIGNAL='@timecard_lib.timecard(sch_1):ft4232_fpga_tdo';
NODE_NAME     J14 3
 '@TIMECARD_LIB.TIMECARD(SCH_1):PAGE127_I427@CONNECTOR.G200_10283_01(CHIPS)':
 '3': CDS_PINID='\3\';
NODE_NAME     R135 1
 '@TIMECARD_LIB.TIMECARD(SCH_1):PAGE127_I438@PASSIVE.RESISTOR(CHIPS)':
 '1': CDS_PINID='\1\';
NODE_NAME     CR7 3
 '@TIMECARD_LIB.TIMECARD(SCH_1):PAGE127_I442@DISCRETE.DIODE_4_V1(CHIPS)':
 'IO2': CDS_PINID='IO2';
NODE_NAME     U30 11
 '@TIMECARD_LIB.TIMECARD(SCH_1):PAGE524_I425@STDLOGIC.TS3A5018PWR_TSSOP16(CHIPS)':
 'NC3': CDS_PINID='NC3';
NET_NAME
'FT4232_FPGA_TMS'
 '@TIMECARD_LIB.TIMECARD(SCH_1):FT4232_FPGA_TMS':
 C_SIGNAL='@timecard_lib.timecard(sch_1):ft4232_fpga_tms';
NODE_NAME     J14 5
 '@TIMECARD_LIB.TIMECARD(SCH_1):PAGE127_I427@CONNECTOR.G200_10283_01(CHIPS)':
 '5': CDS_PINID='\5\';
NODE_NAME     R136 1
 '@TIMECARD_LIB.TIMECARD(SCH_1):PAGE127_I437@PASSIVE.RESISTOR(CHIPS)':
 '1': CDS_PINID='\1\';
NODE_NAME     CR6 2
 '@TIMECARD_LIB.TIMECARD(SCH_1):PAGE127_I443@DISCRETE.DIODE_4_V1(CHIPS)':
 'IO1': CDS_PINID='IO1';
NODE_NAME     U30 14
 '@TIMECARD_LIB.TIMECARD(SCH_1):PAGE524_I425@STDLOGIC.TS3A5018PWR_TSSOP16(CHIPS)':
 'NC4': CDS_PINID='NC4';
NET_NAME
'FT4232_I2C_SCL'
 '@TIMECARD_LIB.TIMECARD(SCH_1):FT4232_I2C_SCL':
 C_SIGNAL='@timecard_lib.timecard(sch_1):ft4232_i2c_scl';
NODE_NAME     R471 2
 '@TIMECARD_LIB.TIMECARD(SCH_1):PAGE524_I169@PASSIVE.RESISTOR(CHIPS)':
 '2': CDS_PINID='\2\';
NODE_NAME     R478 1
 '@TIMECARD_LIB.TIMECARD(SCH_1):PAGE524_I190@PASSIVE.RESISTOR(CHIPS)':
 '1': CDS_PINID='\1\';
NODE_NAME     U37 6
 '@TIMECARD_LIB.TIMECARD(SCH_1):PAGE524_I448@STDLOGIC.TS3A5018PWR_TSSOP16(CHIPS)':
 'NO2': CDS_PINID='NO2';
NODE_NAME     U37 13
 '@TIMECARD_LIB.TIMECARD(SCH_1):PAGE524_I448@STDLOGIC.TS3A5018PWR_TSSOP16(CHIPS)':
 'NO4': CDS_PINID='NO4';
NET_NAME
'FT4232_I2C_SDA'
 '@TIMECARD_LIB.TIMECARD(SCH_1):FT4232_I2C_SDA':
 C_SIGNAL='@timecard_lib.timecard(sch_1):ft4232_i2c_sda';
NODE_NAME     R472 2
 '@TIMECARD_LIB.TIMECARD(SCH_1):PAGE524_I166@PASSIVE.RESISTOR(CHIPS)':
 '2': CDS_PINID='\2\';
NODE_NAME     R473 2
 '@TIMECARD_LIB.TIMECARD(SCH_1):PAGE524_I170@PASSIVE.RESISTOR(CHIPS)':
 '2': CDS_PINID='\2\';
NODE_NAME     R479 1
 '@TIMECARD_LIB.TIMECARD(SCH_1):PAGE524_I191@PASSIVE.RESISTOR(CHIPS)':
 '1': CDS_PINID='\1\';
NODE_NAME     U37 3
 '@TIMECARD_LIB.TIMECARD(SCH_1):PAGE524_I448@STDLOGIC.TS3A5018PWR_TSSOP16(CHIPS)':
 'NO1': CDS_PINID='NO1';
NODE_NAME     U37 10
 '@TIMECARD_LIB.TIMECARD(SCH_1):PAGE524_I448@STDLOGIC.TS3A5018PWR_TSSOP16(CHIPS)':
 'NO3': CDS_PINID='NO3';
NET_NAME
'FT4232_MUX1_SEL'
 '@TIMECARD_LIB.TIMECARD(SCH_1):FT4232_MUX1_SEL':
 C_SIGNAL='@timecard_lib.timecard(sch_1):ft4232_mux1_sel';
NODE_NAME     U18 21
 '@TIMECARD_LIB.TIMECARD(SCH_1):PAGE524_I64@INTERFACE.FT4232HL_REEL_QFP64(CHIPS)':
 'ADBUS4': CDS_PINID='ADBUS4';
NODE_NAME     R449 2
 '@TIMECARD_LIB.TIMECARD(SCH_1):PAGE524_I424@PASSIVE.RESISTOR(CHIPS)':
 '2': CDS_PINID='\2\';
NET_NAME
'FT4232_MUX2_SEL'
 '@TIMECARD_LIB.TIMECARD(SCH_1):FT4232_MUX2_SEL':
 C_SIGNAL='@timecard_lib.timecard(sch_1):ft4232_mux2_sel';
NODE_NAME     U18 22
 '@TIMECARD_LIB.TIMECARD(SCH_1):PAGE524_I64@INTERFACE.FT4232HL_REEL_QFP64(CHIPS)':
 'ADBUS5': CDS_PINID='ADBUS5';
NODE_NAME     R462 1
 '@TIMECARD_LIB.TIMECARD(SCH_1):PAGE524_I412@PASSIVE.RESISTOR(CHIPS)':
 '1': CDS_PINID='\1\';
NET_NAME
'FT4232_MUX3_SEL'
 '@TIMECARD_LIB.TIMECARD(SCH_1):FT4232_MUX3_SEL':
 C_SIGNAL='@timecard_lib.timecard(sch_1):ft4232_mux3_sel';
NODE_NAME     U18 23
 '@TIMECARD_LIB.TIMECARD(SCH_1):PAGE524_I64@INTERFACE.FT4232HL_REEL_QFP64(CHIPS)':
 'ADBUS6': CDS_PINID='ADBUS6';
NODE_NAME     R486 1
 '@TIMECARD_LIB.TIMECARD(SCH_1):PAGE524_I460@PASSIVE.RESISTOR(CHIPS)':
 '1': CDS_PINID='\1\';
NET_NAME
'FT4232_SPI_CLK'
 '@TIMECARD_LIB.TIMECARD(SCH_1):FT4232_SPI_CLK':
 C_SIGNAL='@timecard_lib.timecard(sch_1):ft4232_spi_clk';
NODE_NAME     U38 3
 '@TIMECARD_LIB.TIMECARD(SCH_1):PAGE524_I400@STDLOGIC.TS3A5018PWR_TSSOP16(CHIPS)':
 'NO1': CDS_PINID='NO1';
NODE_NAME     U30 3
 '@TIMECARD_LIB.TIMECARD(SCH_1):PAGE524_I425@STDLOGIC.TS3A5018PWR_TSSOP16(CHIPS)':
 'NO1': CDS_PINID='NO1';
NET_NAME
'FT4232_SPI_CS_N'
 '@TIMECARD_LIB.TIMECARD(SCH_1):FT4232_SPI_CS_N':
 C_SIGNAL='@timecard_lib.timecard(sch_1):ft4232_spi_cs_n';
NODE_NAME     U38 13
 '@TIMECARD_LIB.TIMECARD(SCH_1):PAGE524_I400@STDLOGIC.TS3A5018PWR_TSSOP16(CHIPS)':
 'NO4': CDS_PINID='NO4';
NODE_NAME     U30 13
 '@TIMECARD_LIB.TIMECARD(SCH_1):PAGE524_I425@STDLOGIC.TS3A5018PWR_TSSOP16(CHIPS)':
 'NO4': CDS_PINID='NO4';
NET_NAME
'FT4232_SPI_MISO'
 '@TIMECARD_LIB.TIMECARD(SCH_1):FT4232_SPI_MISO':
 C_SIGNAL='@timecard_lib.timecard(sch_1):ft4232_spi_miso';
NODE_NAME     U38 10
 '@TIMECARD_LIB.TIMECARD(SCH_1):PAGE524_I400@STDLOGIC.TS3A5018PWR_TSSOP16(CHIPS)':
 'NO3': CDS_PINID='NO3';
NODE_NAME     U30 10
 '@TIMECARD_LIB.TIMECARD(SCH_1):PAGE524_I425@STDLOGIC.TS3A5018PWR_TSSOP16(CHIPS)':
 'NO3': CDS_PINID='NO3';
NET_NAME
'FT4232_SPI_MOSI'
 '@TIMECARD_LIB.TIMECARD(SCH_1):FT4232_SPI_MOSI':
 C_SIGNAL='@timecard_lib.timecard(sch_1):ft4232_spi_mosi';
NODE_NAME     U38 6
 '@TIMECARD_LIB.TIMECARD(SCH_1):PAGE524_I400@STDLOGIC.TS3A5018PWR_TSSOP16(CHIPS)':
 'NO2': CDS_PINID='NO2';
NODE_NAME     U30 6
 '@TIMECARD_LIB.TIMECARD(SCH_1):PAGE524_I425@STDLOGIC.TS3A5018PWR_TSSOP16(CHIPS)':
 'NO2': CDS_PINID='NO2';
NET_NAME
'FT4232_TCK_SCLK'
 '@TIMECARD_LIB.TIMECARD(SCH_1):FT4232_TCK_SCLK':
 C_SIGNAL='@timecard_lib.timecard(sch_1):ft4232_tck_sclk';
NODE_NAME     R467 2
 '@TIMECARD_LIB.TIMECARD(SCH_1):PAGE524_I141@PASSIVE.RESISTOR(CHIPS)':
 '2': CDS_PINID='\2\';
NODE_NAME     U30 4
 '@TIMECARD_LIB.TIMECARD(SCH_1):PAGE524_I425@STDLOGIC.TS3A5018PWR_TSSOP16(CHIPS)':
 'COM1': CDS_PINID='COM1';
NET_NAME
'FT4232_TDI_MOSI'
 '@TIMECARD_LIB.TIMECARD(SCH_1):FT4232_TDI_MOSI':
 C_SIGNAL='@timecard_lib.timecard(sch_1):ft4232_tdi_mosi';
NODE_NAME     R468 2
 '@TIMECARD_LIB.TIMECARD(SCH_1):PAGE524_I140@PASSIVE.RESISTOR(CHIPS)':
 '2': CDS_PINID='\2\';
NODE_NAME     U30 7
 '@TIMECARD_LIB.TIMECARD(SCH_1):PAGE524_I425@STDLOGIC.TS3A5018PWR_TSSOP16(CHIPS)':
 'COM2': CDS_PINID='COM2';
NET_NAME
'FT4232_TDO_MISO'
 '@TIMECARD_LIB.TIMECARD(SCH_1):FT4232_TDO_MISO':
 C_SIGNAL='@timecard_lib.timecard(sch_1):ft4232_tdo_miso';
NODE_NAME     R469 2
 '@TIMECARD_LIB.TIMECARD(SCH_1):PAGE524_I142@PASSIVE.RESISTOR(CHIPS)':
 '2': CDS_PINID='\2\';
NODE_NAME     U30 9
 '@TIMECARD_LIB.TIMECARD(SCH_1):PAGE524_I425@STDLOGIC.TS3A5018PWR_TSSOP16(CHIPS)':
 'COM3': CDS_PINID='COM3';
NET_NAME
'FT4232_TMS_SPICS_N'
 '@TIMECARD_LIB.TIMECARD(SCH_1):FT4232_TMS_SPICS_N':
 C_SIGNAL='@timecard_lib.timecard(sch_1):ft4232_tms_spics_n';
NODE_NAME     R470 2
 '@TIMECARD_LIB.TIMECARD(SCH_1):PAGE524_I139@PASSIVE.RESISTOR(CHIPS)':
 '2': CDS_PINID='\2\';
NODE_NAME     U30 12
 '@TIMECARD_LIB.TIMECARD(SCH_1):PAGE524_I425@STDLOGIC.TS3A5018PWR_TSSOP16(CHIPS)':
 'COM4': CDS_PINID='COM4';
NET_NAME
'FT4232_VREGOUT'
 '@TIMECARD_LIB.TIMECARD(SCH_1):FT4232_VREGOUT':
 C_SIGNAL='@timecard_lib.timecard(sch_1):ft4232_vregout';
NODE_NAME     U18 64
 '@TIMECARD_LIB.TIMECARD(SCH_1):PAGE524_I64@INTERFACE.FT4232HL_REEL_QFP64(CHIPS)':
 'VCORE_1': CDS_PINID='VCORE_1';
NODE_NAME     U18 37
 '@TIMECARD_LIB.TIMECARD(SCH_1):PAGE524_I64@INTERFACE.FT4232HL_REEL_QFP64(CHIPS)':
 'VCORE_2': CDS_PINID='VCORE_2';
NODE_NAME     U18 12
 '@TIMECARD_LIB.TIMECARD(SCH_1):PAGE524_I64@INTERFACE.FT4232HL_REEL_QFP64(CHIPS)':
 'VCORE_3': CDS_PINID='VCORE_3';
NODE_NAME     U18 49
 '@TIMECARD_LIB.TIMECARD(SCH_1):PAGE524_I64@INTERFACE.FT4232HL_REEL_QFP64(CHIPS)':
 'VREGOUT': CDS_PINID='VREGOUT';
NODE_NAME     C90 1
 '@TIMECARD_LIB.TIMECARD(SCH_1):PAGE524_I123@PASSIVE.CAPACITOR(CHIPS)':
 '1': CDS_PINID='\1\';
NODE_NAME     C96 1
 '@TIMECARD_LIB.TIMECARD(SCH_1):PAGE524_I376@PASSIVE.CAPACITOR(CHIPS)':
 '1': CDS_PINID='\1\';
NET_NAME
'FTDI_EE_CLK'
 '@TIMECARD_LIB.TIMECARD(SCH_1):FTDI_EE_CLK':
 C_SIGNAL='@timecard_lib.timecard(sch_1):ftdi_ee_clk';
NODE_NAME     U18 62
 '@TIMECARD_LIB.TIMECARD(SCH_1):PAGE524_I64@INTERFACE.FT4232HL_REEL_QFP64(CHIPS)':
 'EECLK': CDS_PINID='EECLK';
NODE_NAME     U31 2
 '@TIMECARD_LIB.TIMECARD(SCH_1):PAGE524_I200@MEMORY.CAT93C46VI_GT3_SOIC8(CHIPS)':
 'SK': CDS_PINID='SK';
NODE_NAME     R447 2
 '@TIMECARD_LIB.TIMECARD(SCH_1):PAGE524_I206@PASSIVE.RESISTOR(CHIPS)':
 '2': CDS_PINID='\2\';
NET_NAME
'FTDI_EE_CS'
 '@TIMECARD_LIB.TIMECARD(SCH_1):FTDI_EE_CS':
 C_SIGNAL='@timecard_lib.timecard(sch_1):ftdi_ee_cs';
NODE_NAME     U18 63
 '@TIMECARD_LIB.TIMECARD(SCH_1):PAGE524_I64@INTERFACE.FT4232HL_REEL_QFP64(CHIPS)':
 'EECS': CDS_PINID='EECS';
NODE_NAME     U31 1
 '@TIMECARD_LIB.TIMECARD(SCH_1):PAGE524_I200@MEMORY.CAT93C46VI_GT3_SOIC8(CHIPS)':
 'CS': CDS_PINID='CS';
NODE_NAME     R446 2
 '@TIMECARD_LIB.TIMECARD(SCH_1):PAGE524_I207@PASSIVE.RESISTOR(CHIPS)':
 '2': CDS_PINID='\2\';
NET_NAME
'FTDI_EE_DAT'
 '@TIMECARD_LIB.TIMECARD(SCH_1):FTDI_EE_DAT':
 C_SIGNAL='@timecard_lib.timecard(sch_1):ftdi_ee_dat';
NODE_NAME     U18 61
 '@TIMECARD_LIB.TIMECARD(SCH_1):PAGE524_I64@INTERFACE.FT4232HL_REEL_QFP64(CHIPS)':
 'EEDATA': CDS_PINID='EEDATA';
NODE_NAME     U31 3
 '@TIMECARD_LIB.TIMECARD(SCH_1):PAGE524_I200@MEMORY.CAT93C46VI_GT3_SOIC8(CHIPS)':
 'DI': CDS_PINID='DI';
NODE_NAME     R454 1
 '@TIMECARD_LIB.TIMECARD(SCH_1):PAGE524_I310@PASSIVE.RESISTOR(CHIPS)':
 '1': CDS_PINID='\1\';
NET_NAME
'FTDI_EE_DO'
 '@TIMECARD_LIB.TIMECARD(SCH_1):FTDI_EE_DO':
 C_SIGNAL='@timecard_lib.timecard(sch_1):ftdi_ee_do';
NODE_NAME     U31 4
 '@TIMECARD_LIB.TIMECARD(SCH_1):PAGE524_I200@MEMORY.CAT93C46VI_GT3_SOIC8(CHIPS)':
 'DO': CDS_PINID='DO';
NODE_NAME     R444 2
 '@TIMECARD_LIB.TIMECARD(SCH_1):PAGE524_I208@PASSIVE.RESISTOR(CHIPS)':
 '2': CDS_PINID='\2\';
NODE_NAME     R454 2
 '@TIMECARD_LIB.TIMECARD(SCH_1):PAGE524_I310@PASSIVE.RESISTOR(CHIPS)':
 '2': CDS_PINID='\2\';
NET_NAME
'FT_USB_DETECT'
 '@TIMECARD_LIB.TIMECARD(SCH_1):FT_USB_DETECT':
 C_SIGNAL='@timecard_lib.timecard(sch_1):ft_usb_detect';
NODE_NAME     R130 1
 '@TIMECARD_LIB.TIMECARD(SCH_1):PAGE524_I23@PASSIVE.RESISTOR(CHIPS)':
 '1': CDS_PINID='\1\';
NODE_NAME     R18 2
 '@TIMECARD_LIB.TIMECARD(SCH_1):PAGE524_I27@PASSIVE.RESISTOR(CHIPS)':
 '2': CDS_PINID='\2\';
NODE_NAME     R460 1
 '@TIMECARD_LIB.TIMECARD(SCH_1):PAGE524_I121@PASSIVE.RESISTOR(CHIPS)':
 '1': CDS_PINID='\1\';
NODE_NAME     R456 2
 '@TIMECARD_LIB.TIMECARD(SCH_1):PAGE524_I368@PASSIVE.RESISTOR(CHIPS)':
 '2': CDS_PINID='\2\';
NODE_NAME     Q1 1
 '@TIMECARD_LIB.TIMECARD(SCH_1):PAGE524_I445@DISCRETE.POWERMOS_3P_NCH_V1(CHIPS)':
 'G': CDS_PINID='G';
NODE_NAME     R443 1
 '@TIMECARD_LIB.TIMECARD(SCH_1):PAGE524_I446@PASSIVE.RESISTOR(CHIPS)':
 '1': CDS_PINID='\1\';
NODE_NAME     TP11 1
 '@TIMECARD_LIB.TIMECARD(SCH_1):PAGE16_I1626@CLS.TP_PIONT(CHIPS)':
 '1': CDS_PINID='\1\';
NET_NAME
'FT_USB_DM'
 '@TIMECARD_LIB.TIMECARD(SCH_1):FT_USB_DM':
 C_SIGNAL='@timecard_lib.timecard(sch_1):ft_usb_dm';
NODE_NAME     U17 4
 '@TIMECARD_LIB.TIMECARD(SCH_1):PAGE524_I3@OTHER.CL1001485A(CHIPS)':
 '4': CDS_PINID='\4\';
NODE_NAME     R128 1
 '@TIMECARD_LIB.TIMECARD(SCH_1):PAGE524_I28@PASSIVE.RESISTOR(CHIPS)':
 '1': CDS_PINID='\1\';
NODE_NAME     J13 A7
 '@TIMECARD_LIB.TIMECARD(SCH_1):PAGE524_I495@CONNECTOR.CONN_USB_14P_GH4_F_RA_TH(CHIPS)':
 'D1_N': CDS_PINID='D1_N';
NODE_NAME     J13 B7
 '@TIMECARD_LIB.TIMECARD(SCH_1):PAGE524_I495@CONNECTOR.CONN_USB_14P_GH4_F_RA_TH(CHIPS)':
 'D2_N': CDS_PINID='D2_N';
NET_NAME
'FT_USB_DP'
 '@TIMECARD_LIB.TIMECARD(SCH_1):FT_USB_DP':
 C_SIGNAL='@timecard_lib.timecard(sch_1):ft_usb_dp';
NODE_NAME     U17 6
 '@TIMECARD_LIB.TIMECARD(SCH_1):PAGE524_I3@OTHER.CL1001485A(CHIPS)':
 '6': CDS_PINID='\6\';
NODE_NAME     R129 1
 '@TIMECARD_LIB.TIMECARD(SCH_1):PAGE524_I26@PASSIVE.RESISTOR(CHIPS)':
 '1': CDS_PINID='\1\';
NODE_NAME     J13 A6
 '@TIMECARD_LIB.TIMECARD(SCH_1):PAGE524_I495@CONNECTOR.CONN_USB_14P_GH4_F_RA_TH(CHIPS)':
 'D1_P': CDS_PINID='D1_P';
NODE_NAME     J13 B6
 '@TIMECARD_LIB.TIMECARD(SCH_1):PAGE524_I495@CONNECTOR.CONN_USB_14P_GH4_F_RA_TH(CHIPS)':
 'D2_P': CDS_PINID='D2_P';
NET_NAME
'GPSTP1_OUT'
 '@TIMECARD_LIB.TIMECARD(SCH_1):GPSTP1_OUT':
 C_SIGNAL='@timecard_lib.timecard(sch_1):gpstp1_out';
NODE_NAME     R117 1
 '@TIMECARD_LIB.TIMECARD(SCH_1):PAGE11_I20@PASSIVE.RESISTOR(CHIPS)':
 '1': CDS_PINID='\1\';
NODE_NAME     P2 6
 '@TIMECARD_LIB.TIMECARD(SCH_1):PAGE11_I36@CONNECTOR.CONN_HDR_2X4_F_S_SMT(CHIPS)':
 '6': CDS_PINID='\6\';
NET_NAME
'GPSTP2_OUT'
 '@TIMECARD_LIB.TIMECARD(SCH_1):GPSTP2_OUT':
 C_SIGNAL='@timecard_lib.timecard(sch_1):gpstp2_out';
NODE_NAME     R111 2
 '@TIMECARD_LIB.TIMECARD(SCH_1):PAGE11_I5@PASSIVE.RESISTOR(CHIPS)':
 '2': CDS_PINID='\2\';
NODE_NAME     P2 7
 '@TIMECARD_LIB.TIMECARD(SCH_1):PAGE11_I36@CONNECTOR.CONN_HDR_2X4_F_S_SMT(CHIPS)':
 '7': CDS_PINID='\7\';
NET_NAME
'GPS_RST_N'
 '@TIMECARD_LIB.TIMECARD(SCH_1):GPS_RST_N':
 C_SIGNAL='@timecard_lib.timecard(sch_1):gps_rst_n';
NODE_NAME     R114 1
 '@TIMECARD_LIB.TIMECARD(SCH_1):PAGE11_I18@PASSIVE.RESISTOR(CHIPS)':
 '1': CDS_PINID='\1\';
NODE_NAME     R115 2
 '@TIMECARD_LIB.TIMECARD(SCH_1):PAGE11_I21@PASSIVE.RESISTOR(CHIPS)':
 '2': CDS_PINID='\2\';
NODE_NAME     R116 1
 '@TIMECARD_LIB.TIMECARD(SCH_1):PAGE11_I25@PASSIVE.RESISTOR(CHIPS)':
 '1': CDS_PINID='\1\';
NODE_NAME     P2 4
 '@TIMECARD_LIB.TIMECARD(SCH_1):PAGE11_I36@CONNECTOR.CONN_HDR_2X4_F_S_SMT(CHIPS)':
 '4': CDS_PINID='\4\';
NODE_NAME     TP15 1
 '@TIMECARD_LIB.TIMECARD(SCH_1):PAGE16_I1630@CLS.TP_PIONT(CHIPS)':
 '1': CDS_PINID='\1\';
NET_NAME
'GPS_SMA_LED_BLUE_N'
 '@TIMECARD_LIB.TIMECARD(SCH_1):GPS_SMA_LED_BLUE_N':
 C_SIGNAL='@timecard_lib.timecard(sch_1):gps_sma_led_blue_n';
NODE_NAME     R397 1
 '@TIMECARD_LIB.TIMECARD(SCH_1):PAGE14_I156@PASSIVE.RESISTOR(CHIPS)':
 '1': CDS_PINID='\1\';
NODE_NAME     U33 24
 '@TIMECARD_LIB.TIMECARD(SCH_1):PAGE14_I219@INTERFACE.IS32FL3207_QWLA3_TR_QFN29(CHIPS)':
 'OUT15': CDS_PINID='OUT15';
NET_NAME
'GPS_SMA_LED_GREEN_N'
 '@TIMECARD_LIB.TIMECARD(SCH_1):GPS_SMA_LED_GREEN_N':
 C_SIGNAL='@timecard_lib.timecard(sch_1):gps_sma_led_green_n';
NODE_NAME     R398 1
 '@TIMECARD_LIB.TIMECARD(SCH_1):PAGE14_I155@PASSIVE.RESISTOR(CHIPS)':
 '1': CDS_PINID='\1\';
NODE_NAME     U33 22
 '@TIMECARD_LIB.TIMECARD(SCH_1):PAGE14_I219@INTERFACE.IS32FL3207_QWLA3_TR_QFN29(CHIPS)':
 'OUT13': CDS_PINID='OUT13';
NET_NAME
'GPS_SMA_LED_RED_N'
 '@TIMECARD_LIB.TIMECARD(SCH_1):GPS_SMA_LED_RED_N':
 C_SIGNAL='@timecard_lib.timecard(sch_1):gps_sma_led_red_n';
NODE_NAME     R399 1
 '@TIMECARD_LIB.TIMECARD(SCH_1):PAGE14_I157@PASSIVE.RESISTOR(CHIPS)':
 '1': CDS_PINID='\1\';
NODE_NAME     U33 23
 '@TIMECARD_LIB.TIMECARD(SCH_1):PAGE14_I219@INTERFACE.IS32FL3207_QWLA3_TR_QFN29(CHIPS)':
 'OUT14': CDS_PINID='OUT14';
NET_NAME
'GPS_UART_RXD'
 '@TIMECARD_LIB.TIMECARD(SCH_1):GPS_UART_RXD':
 C_SIGNAL='@timecard_lib.timecard(sch_1):gps_uart_rxd';
NODE_NAME     R113 2
 '@TIMECARD_LIB.TIMECARD(SCH_1):PAGE11_I7@PASSIVE.RESISTOR(CHIPS)':
 '2': CDS_PINID='\2\';
NODE_NAME     R110 2
 '@TIMECARD_LIB.TIMECARD(SCH_1):PAGE11_I29@PASSIVE.RESISTOR(CHIPS)':
 '2': CDS_PINID='\2\';
NODE_NAME     P2 5
 '@TIMECARD_LIB.TIMECARD(SCH_1):PAGE11_I36@CONNECTOR.CONN_HDR_2X4_F_S_SMT(CHIPS)':
 '5': CDS_PINID='\5\';
NODE_NAME     R268 2
 '@TIMECARD_LIB.TIMECARD(SCH_1):PAGE11_I38@PASSIVE.RESISTOR(CHIPS)':
 '2': CDS_PINID='\2\';
NET_NAME
'GPS_UART_TXD'
 '@TIMECARD_LIB.TIMECARD(SCH_1):GPS_UART_TXD':
 C_SIGNAL='@timecard_lib.timecard(sch_1):gps_uart_txd';
NODE_NAME     R112 2
 '@TIMECARD_LIB.TIMECARD(SCH_1):PAGE11_I8@PASSIVE.RESISTOR(CHIPS)':
 '2': CDS_PINID='\2\';
NODE_NAME     R109 2
 '@TIMECARD_LIB.TIMECARD(SCH_1):PAGE11_I11@PASSIVE.RESISTOR(CHIPS)':
 '2': CDS_PINID='\2\';
NODE_NAME     P2 3
 '@TIMECARD_LIB.TIMECARD(SCH_1):PAGE11_I36@CONNECTOR.CONN_HDR_2X4_F_S_SMT(CHIPS)':
 '3': CDS_PINID='\3\';
NET_NAME
'ICP10100_I2C_SCL'
 '@TIMECARD_LIB.TIMECARD(SCH_1):ICP10100_I2C_SCL':
 C_SIGNAL='@timecard_lib.timecard(sch_1):icp10100_i2c_scl';
NODE_NAME     U4 10
 '@TIMECARD_LIB.TIMECARD(SCH_1):PAGE5_I33@INTERFACE.PCA9546APW_TSSOP16(CHIPS)':
 'SC2': CDS_PINID='SC2';
NODE_NAME     U32 7
 '@TIMECARD_LIB.TIMECARD(SCH_1):PAGE8_I51@STDLOGIC.PCA9508DP_TSSOP8(CHIPS)':
 'SCLB': CDS_PINID='SCLB';
NODE_NAME     R315 1
 '@TIMECARD_LIB.TIMECARD(SCH_1):PAGE8_I63@PASSIVE.RESISTOR(CHIPS)':
 '1': CDS_PINID='\1\';
NODE_NAME     R282 2
 '@TIMECARD_LIB.TIMECARD(SCH_1):PAGE8_I69@PASSIVE.RESISTOR(CHIPS)':
 '2': CDS_PINID='\2\';
NET_NAME
'ICP10100_I2C_SDA'
 '@TIMECARD_LIB.TIMECARD(SCH_1):ICP10100_I2C_SDA':
 C_SIGNAL='@timecard_lib.timecard(sch_1):icp10100_i2c_sda';
NODE_NAME     U4 9
 '@TIMECARD_LIB.TIMECARD(SCH_1):PAGE5_I33@INTERFACE.PCA9546APW_TSSOP16(CHIPS)':
 'SD2': CDS_PINID='SD2';
NODE_NAME     U32 6
 '@TIMECARD_LIB.TIMECARD(SCH_1):PAGE8_I51@STDLOGIC.PCA9508DP_TSSOP8(CHIPS)':
 'SDAB': CDS_PINID='SDAB';
NODE_NAME     R316 1
 '@TIMECARD_LIB.TIMECARD(SCH_1):PAGE8_I64@PASSIVE.RESISTOR(CHIPS)':
 '1': CDS_PINID='\1\';
NODE_NAME     R281 2
 '@TIMECARD_LIB.TIMECARD(SCH_1):PAGE8_I70@PASSIVE.RESISTOR(CHIPS)':
 '2': CDS_PINID='\2\';
NET_NAME
'IO_L20N_16'
 '@TIMECARD_LIB.TIMECARD(SCH_1):IO_L20N_16':
 C_SIGNAL='@timecard_lib.timecard(sch_1):io_l20n_16';
NODE_NAME     U24 B22
 '@TIMECARD_LIB.TIMECARD(SCH_1):PAGE162_I228@PLD.XC7A200T_2FBG484C_FBG484(CHIPS)':
 'IO_L20N_T3_16': CDS_PINID='IO_L20N_T3_16';
NODE_NAME     TP180 1
 '@TIMECARD_LIB.TIMECARD(SCH_1):PAGE16_I1511@CLS.TP_PIONT(CHIPS)':
 '1': CDS_PINID='\1\';
NET_NAME
'IO_L20N_34'
 '@TIMECARD_LIB.TIMECARD(SCH_1):IO_L20N_34':
 C_SIGNAL='@timecard_lib.timecard(sch_1):io_l20n_34';
NODE_NAME     U24 AB6
 '@TIMECARD_LIB.TIMECARD(SCH_1):PAGE163_I1@PLD.XC7A200T_2FBG484C_FBG484(CHIPS)':
 'IO_L20N_T3_34': CDS_PINID='IO_L20N_T3_34';
NODE_NAME     TP133 1
 '@TIMECARD_LIB.TIMECARD(SCH_1):PAGE16_I1015@CLS.TP_PIONT(CHIPS)':
 '1': CDS_PINID='\1\';
NET_NAME
'IO_L20N_35'
 '@TIMECARD_LIB.TIMECARD(SCH_1):IO_L20N_35':
 C_SIGNAL='@timecard_lib.timecard(sch_1):io_l20n_35';
NODE_NAME     U24 P1
 '@TIMECARD_LIB.TIMECARD(SCH_1):PAGE163_I1@PLD.XC7A200T_2FBG484C_FBG484(CHIPS)':
 'IO_L20N_T3_35': CDS_PINID='IO_L20N_T3_35';
NODE_NAME     TP200 1
 '@TIMECARD_LIB.TIMECARD(SCH_1):PAGE16_I1528@CLS.TP_PIONT(CHIPS)':
 '1': CDS_PINID='\1\';
NET_NAME
'IO_L20P_16'
 '@TIMECARD_LIB.TIMECARD(SCH_1):IO_L20P_16':
 C_SIGNAL='@timecard_lib.timecard(sch_1):io_l20p_16';
NODE_NAME     U24 C22
 '@TIMECARD_LIB.TIMECARD(SCH_1):PAGE162_I228@PLD.XC7A200T_2FBG484C_FBG484(CHIPS)':
 'IO_L20P_T3_16': CDS_PINID='IO_L20P_T3_16';
NODE_NAME     TP78 1
 '@TIMECARD_LIB.TIMECARD(SCH_1):PAGE16_I1516@CLS.TP_PIONT(CHIPS)':
 '1': CDS_PINID='\1\';
NET_NAME
'IO_L20P_34'
 '@TIMECARD_LIB.TIMECARD(SCH_1):IO_L20P_34':
 C_SIGNAL='@timecard_lib.timecard(sch_1):io_l20p_34';
NODE_NAME     U24 AB7
 '@TIMECARD_LIB.TIMECARD(SCH_1):PAGE163_I1@PLD.XC7A200T_2FBG484C_FBG484(CHIPS)':
 'IO_L20P_T3_34': CDS_PINID='IO_L20P_T3_34';
NODE_NAME     TP132 1
 '@TIMECARD_LIB.TIMECARD(SCH_1):PAGE16_I1014@CLS.TP_PIONT(CHIPS)':
 '1': CDS_PINID='\1\';
NET_NAME
'IO_L20P_35'
 '@TIMECARD_LIB.TIMECARD(SCH_1):IO_L20P_35':
 C_SIGNAL='@timecard_lib.timecard(sch_1):io_l20p_35';
NODE_NAME     U24 R1
 '@TIMECARD_LIB.TIMECARD(SCH_1):PAGE163_I1@PLD.XC7A200T_2FBG484C_FBG484(CHIPS)':
 'IO_L20P_T3_35': CDS_PINID='IO_L20P_T3_35';
NODE_NAME     TP199 1
 '@TIMECARD_LIB.TIMECARD(SCH_1):PAGE16_I1527@CLS.TP_PIONT(CHIPS)':
 '1': CDS_PINID='\1\';
NET_NAME
'IO_L21N_16'
 '@TIMECARD_LIB.TIMECARD(SCH_1):IO_L21N_16':
 C_SIGNAL='@timecard_lib.timecard(sch_1):io_l21n_16';
NODE_NAME     U24 A21
 '@TIMECARD_LIB.TIMECARD(SCH_1):PAGE162_I228@PLD.XC7A200T_2FBG484C_FBG484(CHIPS)':
 'IO_L21N_T3_DQS_16': CDS_PINID='IO_L21N_T3_DQS_16';
NODE_NAME     TP182 1
 '@TIMECARD_LIB.TIMECARD(SCH_1):PAGE16_I1513@CLS.TP_PIONT(CHIPS)':
 '1': CDS_PINID='\1\';
NET_NAME
'IO_L21N_34'
 '@TIMECARD_LIB.TIMECARD(SCH_1):IO_L21N_34':
 C_SIGNAL='@timecard_lib.timecard(sch_1):io_l21n_34';
NODE_NAME     U24 V8
 '@TIMECARD_LIB.TIMECARD(SCH_1):PAGE163_I1@PLD.XC7A200T_2FBG484C_FBG484(CHIPS)':
 'IO_L21N_T3_DQS_34': CDS_PINID='IO_L21N_T3_DQS_34';
NODE_NAME     TP135 1
 '@TIMECARD_LIB.TIMECARD(SCH_1):PAGE16_I1017@CLS.TP_PIONT(CHIPS)':
 '1': CDS_PINID='\1\';
NET_NAME
'IO_L21N_35'
 '@TIMECARD_LIB.TIMECARD(SCH_1):IO_L21N_35':
 C_SIGNAL='@timecard_lib.timecard(sch_1):io_l21n_35';
NODE_NAME     U24 P4
 '@TIMECARD_LIB.TIMECARD(SCH_1):PAGE163_I1@PLD.XC7A200T_2FBG484C_FBG484(CHIPS)':
 'IO_L21N_T3_DQS_35': CDS_PINID='IO_L21N_T3_DQS_35';
NODE_NAME     TP194 1
 '@TIMECARD_LIB.TIMECARD(SCH_1):PAGE16_I1488@CLS.TP_PIONT(CHIPS)':
 '1': CDS_PINID='\1\';
NET_NAME
'IO_L21P_16'
 '@TIMECARD_LIB.TIMECARD(SCH_1):IO_L21P_16':
 C_SIGNAL='@timecard_lib.timecard(sch_1):io_l21p_16';
NODE_NAME     U24 B21
 '@TIMECARD_LIB.TIMECARD(SCH_1):PAGE162_I228@PLD.XC7A200T_2FBG484C_FBG484(CHIPS)':
 'IO_L21P_T3_DQS_16': CDS_PINID='IO_L21P_T3_DQS_16';
NODE_NAME     TP181 1
 '@TIMECARD_LIB.TIMECARD(SCH_1):PAGE16_I1512@CLS.TP_PIONT(CHIPS)':
 '1': CDS_PINID='\1\';
NET_NAME
'IO_L21P_34'
 '@TIMECARD_LIB.TIMECARD(SCH_1):IO_L21P_34':
 C_SIGNAL='@timecard_lib.timecard(sch_1):io_l21p_34';
NODE_NAME     U24 V9
 '@TIMECARD_LIB.TIMECARD(SCH_1):PAGE163_I1@PLD.XC7A200T_2FBG484C_FBG484(CHIPS)':
 'IO_L21P_T3_DQS_34': CDS_PINID='IO_L21P_T3_DQS_34';
NODE_NAME     TP134 1
 '@TIMECARD_LIB.TIMECARD(SCH_1):PAGE16_I1016@CLS.TP_PIONT(CHIPS)':
 '1': CDS_PINID='\1\';
NET_NAME
'IO_L21P_35'
 '@TIMECARD_LIB.TIMECARD(SCH_1):IO_L21P_35':
 C_SIGNAL='@timecard_lib.timecard(sch_1):io_l21p_35';
NODE_NAME     U24 P5
 '@TIMECARD_LIB.TIMECARD(SCH_1):PAGE163_I1@PLD.XC7A200T_2FBG484C_FBG484(CHIPS)':
 'IO_L21P_T3_DQS_35': CDS_PINID='IO_L21P_T3_DQS_35';
NODE_NAME     TP193 1
 '@TIMECARD_LIB.TIMECARD(SCH_1):PAGE16_I1487@CLS.TP_PIONT(CHIPS)':
 '1': CDS_PINID='\1\';
NET_NAME
'IO_L22N_16'
 '@TIMECARD_LIB.TIMECARD(SCH_1):IO_L22N_16':
 C_SIGNAL='@timecard_lib.timecard(sch_1):io_l22n_16';
NODE_NAME     U24 D22
 '@TIMECARD_LIB.TIMECARD(SCH_1):PAGE162_I228@PLD.XC7A200T_2FBG484C_FBG484(CHIPS)':
 'IO_L22N_T3_16': CDS_PINID='IO_L22N_T3_16';
NODE_NAME     TP184 1
 '@TIMECARD_LIB.TIMECARD(SCH_1):PAGE16_I1506@CLS.TP_PIONT(CHIPS)':
 '1': CDS_PINID='\1\';
NET_NAME
'IO_L22N_34'
 '@TIMECARD_LIB.TIMECARD(SCH_1):IO_L22N_34':
 C_SIGNAL='@timecard_lib.timecard(sch_1):io_l22n_34';
NODE_NAME     U24 AB8
 '@TIMECARD_LIB.TIMECARD(SCH_1):PAGE163_I1@PLD.XC7A200T_2FBG484C_FBG484(CHIPS)':
 'IO_L22N_T3_34': CDS_PINID='IO_L22N_T3_34';
NODE_NAME     TP137 1
 '@TIMECARD_LIB.TIMECARD(SCH_1):PAGE16_I1019@CLS.TP_PIONT(CHIPS)':
 '1': CDS_PINID='\1\';
NET_NAME
'IO_L22N_35'
 '@TIMECARD_LIB.TIMECARD(SCH_1):IO_L22N_35':
 C_SIGNAL='@timecard_lib.timecard(sch_1):io_l22n_35';
NODE_NAME     U24 N2
 '@TIMECARD_LIB.TIMECARD(SCH_1):PAGE163_I1@PLD.XC7A200T_2FBG484C_FBG484(CHIPS)':
 'IO_L22N_T3_35': CDS_PINID='IO_L22N_T3_35';
NODE_NAME     TP202 1
 '@TIMECARD_LIB.TIMECARD(SCH_1):PAGE16_I1530@CLS.TP_PIONT(CHIPS)':
 '1': CDS_PINID='\1\';
NET_NAME
'IO_L22P_16'
 '@TIMECARD_LIB.TIMECARD(SCH_1):IO_L22P_16':
 C_SIGNAL='@timecard_lib.timecard(sch_1):io_l22p_16';
NODE_NAME     U24 E22
 '@TIMECARD_LIB.TIMECARD(SCH_1):PAGE162_I228@PLD.XC7A200T_2FBG484C_FBG484(CHIPS)':
 'IO_L22P_T3_16': CDS_PINID='IO_L22P_T3_16';
NODE_NAME     TP183 1
 '@TIMECARD_LIB.TIMECARD(SCH_1):PAGE16_I1505@CLS.TP_PIONT(CHIPS)':
 '1': CDS_PINID='\1\';
NET_NAME
'IO_L22P_34'
 '@TIMECARD_LIB.TIMECARD(SCH_1):IO_L22P_34':
 C_SIGNAL='@timecard_lib.timecard(sch_1):io_l22p_34';
NODE_NAME     U24 AA8
 '@TIMECARD_LIB.TIMECARD(SCH_1):PAGE163_I1@PLD.XC7A200T_2FBG484C_FBG484(CHIPS)':
 'IO_L22P_T3_34': CDS_PINID='IO_L22P_T3_34';
NODE_NAME     TP136 1
 '@TIMECARD_LIB.TIMECARD(SCH_1):PAGE16_I1018@CLS.TP_PIONT(CHIPS)':
 '1': CDS_PINID='\1\';
NET_NAME
'IO_L22P_35'
 '@TIMECARD_LIB.TIMECARD(SCH_1):IO_L22P_35':
 C_SIGNAL='@timecard_lib.timecard(sch_1):io_l22p_35';
NODE_NAME     U24 P2
 '@TIMECARD_LIB.TIMECARD(SCH_1):PAGE163_I1@PLD.XC7A200T_2FBG484C_FBG484(CHIPS)':
 'IO_L22P_T3_35': CDS_PINID='IO_L22P_T3_35';
NODE_NAME     TP201 1
 '@TIMECARD_LIB.TIMECARD(SCH_1):PAGE16_I1529@CLS.TP_PIONT(CHIPS)':
 '1': CDS_PINID='\1\';
NET_NAME
'IO_L23N_16'
 '@TIMECARD_LIB.TIMECARD(SCH_1):IO_L23N_16':
 C_SIGNAL='@timecard_lib.timecard(sch_1):io_l23n_16';
NODE_NAME     U24 D21
 '@TIMECARD_LIB.TIMECARD(SCH_1):PAGE162_I228@PLD.XC7A200T_2FBG484C_FBG484(CHIPS)':
 'IO_L23N_T3_16': CDS_PINID='IO_L23N_T3_16';
NODE_NAME     TP186 1
 '@TIMECARD_LIB.TIMECARD(SCH_1):PAGE16_I1508@CLS.TP_PIONT(CHIPS)':
 '1': CDS_PINID='\1\';
NET_NAME
'IO_L23N_34'
 '@TIMECARD_LIB.TIMECARD(SCH_1):IO_L23N_34':
 C_SIGNAL='@timecard_lib.timecard(sch_1):io_l23n_34';
NODE_NAME     U24 Y7
 '@TIMECARD_LIB.TIMECARD(SCH_1):PAGE163_I1@PLD.XC7A200T_2FBG484C_FBG484(CHIPS)':
 'IO_L23N_T3_34': CDS_PINID='IO_L23N_T3_34';
NODE_NAME     TP139 1
 '@TIMECARD_LIB.TIMECARD(SCH_1):PAGE16_I1021@CLS.TP_PIONT(CHIPS)':
 '1': CDS_PINID='\1\';
NET_NAME
'IO_L23N_35'
 '@TIMECARD_LIB.TIMECARD(SCH_1):IO_L23N_35':
 C_SIGNAL='@timecard_lib.timecard(sch_1):io_l23n_35';
NODE_NAME     U24 M5
 '@TIMECARD_LIB.TIMECARD(SCH_1):PAGE163_I1@PLD.XC7A200T_2FBG484C_FBG484(CHIPS)':
 'IO_L23N_T3_35': CDS_PINID='IO_L23N_T3_35';
NODE_NAME     TP196 1
 '@TIMECARD_LIB.TIMECARD(SCH_1):PAGE16_I1490@CLS.TP_PIONT(CHIPS)':
 '1': CDS_PINID='\1\';
NET_NAME
'IO_L23P_16'
 '@TIMECARD_LIB.TIMECARD(SCH_1):IO_L23P_16':
 C_SIGNAL='@timecard_lib.timecard(sch_1):io_l23p_16';
NODE_NAME     U24 E21
 '@TIMECARD_LIB.TIMECARD(SCH_1):PAGE162_I228@PLD.XC7A200T_2FBG484C_FBG484(CHIPS)':
 'IO_L23P_T3_16': CDS_PINID='IO_L23P_T3_16';
NODE_NAME     TP185 1
 '@TIMECARD_LIB.TIMECARD(SCH_1):PAGE16_I1507@CLS.TP_PIONT(CHIPS)':
 '1': CDS_PINID='\1\';
NET_NAME
'IO_L23P_34'
 '@TIMECARD_LIB.TIMECARD(SCH_1):IO_L23P_34':
 C_SIGNAL='@timecard_lib.timecard(sch_1):io_l23p_34';
NODE_NAME     U24 Y8
 '@TIMECARD_LIB.TIMECARD(SCH_1):PAGE163_I1@PLD.XC7A200T_2FBG484C_FBG484(CHIPS)':
 'IO_L23P_T3_34': CDS_PINID='IO_L23P_T3_34';
NODE_NAME     TP138 1
 '@TIMECARD_LIB.TIMECARD(SCH_1):PAGE16_I1020@CLS.TP_PIONT(CHIPS)':
 '1': CDS_PINID='\1\';
NET_NAME
'IO_L23P_35'
 '@TIMECARD_LIB.TIMECARD(SCH_1):IO_L23P_35':
 C_SIGNAL='@timecard_lib.timecard(sch_1):io_l23p_35';
NODE_NAME     U24 M6
 '@TIMECARD_LIB.TIMECARD(SCH_1):PAGE163_I1@PLD.XC7A200T_2FBG484C_FBG484(CHIPS)':
 'IO_L23P_T3_35': CDS_PINID='IO_L23P_T3_35';
NODE_NAME     TP195 1
 '@TIMECARD_LIB.TIMECARD(SCH_1):PAGE16_I1489@CLS.TP_PIONT(CHIPS)':
 '1': CDS_PINID='\1\';
NET_NAME
'IO_L24N_16'
 '@TIMECARD_LIB.TIMECARD(SCH_1):IO_L24N_16':
 C_SIGNAL='@timecard_lib.timecard(sch_1):io_l24n_16';
NODE_NAME     U24 G22
 '@TIMECARD_LIB.TIMECARD(SCH_1):PAGE162_I228@PLD.XC7A200T_2FBG484C_FBG484(CHIPS)':
 'IO_L24N_T3_16': CDS_PINID='IO_L24N_T3_16';
NODE_NAME     TP188 1
 '@TIMECARD_LIB.TIMECARD(SCH_1):PAGE16_I1510@CLS.TP_PIONT(CHIPS)':
 '1': CDS_PINID='\1\';
NET_NAME
'IO_L24N_34'
 '@TIMECARD_LIB.TIMECARD(SCH_1):IO_L24N_34':
 C_SIGNAL='@timecard_lib.timecard(sch_1):io_l24n_34';
NODE_NAME     U24 Y9
 '@TIMECARD_LIB.TIMECARD(SCH_1):PAGE163_I1@PLD.XC7A200T_2FBG484C_FBG484(CHIPS)':
 'IO_L24N_T3_34': CDS_PINID='IO_L24N_T3_34';
NODE_NAME     TP141 1
 '@TIMECARD_LIB.TIMECARD(SCH_1):PAGE16_I1023@CLS.TP_PIONT(CHIPS)':
 '1': CDS_PINID='\1\';
NET_NAME
'IO_L24N_35'
 '@TIMECARD_LIB.TIMECARD(SCH_1):IO_L24N_35':
 C_SIGNAL='@timecard_lib.timecard(sch_1):io_l24n_35';
NODE_NAME     U24 N5
 '@TIMECARD_LIB.TIMECARD(SCH_1):PAGE163_I1@PLD.XC7A200T_2FBG484C_FBG484(CHIPS)':
 'IO_L24N_T3_35': CDS_PINID='IO_L24N_T3_35';
NODE_NAME     TP204 1
 '@TIMECARD_LIB.TIMECARD(SCH_1):PAGE16_I1524@CLS.TP_PIONT(CHIPS)':
 '1': CDS_PINID='\1\';
NET_NAME
'IO_L24P_16'
 '@TIMECARD_LIB.TIMECARD(SCH_1):IO_L24P_16':
 C_SIGNAL='@timecard_lib.timecard(sch_1):io_l24p_16';
NODE_NAME     U24 G21
 '@TIMECARD_LIB.TIMECARD(SCH_1):PAGE162_I228@PLD.XC7A200T_2FBG484C_FBG484(CHIPS)':
 'IO_L24P_T3_16': CDS_PINID='IO_L24P_T3_16';
NODE_NAME     TP187 1
 '@TIMECARD_LIB.TIMECARD(SCH_1):PAGE16_I1509@CLS.TP_PIONT(CHIPS)':
 '1': CDS_PINID='\1\';
NET_NAME
'IO_L24P_34'
 '@TIMECARD_LIB.TIMECARD(SCH_1):IO_L24P_34':
 C_SIGNAL='@timecard_lib.timecard(sch_1):io_l24p_34';
NODE_NAME     U24 W9
 '@TIMECARD_LIB.TIMECARD(SCH_1):PAGE163_I1@PLD.XC7A200T_2FBG484C_FBG484(CHIPS)':
 'IO_L24P_T3_34': CDS_PINID='IO_L24P_T3_34';
NODE_NAME     TP140 1
 '@TIMECARD_LIB.TIMECARD(SCH_1):PAGE16_I1022@CLS.TP_PIONT(CHIPS)':
 '1': CDS_PINID='\1\';
NET_NAME
'IO_L24P_35'
 '@TIMECARD_LIB.TIMECARD(SCH_1):IO_L24P_35':
 C_SIGNAL='@timecard_lib.timecard(sch_1):io_l24p_35';
NODE_NAME     U24 P6
 '@TIMECARD_LIB.TIMECARD(SCH_1):PAGE163_I1@PLD.XC7A200T_2FBG484C_FBG484(CHIPS)':
 'IO_L24P_T3_35': CDS_PINID='IO_L24P_T3_35';
NODE_NAME     TP203 1
 '@TIMECARD_LIB.TIMECARD(SCH_1):PAGE16_I1523@CLS.TP_PIONT(CHIPS)':
 '1': CDS_PINID='\1\';
NET_NAME
'LED_DATOUT0'
 '@TIMECARD_LIB.TIMECARD(SCH_1):LED_DATOUT0':
 C_SIGNAL='@timecard_lib.timecard(sch_1):led_datout0';
NODE_NAME     U24 B13
 '@TIMECARD_LIB.TIMECARD(SCH_1):PAGE162_I228@PLD.XC7A200T_2FBG484C_FBG484(CHIPS)':
 'IO_L8N_T1_16': CDS_PINID='IO_L8N_T1_16';
NODE_NAME     DS4 C
 '@TIMECARD_LIB.TIMECARD(SCH_1):PAGE14_I137@DISCRETE.OPTICAL(CHIPS)':
 'C': CDS_PINID='C';
NET_NAME
'LED_DATOUT1'
 '@TIMECARD_LIB.TIMECARD(SCH_1):LED_DATOUT1':
 C_SIGNAL='@timecard_lib.timecard(sch_1):led_datout1';
NODE_NAME     U24 C13
 '@TIMECARD_LIB.TIMECARD(SCH_1):PAGE162_I228@PLD.XC7A200T_2FBG484C_FBG484(CHIPS)':
 'IO_L8P_T1_16': CDS_PINID='IO_L8P_T1_16';
NODE_NAME     DS3 C
 '@TIMECARD_LIB.TIMECARD(SCH_1):PAGE14_I136@DISCRETE.OPTICAL(CHIPS)':
 'C': CDS_PINID='C';
NET_NAME
'LED_DATOUT2'
 '@TIMECARD_LIB.TIMECARD(SCH_1):LED_DATOUT2':
 C_SIGNAL='@timecard_lib.timecard(sch_1):led_datout2';
NODE_NAME     DS2 C
 '@TIMECARD_LIB.TIMECARD(SCH_1):PAGE14_I11@DISCRETE.OPTICAL(CHIPS)':
 'C': CDS_PINID='C';
NODE_NAME     U24 D14
 '@TIMECARD_LIB.TIMECARD(SCH_1):PAGE162_I228@PLD.XC7A200T_2FBG484C_FBG484(CHIPS)':
 'IO_L6P_T0_16': CDS_PINID='IO_L6P_T0_16';
NET_NAME
'LED_DATOUT3'
 '@TIMECARD_LIB.TIMECARD(SCH_1):LED_DATOUT3':
 C_SIGNAL='@timecard_lib.timecard(sch_1):led_datout3';
NODE_NAME     DS1 C
 '@TIMECARD_LIB.TIMECARD(SCH_1):PAGE14_I12@DISCRETE.OPTICAL(CHIPS)':
 'C': CDS_PINID='C';
NODE_NAME     U24 D15
 '@TIMECARD_LIB.TIMECARD(SCH_1):PAGE162_I228@PLD.XC7A200T_2FBG484C_FBG484(CHIPS)':
 'IO_L6N_T0_VREF_16': CDS_PINID='IO_L6N_T0_VREF_16';
NET_NAME
'LM75B_I2C_SCL'
 '@TIMECARD_LIB.TIMECARD(SCH_1):LM75B_I2C_SCL':
 C_SIGNAL='@timecard_lib.timecard(sch_1):lm75b_i2c_scl';
NODE_NAME     U4 5
 '@TIMECARD_LIB.TIMECARD(SCH_1):PAGE5_I33@INTERFACE.PCA9546APW_TSSOP16(CHIPS)':
 'SC0': CDS_PINID='SC0';
NODE_NAME     R21 2
 '@TIMECARD_LIB.TIMECARD(SCH_1):PAGE6_I16@PASSIVE.RESISTOR(CHIPS)':
 '2': CDS_PINID='\2\';
NODE_NAME     U8 2
 '@TIMECARD_LIB.TIMECARD(SCH_1):PAGE6_I34@INTERFACE.LM75BDP_TSSOP8(CHIPS)':
 'SCL': CDS_PINID='SCL';
NODE_NAME     U35 2
 '@TIMECARD_LIB.TIMECARD(SCH_1):PAGE6_I59@INTERFACE.LM75BDP_TSSOP8(CHIPS)':
 'SCL': CDS_PINID='SCL';
NODE_NAME     U36 2
 '@TIMECARD_LIB.TIMECARD(SCH_1):PAGE6_I81@INTERFACE.LM75BDP_TSSOP8(CHIPS)':
 'SCL': CDS_PINID='SCL';
NET_NAME
'LM75B_I2C_SDA'
 '@TIMECARD_LIB.TIMECARD(SCH_1):LM75B_I2C_SDA':
 C_SIGNAL='@timecard_lib.timecard(sch_1):lm75b_i2c_sda';
NODE_NAME     U4 4
 '@TIMECARD_LIB.TIMECARD(SCH_1):PAGE5_I33@INTERFACE.PCA9546APW_TSSOP16(CHIPS)':
 'SD0': CDS_PINID='SD0';
NODE_NAME     R20 2
 '@TIMECARD_LIB.TIMECARD(SCH_1):PAGE6_I14@PASSIVE.RESISTOR(CHIPS)':
 '2': CDS_PINID='\2\';
NODE_NAME     R332 1
 '@TIMECARD_LIB.TIMECARD(SCH_1):PAGE6_I15@PASSIVE.RESISTOR(CHIPS)':
 '1': CDS_PINID='\1\';
NODE_NAME     R406 1
 '@TIMECARD_LIB.TIMECARD(SCH_1):PAGE6_I76@PASSIVE.RESISTOR(CHIPS)':
 '1': CDS_PINID='\1\';
NODE_NAME     R407 1
 '@TIMECARD_LIB.TIMECARD(SCH_1):PAGE6_I100@PASSIVE.RESISTOR(CHIPS)':
 '1': CDS_PINID='\1\';
NET_NAME
'MAC_ALARM'
 '@TIMECARD_LIB.TIMECARD(SCH_1):MAC_ALARM':
 C_SIGNAL='@timecard_lib.timecard(sch_1):mac_alarm';
NODE_NAME     R96 1
 '@TIMECARD_LIB.TIMECARD(SCH_1):PAGE527_I23@PASSIVE.RESISTOR(CHIPS)':
 '1': CDS_PINID='\1\';
NODE_NAME     P1 20
 '@TIMECARD_LIB.TIMECARD(SCH_1):PAGE527_I193@CONNECTOR.CONN_HDR_2X10_M_S_SMT(CHIPS)':
 '20': CDS_PINID='\20\';
NODE_NAME     TP51 1
 '@TIMECARD_LIB.TIMECARD(SCH_1):PAGE16_I1704@CLS.TP_PIONT(CHIPS)':
 '1': CDS_PINID='\1\';
NET_NAME
'MAC_USB_DM'
 '@TIMECARD_LIB.TIMECARD(SCH_1):MAC_USB_DM':
 C_SIGNAL='@timecard_lib.timecard(sch_1):mac_usb_dm';
NODE_NAME     U24 R14
 '@TIMECARD_LIB.TIMECARD(SCH_1):PAGE161_I2@PLD.XC7A200T_2FBG484C_FBG484(CHIPS)':
 'IO_L19N_T3_A09_D25_VREF_14': CDS_PINID='IO_L19N_T3_A09_D25_VREF_14';
NODE_NAME     R437 2
 '@TIMECARD_LIB.TIMECARD(SCH_1):PAGE161_I239@PASSIVE.RESISTOR(CHIPS)':
 '2': CDS_PINID='\2\';
NODE_NAME     U11 4
 '@TIMECARD_LIB.TIMECARD(SCH_1):PAGE527_I108@STDLOGIC.TS3USB3031RMGR_WQFN12(CHIPS)':
 'USB1_N': CDS_PINID='USB1_N';
NODE_NAME     R105 2
 '@TIMECARD_LIB.TIMECARD(SCH_1):PAGE527_I123@PASSIVE.RESISTOR(CHIPS)':
 '2': CDS_PINID='\2\';
NET_NAME
'MAC_USB_DP'
 '@TIMECARD_LIB.TIMECARD(SCH_1):MAC_USB_DP':
 C_SIGNAL='@timecard_lib.timecard(sch_1):mac_usb_dp';
NODE_NAME     U24 P14
 '@TIMECARD_LIB.TIMECARD(SCH_1):PAGE161_I2@PLD.XC7A200T_2FBG484C_FBG484(CHIPS)':
 'IO_L19P_T3_A10_D26_14': CDS_PINID='IO_L19P_T3_A10_D26_14';
NODE_NAME     R436 2
 '@TIMECARD_LIB.TIMECARD(SCH_1):PAGE161_I240@PASSIVE.RESISTOR(CHIPS)':
 '2': CDS_PINID='\2\';
NODE_NAME     U11 3
 '@TIMECARD_LIB.TIMECARD(SCH_1):PAGE527_I108@STDLOGIC.TS3USB3031RMGR_WQFN12(CHIPS)':
 'USB1_P': CDS_PINID='USB1_P';
NODE_NAME     R106 2
 '@TIMECARD_LIB.TIMECARD(SCH_1):PAGE527_I124@PASSIVE.RESISTOR(CHIPS)':
 '2': CDS_PINID='\2\';
NET_NAME
'MHZ125CLKN_CLKIN'
 '@TIMECARD_LIB.TIMECARD(SCH_1):MHZ125CLKN_CLKIN':
 C_SIGNAL='@timecard_lib.timecard(sch_1):mhz125clkn_clkin';
NODE_NAME     U24 E6
 '@TIMECARD_LIB.TIMECARD(SCH_1):PAGE127_I232@PLD.XC7A200T_2FBG484C_FBG484(CHIPS)':
 'MGTREFCLK0N_216': CDS_PINID='MGTREFCLK0N_216';
NODE_NAME     R197 2
 '@TIMECARD_LIB.TIMECARD(SCH_1):PAGE127_I333@PASSIVE.RESISTOR(CHIPS)':
 '2': CDS_PINID='\2\';
NODE_NAME     C254 2
 '@TIMECARD_LIB.TIMECARD(SCH_1):PAGE522_I142@PASSIVE.CAPACITOR(CHIPS)':
 '2': CDS_PINID='\2\';
NET_NAME
'MHZ125CLKP_CLKIN'
 '@TIMECARD_LIB.TIMECARD(SCH_1):MHZ125CLKP_CLKIN':
 C_SIGNAL='@timecard_lib.timecard(sch_1):mhz125clkp_clkin';
NODE_NAME     U24 F6
 '@TIMECARD_LIB.TIMECARD(SCH_1):PAGE127_I232@PLD.XC7A200T_2FBG484C_FBG484(CHIPS)':
 'MGTREFCLK0P_216': CDS_PINID='MGTREFCLK0P_216';
NODE_NAME     R197 1
 '@TIMECARD_LIB.TIMECARD(SCH_1):PAGE127_I333@PASSIVE.RESISTOR(CHIPS)':
 '1': CDS_PINID='\1\';
NODE_NAME     C253 2
 '@TIMECARD_LIB.TIMECARD(SCH_1):PAGE522_I143@PASSIVE.CAPACITOR(CHIPS)':
 '2': CDS_PINID='\2\';
NET_NAME
'MHZ200CLKN_CLKIN'
 '@TIMECARD_LIB.TIMECARD(SCH_1):MHZ200CLKN_CLKIN':
 C_SIGNAL='@timecard_lib.timecard(sch_1):mhz200clkn_clkin';
NODE_NAME     U24 T4
 '@TIMECARD_LIB.TIMECARD(SCH_1):PAGE163_I1@PLD.XC7A200T_2FBG484C_FBG484(CHIPS)':
 'IO_L13N_T2_MRCC_34': CDS_PINID='IO_L13N_T2_MRCC_34';
NODE_NAME     C252 2
 '@TIMECARD_LIB.TIMECARD(SCH_1):PAGE522_I160@PASSIVE.CAPACITOR(CHIPS)':
 '2': CDS_PINID='\2\';
NODE_NAME     R278 2
 '@TIMECARD_LIB.TIMECARD(SCH_1):PAGE163_I36@PASSIVE.RESISTOR(CHIPS)':
 '2': CDS_PINID='\2\';
NODE_NAME     R355 1
 '@TIMECARD_LIB.TIMECARD(SCH_1):PAGE163_I120@PASSIVE.RESISTOR(CHIPS)':
 '1': CDS_PINID='\1\';
NODE_NAME     R360 1
 '@TIMECARD_LIB.TIMECARD(SCH_1):PAGE163_I128@PASSIVE.RESISTOR(CHIPS)':
 '1': CDS_PINID='\1\';
NET_NAME
'MHZ200CLKP_CLKIN'
 '@TIMECARD_LIB.TIMECARD(SCH_1):MHZ200CLKP_CLKIN':
 C_SIGNAL='@timecard_lib.timecard(sch_1):mhz200clkp_clkin';
NODE_NAME     U24 R4
 '@TIMECARD_LIB.TIMECARD(SCH_1):PAGE163_I1@PLD.XC7A200T_2FBG484C_FBG484(CHIPS)':
 'IO_L13P_T2_MRCC_34': CDS_PINID='IO_L13P_T2_MRCC_34';
NODE_NAME     C251 2
 '@TIMECARD_LIB.TIMECARD(SCH_1):PAGE522_I161@PASSIVE.CAPACITOR(CHIPS)':
 '2': CDS_PINID='\2\';
NODE_NAME     R278 1
 '@TIMECARD_LIB.TIMECARD(SCH_1):PAGE163_I36@PASSIVE.RESISTOR(CHIPS)':
 '1': CDS_PINID='\1\';
NODE_NAME     R358 1
 '@TIMECARD_LIB.TIMECARD(SCH_1):PAGE163_I126@PASSIVE.RESISTOR(CHIPS)':
 '1': CDS_PINID='\1\';
NODE_NAME     R359 1
 '@TIMECARD_LIB.TIMECARD(SCH_1):PAGE163_I127@PASSIVE.RESISTOR(CHIPS)':
 '1': CDS_PINID='\1\';
NET_NAME
'MUX1_SEL'
 '@TIMECARD_LIB.TIMECARD(SCH_1):MUX1_SEL':
 C_SIGNAL='@timecard_lib.timecard(sch_1):mux1_sel';
NODE_NAME     R448 1
 '@TIMECARD_LIB.TIMECARD(SCH_1):PAGE524_I423@PASSIVE.RESISTOR(CHIPS)':
 '1': CDS_PINID='\1\';
NODE_NAME     R449 1
 '@TIMECARD_LIB.TIMECARD(SCH_1):PAGE524_I424@PASSIVE.RESISTOR(CHIPS)':
 '1': CDS_PINID='\1\';
NODE_NAME     U30 1
 '@TIMECARD_LIB.TIMECARD(SCH_1):PAGE524_I425@STDLOGIC.TS3A5018PWR_TSSOP16(CHIPS)':
 'IN': CDS_PINID='\in\';
NODE_NAME     R450 1
 '@TIMECARD_LIB.TIMECARD(SCH_1):PAGE524_I440@PASSIVE.RESISTOR(CHIPS)':
 '1': CDS_PINID='\1\';
NODE_NAME     R451 1
 '@TIMECARD_LIB.TIMECARD(SCH_1):PAGE524_I441@PASSIVE.RESISTOR(CHIPS)':
 '1': CDS_PINID='\1\';
NODE_NAME     TP14 1
 '@TIMECARD_LIB.TIMECARD(SCH_1):PAGE16_I1629@CLS.TP_PIONT(CHIPS)':
 '1': CDS_PINID='\1\';
NET_NAME
'MUX2_SEL'
 '@TIMECARD_LIB.TIMECARD(SCH_1):MUX2_SEL':
 C_SIGNAL='@timecard_lib.timecard(sch_1):mux2_sel';
NODE_NAME     U38 1
 '@TIMECARD_LIB.TIMECARD(SCH_1):PAGE524_I400@STDLOGIC.TS3A5018PWR_TSSOP16(CHIPS)':
 'IN': CDS_PINID='\in\';
NODE_NAME     U39 6
 '@TIMECARD_LIB.TIMECARD(SCH_1):PAGE524_I407@INTERFACE.NLASB3157DFT2G_SC88(CHIPS)':
 'SELECT': CDS_PINID='\select\';
NODE_NAME     U40 6
 '@TIMECARD_LIB.TIMECARD(SCH_1):PAGE524_I408@INTERFACE.NLASB3157DFT2G_SC88(CHIPS)':
 'SELECT': CDS_PINID='\select\';
NODE_NAME     R461 2
 '@TIMECARD_LIB.TIMECARD(SCH_1):PAGE524_I411@PASSIVE.RESISTOR(CHIPS)':
 '2': CDS_PINID='\2\';
NODE_NAME     R462 2
 '@TIMECARD_LIB.TIMECARD(SCH_1):PAGE524_I412@PASSIVE.RESISTOR(CHIPS)':
 '2': CDS_PINID='\2\';
NODE_NAME     R458 2
 '@TIMECARD_LIB.TIMECARD(SCH_1):PAGE524_I430@PASSIVE.RESISTOR(CHIPS)':
 '2': CDS_PINID='\2\';
NODE_NAME     R457 2
 '@TIMECARD_LIB.TIMECARD(SCH_1):PAGE524_I431@PASSIVE.RESISTOR(CHIPS)':
 '2': CDS_PINID='\2\';
NODE_NAME     TP13 1
 '@TIMECARD_LIB.TIMECARD(SCH_1):PAGE16_I1628@CLS.TP_PIONT(CHIPS)':
 '1': CDS_PINID='\1\';
NET_NAME
'MUX3_SEL'
 '@TIMECARD_LIB.TIMECARD(SCH_1):MUX3_SEL':
 C_SIGNAL='@timecard_lib.timecard(sch_1):mux3_sel';
NODE_NAME     U37 1
 '@TIMECARD_LIB.TIMECARD(SCH_1):PAGE524_I448@STDLOGIC.TS3A5018PWR_TSSOP16(CHIPS)':
 'IN': CDS_PINID='\in\';
NODE_NAME     R485 2
 '@TIMECARD_LIB.TIMECARD(SCH_1):PAGE524_I459@PASSIVE.RESISTOR(CHIPS)':
 '2': CDS_PINID='\2\';
NODE_NAME     R486 2
 '@TIMECARD_LIB.TIMECARD(SCH_1):PAGE524_I460@PASSIVE.RESISTOR(CHIPS)':
 '2': CDS_PINID='\2\';
NODE_NAME     R483 2
 '@TIMECARD_LIB.TIMECARD(SCH_1):PAGE524_I462@PASSIVE.RESISTOR(CHIPS)':
 '2': CDS_PINID='\2\';
NODE_NAME     R482 2
 '@TIMECARD_LIB.TIMECARD(SCH_1):PAGE524_I464@PASSIVE.RESISTOR(CHIPS)':
 '2': CDS_PINID='\2\';
NODE_NAME     TP12 1
 '@TIMECARD_LIB.TIMECARD(SCH_1):PAGE16_I1627@CLS.TP_PIONT(CHIPS)':
 '1': CDS_PINID='\1\';
NET_NAME
'MUX_USB_DM'
 '@TIMECARD_LIB.TIMECARD(SCH_1):MUX_USB_DM':
 C_SIGNAL='@timecard_lib.timecard(sch_1):mux_usb_dm';
NODE_NAME     U11 10
 '@TIMECARD_LIB.TIMECARD(SCH_1):PAGE527_I108@STDLOGIC.TS3USB3031RMGR_WQFN12(CHIPS)':
 'D_N': CDS_PINID='D_N';
NODE_NAME     R105 1
 '@TIMECARD_LIB.TIMECARD(SCH_1):PAGE527_I123@PASSIVE.RESISTOR(CHIPS)':
 '1': CDS_PINID='\1\';
NODE_NAME     R98 2
 '@TIMECARD_LIB.TIMECARD(SCH_1):PAGE527_I175@PASSIVE.RESISTOR(CHIPS)':
 '2': CDS_PINID='\2\';
NET_NAME
'MUX_USB_DP'
 '@TIMECARD_LIB.TIMECARD(SCH_1):MUX_USB_DP':
 C_SIGNAL='@timecard_lib.timecard(sch_1):mux_usb_dp';
NODE_NAME     U11 11
 '@TIMECARD_LIB.TIMECARD(SCH_1):PAGE527_I108@STDLOGIC.TS3USB3031RMGR_WQFN12(CHIPS)':
 'D_P': CDS_PINID='D_P';
NODE_NAME     R106 1
 '@TIMECARD_LIB.TIMECARD(SCH_1):PAGE527_I124@PASSIVE.RESISTOR(CHIPS)':
 '1': CDS_PINID='\1\';
NODE_NAME     R97 2
 '@TIMECARD_LIB.TIMECARD(SCH_1):PAGE527_I176@PASSIVE.RESISTOR(CHIPS)':
 '2': CDS_PINID='\2\';
NET_NAME
'NC'
 'NC':
 C_SIGNAL='NC';
NODE_NAME     GF1 B9
 '@TIMECARD_LIB.TIMECARD(SCH_1):PAGE3_I61@CONNECTOR.CONN_64P_GF(CHIPS)':
 'JTAG1': CDS_PINID='JTAG1';
NODE_NAME     GF1 B12
 '@TIMECARD_LIB.TIMECARD(SCH_1):PAGE3_I61@CONNECTOR.CONN_64P_GF(CHIPS)':
 'RSVD1': CDS_PINID='RSVD1';
NODE_NAME     GF1 A19
 '@TIMECARD_LIB.TIMECARD(SCH_1):PAGE3_I61@CONNECTOR.CONN_64P_GF(CHIPS)':
 'RSVD2': CDS_PINID='RSVD2';
NODE_NAME     GF1 B30
 '@TIMECARD_LIB.TIMECARD(SCH_1):PAGE3_I61@CONNECTOR.CONN_64P_GF(CHIPS)':
 'RSVD3': CDS_PINID='RSVD3';
NODE_NAME     GF1 A32
 '@TIMECARD_LIB.TIMECARD(SCH_1):PAGE3_I61@CONNECTOR.CONN_64P_GF(CHIPS)':
 'RSVD4': CDS_PINID='RSVD4';
NODE_NAME     GF1 B11
 '@TIMECARD_LIB.TIMECARD(SCH_1):PAGE3_I61@CONNECTOR.CONN_64P_GF(CHIPS)':
 'WAKE*': CDS_PINID='\wake*\';
NODE_NAME     CR5 4
 '@TIMECARD_LIB.TIMECARD(SCH_1):PAGE12_I42@DISCRETE.DIODE_4_V1(CHIPS)':
 'VDD': CDS_PINID='VDD';
NODE_NAME     U2 5
 '@TIMECARD_LIB.TIMECARD(SCH_1):PAGE3_I100@STDLOGIC.G220_10198_01(CHIPS)':
 'READY': CDS_PINID='READY';
NODE_NAME     U20 8
 '@TIMECARD_LIB.TIMECARD(SCH_1):PAGE68_I6@ANALOG.ISL80101IRAJZ_DFN10(CHIPS)':
 'NC': CDS_PINID='NC';
NODE_NAME     U21 8
 '@TIMECARD_LIB.TIMECARD(SCH_1):PAGE68_I52@ANALOG.ISL80101IRAJZ_DFN10(CHIPS)':
 'NC': CDS_PINID='NC';
NODE_NAME     U24 Y17
 '@TIMECARD_LIB.TIMECARD(SCH_1):PAGE161_I2@PLD.XC7A200T_2FBG484C_FBG484(CHIPS)':
 'IO_0_13': CDS_PINID='IO_0_13';
NODE_NAME     U24 AA16
 '@TIMECARD_LIB.TIMECARD(SCH_1):PAGE161_I2@PLD.XC7A200T_2FBG484C_FBG484(CHIPS)':
 'IO_L1N_T0_13': CDS_PINID='IO_L1N_T0_13';
NODE_NAME     U24 V22
 '@TIMECARD_LIB.TIMECARD(SCH_1):PAGE161_I2@PLD.XC7A200T_2FBG484C_FBG484(CHIPS)':
 'IO_L3N_T0_DQS_EMCCLK_14': CDS_PINID='IO_L3N_T0_DQS_EMCCLK_14';
NODE_NAME     U24 AB15
 '@TIMECARD_LIB.TIMECARD(SCH_1):PAGE161_I2@PLD.XC7A200T_2FBG484C_FBG484(CHIPS)':
 'IO_L4N_T0_13': CDS_PINID='IO_L4N_T0_13';
NODE_NAME     U24 U21
 '@TIMECARD_LIB.TIMECARD(SCH_1):PAGE161_I2@PLD.XC7A200T_2FBG484C_FBG484(CHIPS)':
 'IO_L4N_T0_D05_14': CDS_PINID='IO_L4N_T0_D05_14';
NODE_NAME     U24 T21
 '@TIMECARD_LIB.TIMECARD(SCH_1):PAGE161_I2@PLD.XC7A200T_2FBG484C_FBG484(CHIPS)':
 'IO_L4P_T0_D04_14': CDS_PINID='IO_L4P_T0_D04_14';
NODE_NAME     U24 AA14
 '@TIMECARD_LIB.TIMECARD(SCH_1):PAGE161_I2@PLD.XC7A200T_2FBG484C_FBG484(CHIPS)':
 'IO_L5N_T0_13': CDS_PINID='IO_L5N_T0_13';
NODE_NAME     U24 R19
 '@TIMECARD_LIB.TIMECARD(SCH_1):PAGE161_I2@PLD.XC7A200T_2FBG484C_FBG484(CHIPS)':
 'IO_L5N_T0_D07_14': CDS_PINID='IO_L5N_T0_D07_14';
NODE_NAME     U24 Y13
 '@TIMECARD_LIB.TIMECARD(SCH_1):PAGE161_I2@PLD.XC7A200T_2FBG484C_FBG484(CHIPS)':
 'IO_L5P_T0_13': CDS_PINID='IO_L5P_T0_13';
NODE_NAME     U24 P19
 '@TIMECARD_LIB.TIMECARD(SCH_1):PAGE161_I2@PLD.XC7A200T_2FBG484C_FBG484(CHIPS)':
 'IO_L5P_T0_D06_14': CDS_PINID='IO_L5P_T0_D06_14';
NODE_NAME     U24 T20
 '@TIMECARD_LIB.TIMECARD(SCH_1):PAGE161_I2@PLD.XC7A200T_2FBG484C_FBG484(CHIPS)':
 'IO_L6N_T0_D08_VREF_14': CDS_PINID='IO_L6N_T0_D08_VREF_14';
NODE_NAME     U24 AB12
 '@TIMECARD_LIB.TIMECARD(SCH_1):PAGE161_I2@PLD.XC7A200T_2FBG484C_FBG484(CHIPS)':
 'IO_L7N_T1_13': CDS_PINID='IO_L7N_T1_13';
NODE_NAME     U24 W22
 '@TIMECARD_LIB.TIMECARD(SCH_1):PAGE161_I2@PLD.XC7A200T_2FBG484C_FBG484(CHIPS)':
 'IO_L7N_T1_D10_14': CDS_PINID='IO_L7N_T1_D10_14';
NODE_NAME     U24 AB11
 '@TIMECARD_LIB.TIMECARD(SCH_1):PAGE161_I2@PLD.XC7A200T_2FBG484C_FBG484(CHIPS)':
 'IO_L7P_T1_13': CDS_PINID='IO_L7P_T1_13';
NODE_NAME     U24 W21
 '@TIMECARD_LIB.TIMECARD(SCH_1):PAGE161_I2@PLD.XC7A200T_2FBG484C_FBG484(CHIPS)':
 'IO_L7P_T1_D09_14': CDS_PINID='IO_L7P_T1_D09_14';
NODE_NAME     U24 AA11
 '@TIMECARD_LIB.TIMECARD(SCH_1):PAGE161_I2@PLD.XC7A200T_2FBG484C_FBG484(CHIPS)':
 'IO_L9N_T1_DQS_13': CDS_PINID='IO_L9N_T1_DQS_13';
NODE_NAME     U24 Y22
 '@TIMECARD_LIB.TIMECARD(SCH_1):PAGE161_I2@PLD.XC7A200T_2FBG484C_FBG484(CHIPS)':
 'IO_L9N_T1_DQS_D13_14': CDS_PINID='IO_L9N_T1_DQS_D13_14';
NODE_NAME     U24 AA10
 '@TIMECARD_LIB.TIMECARD(SCH_1):PAGE161_I2@PLD.XC7A200T_2FBG484C_FBG484(CHIPS)':
 'IO_L9P_T1_DQS_13': CDS_PINID='IO_L9P_T1_DQS_13';
NODE_NAME     U24 Y21
 '@TIMECARD_LIB.TIMECARD(SCH_1):PAGE161_I2@PLD.XC7A200T_2FBG484C_FBG484(CHIPS)':
 'IO_L9P_T1_DQS_14': CDS_PINID='IO_L9P_T1_DQS_14';
NODE_NAME     U24 AB22
 '@TIMECARD_LIB.TIMECARD(SCH_1):PAGE161_I2@PLD.XC7A200T_2FBG484C_FBG484(CHIPS)':
 'IO_L10N_T1_D15_14': CDS_PINID='IO_L10N_T1_D15_14';
NODE_NAME     U24 AB21
 '@TIMECARD_LIB.TIMECARD(SCH_1):PAGE161_I2@PLD.XC7A200T_2FBG484C_FBG484(CHIPS)':
 'IO_L10P_T1_D14_14': CDS_PINID='IO_L10P_T1_D14_14';
NODE_NAME     U24 V20
 '@TIMECARD_LIB.TIMECARD(SCH_1):PAGE161_I2@PLD.XC7A200T_2FBG484C_FBG484(CHIPS)':
 'IO_L11N_T1_SRCC_14': CDS_PINID='IO_L11N_T1_SRCC_14';
NODE_NAME     U24 U20
 '@TIMECARD_LIB.TIMECARD(SCH_1):PAGE161_I2@PLD.XC7A200T_2FBG484C_FBG484(CHIPS)':
 'IO_L11P_T1_SRCC_14': CDS_PINID='IO_L11P_T1_SRCC_14';
NODE_NAME     U24 V14
 '@TIMECARD_LIB.TIMECARD(SCH_1):PAGE161_I2@PLD.XC7A200T_2FBG484C_FBG484(CHIPS)':
 'IO_L13N_T2_MRCC_13': CDS_PINID='IO_L13N_T2_MRCC_13';
NODE_NAME     U24 Y19
 '@TIMECARD_LIB.TIMECARD(SCH_1):PAGE161_I2@PLD.XC7A200T_2FBG484C_FBG484(CHIPS)':
 'IO_L13N_T2_MRCC_14': CDS_PINID='IO_L13N_T2_MRCC_14';
NODE_NAME     U24 V19
 '@TIMECARD_LIB.TIMECARD(SCH_1):PAGE161_I2@PLD.XC7A200T_2FBG484C_FBG484(CHIPS)':
 'IO_L14N_T2_SRCC_14': CDS_PINID='IO_L14N_T2_SRCC_14';
NODE_NAME     U24 U15
 '@TIMECARD_LIB.TIMECARD(SCH_1):PAGE161_I2@PLD.XC7A200T_2FBG484C_FBG484(CHIPS)':
 'IO_L14P_T2_SRCC_13': CDS_PINID='IO_L14P_T2_SRCC_13';
NODE_NAME     U24 V18
 '@TIMECARD_LIB.TIMECARD(SCH_1):PAGE161_I2@PLD.XC7A200T_2FBG484C_FBG484(CHIPS)':
 'IO_L14P_T2_SRCC_14': CDS_PINID='IO_L14P_T2_SRCC_14';
NODE_NAME     U24 T15
 '@TIMECARD_LIB.TIMECARD(SCH_1):PAGE161_I2@PLD.XC7A200T_2FBG484C_FBG484(CHIPS)':
 'IO_L15N_T2_DQS_13': CDS_PINID='IO_L15N_T2_DQS_13';
NODE_NAME     U24 AB20
 '@TIMECARD_LIB.TIMECARD(SCH_1):PAGE161_I2@PLD.XC7A200T_2FBG484C_FBG484(CHIPS)':
 'IO_L15N_T2_DQS_DOUT_CSO_14*': CDS_PINID='\io_l15n_t2_dqs_dout_cso_14*\';
NODE_NAME     U24 T14
 '@TIMECARD_LIB.TIMECARD(SCH_1):PAGE161_I2@PLD.XC7A200T_2FBG484C_FBG484(CHIPS)':
 'IO_L15P_T2_DQS_13': CDS_PINID='IO_L15P_T2_DQS_13';
NODE_NAME     U24 AA19
 '@TIMECARD_LIB.TIMECARD(SCH_1):PAGE161_I2@PLD.XC7A200T_2FBG484C_FBG484(CHIPS)':
 'IO_L15P_T2_DQS_RDWR_14*': CDS_PINID='\io_l15p_t2_dqs_rdwr_14*\';
NODE_NAME     U24 W16
 '@TIMECARD_LIB.TIMECARD(SCH_1):PAGE161_I2@PLD.XC7A200T_2FBG484C_FBG484(CHIPS)':
 'IO_L16N_T2_13': CDS_PINID='IO_L16N_T2_13';
NODE_NAME     U24 W17
 '@TIMECARD_LIB.TIMECARD(SCH_1):PAGE161_I2@PLD.XC7A200T_2FBG484C_FBG484(CHIPS)':
 'IO_L16N_T2_A15_D31_14': CDS_PINID='IO_L16N_T2_A15_D31_14';
NODE_NAME     U24 W15
 '@TIMECARD_LIB.TIMECARD(SCH_1):PAGE161_I2@PLD.XC7A200T_2FBG484C_FBG484(CHIPS)':
 'IO_L16P_T2_13': CDS_PINID='IO_L16P_T2_13';
NODE_NAME     U24 V17
 '@TIMECARD_LIB.TIMECARD(SCH_1):PAGE161_I2@PLD.XC7A200T_2FBG484C_FBG484(CHIPS)':
 'IO_L16P_T2_CSI_14*': CDS_PINID='\io_l16p_t2_csi_14*\';
NODE_NAME     U24 U18
 '@TIMECARD_LIB.TIMECARD(SCH_1):PAGE161_I2@PLD.XC7A200T_2FBG484C_FBG484(CHIPS)':
 'IO_L18N_T2_A11_D27_14': CDS_PINID='IO_L18N_T2_A11_D27_14';
NODE_NAME     U24 U17
 '@TIMECARD_LIB.TIMECARD(SCH_1):PAGE161_I2@PLD.XC7A200T_2FBG484C_FBG484(CHIPS)':
 'IO_L18P_T2_A12_D28_14': CDS_PINID='IO_L18P_T2_A12_D28_14';
NODE_NAME     U24 T18
 '@TIMECARD_LIB.TIMECARD(SCH_1):PAGE161_I2@PLD.XC7A200T_2FBG484C_FBG484(CHIPS)':
 'IO_L20N_T3_A07_D23_14': CDS_PINID='IO_L20N_T3_A07_D23_14';
NODE_NAME     U24 R18
 '@TIMECARD_LIB.TIMECARD(SCH_1):PAGE161_I2@PLD.XC7A200T_2FBG484C_FBG484(CHIPS)':
 'IO_L20P_T3_A08_D24_14': CDS_PINID='IO_L20P_T3_A08_D24_14';
NODE_NAME     U24 P17
 '@TIMECARD_LIB.TIMECARD(SCH_1):PAGE161_I2@PLD.XC7A200T_2FBG484C_FBG484(CHIPS)':
 'IO_L21N_T3_DQS_A06_D22_14': CDS_PINID='IO_L21N_T3_DQS_A06_D22_14';
NODE_NAME     U24 R16
 '@TIMECARD_LIB.TIMECARD(SCH_1):PAGE161_I2@PLD.XC7A200T_2FBG484C_FBG484(CHIPS)':
 'IO_L22N_T3_A04_D20_14': CDS_PINID='IO_L22N_T3_A04_D20_14';
NODE_NAME     U24 N14
 '@TIMECARD_LIB.TIMECARD(SCH_1):PAGE161_I2@PLD.XC7A200T_2FBG484C_FBG484(CHIPS)':
 'IO_L23N_T3_A02_D18_14': CDS_PINID='IO_L23N_T3_A02_D18_14';
NODE_NAME     U24 N13
 '@TIMECARD_LIB.TIMECARD(SCH_1):PAGE161_I2@PLD.XC7A200T_2FBG484C_FBG484(CHIPS)':
 'IO_L23P_T3_A03_D19_14': CDS_PINID='IO_L23P_T3_A03_D19_14';
NODE_NAME     U24 R17
 '@TIMECARD_LIB.TIMECARD(SCH_1):PAGE161_I2@PLD.XC7A200T_2FBG484C_FBG484(CHIPS)':
 'IO_L24N_T3_A00_D16_14': CDS_PINID='IO_L24N_T3_A00_D16_14';
NODE_NAME     U24 J16
 '@TIMECARD_LIB.TIMECARD(SCH_1):PAGE162_I228@PLD.XC7A200T_2FBG484C_FBG484(CHIPS)':
 'IO_0_15': CDS_PINID='IO_0_15';
NODE_NAME     U24 F15
 '@TIMECARD_LIB.TIMECARD(SCH_1):PAGE162_I228@PLD.XC7A200T_2FBG484C_FBG484(CHIPS)':
 'IO_0_16': CDS_PINID='IO_0_16';
NODE_NAME     U24 M17
 '@TIMECARD_LIB.TIMECARD(SCH_1):PAGE162_I228@PLD.XC7A200T_2FBG484C_FBG484(CHIPS)':
 'IO_25_15': CDS_PINID='IO_25_15';
NODE_NAME     U24 F21
 '@TIMECARD_LIB.TIMECARD(SCH_1):PAGE162_I228@PLD.XC7A200T_2FBG484C_FBG484(CHIPS)':
 'IO_25_16': CDS_PINID='IO_25_16';
NODE_NAME     U24 E17
 '@TIMECARD_LIB.TIMECARD(SCH_1):PAGE162_I228@PLD.XC7A200T_2FBG484C_FBG484(CHIPS)':
 'IO_L2N_T0_16': CDS_PINID='IO_L2N_T0_16';
NODE_NAME     U24 G16
 '@TIMECARD_LIB.TIMECARD(SCH_1):PAGE162_I228@PLD.XC7A200T_2FBG484C_FBG484(CHIPS)':
 'IO_L2N_T0_AD8N_15': CDS_PINID='IO_L2N_T0_AD8N_15';
NODE_NAME     U24 G18
 '@TIMECARD_LIB.TIMECARD(SCH_1):PAGE162_I228@PLD.XC7A200T_2FBG484C_FBG484(CHIPS)':
 'IO_L4N_T0_15': CDS_PINID='IO_L4N_T0_15';
NODE_NAME     U24 E14
 '@TIMECARD_LIB.TIMECARD(SCH_1):PAGE162_I228@PLD.XC7A200T_2FBG484C_FBG484(CHIPS)':
 'IO_L4N_T0_16': CDS_PINID='IO_L4N_T0_16';
NODE_NAME     U24 G17
 '@TIMECARD_LIB.TIMECARD(SCH_1):PAGE162_I228@PLD.XC7A200T_2FBG484C_FBG484(CHIPS)':
 'IO_L4P_T0_15': CDS_PINID='IO_L4P_T0_15';
NODE_NAME     U24 D16
 '@TIMECARD_LIB.TIMECARD(SCH_1):PAGE162_I228@PLD.XC7A200T_2FBG484C_FBG484(CHIPS)':
 'IO_L5N_T0_16': CDS_PINID='IO_L5N_T0_16';
NODE_NAME     U24 E16
 '@TIMECARD_LIB.TIMECARD(SCH_1):PAGE162_I228@PLD.XC7A200T_2FBG484C_FBG484(CHIPS)':
 'IO_L5P_T0_16': CDS_PINID='IO_L5P_T0_16';
NODE_NAME     U24 H18
 '@TIMECARD_LIB.TIMECARD(SCH_1):PAGE162_I228@PLD.XC7A200T_2FBG484C_FBG484(CHIPS)':
 'IO_L6N_T0_VREF_15': CDS_PINID='IO_L6N_T0_VREF_15';
NODE_NAME     U24 H17
 '@TIMECARD_LIB.TIMECARD(SCH_1):PAGE162_I228@PLD.XC7A200T_2FBG484C_FBG484(CHIPS)':
 'IO_L6P_T0_15': CDS_PINID='IO_L6P_T0_15';
NODE_NAME     U24 B16
 '@TIMECARD_LIB.TIMECARD(SCH_1):PAGE162_I228@PLD.XC7A200T_2FBG484C_FBG484(CHIPS)':
 'IO_L7N_T1_16': CDS_PINID='IO_L7N_T1_16';
NODE_NAME     U24 B15
 '@TIMECARD_LIB.TIMECARD(SCH_1):PAGE162_I228@PLD.XC7A200T_2FBG484C_FBG484(CHIPS)':
 'IO_L7P_T1_16': CDS_PINID='IO_L7P_T1_16';
NODE_NAME     U24 A16
 '@TIMECARD_LIB.TIMECARD(SCH_1):PAGE162_I228@PLD.XC7A200T_2FBG484C_FBG484(CHIPS)':
 'IO_L9N_T1_DQS_16': CDS_PINID='IO_L9N_T1_DQS_16';
NODE_NAME     U24 A15
 '@TIMECARD_LIB.TIMECARD(SCH_1):PAGE162_I228@PLD.XC7A200T_2FBG484C_FBG484(CHIPS)':
 'IO_L9P_T1_DQS_16': CDS_PINID='IO_L9P_T1_DQS_16';
NODE_NAME     U24 J21
 '@TIMECARD_LIB.TIMECARD(SCH_1):PAGE162_I228@PLD.XC7A200T_2FBG484C_FBG484(CHIPS)':
 'IO_L11N_T1_SRCC_15': CDS_PINID='IO_L11N_T1_SRCC_15';
NODE_NAME     U24 B18
 '@TIMECARD_LIB.TIMECARD(SCH_1):PAGE162_I228@PLD.XC7A200T_2FBG484C_FBG484(CHIPS)':
 'IO_L11N_T1_SRCC_16': CDS_PINID='IO_L11N_T1_SRCC_16';
NODE_NAME     U24 B17
 '@TIMECARD_LIB.TIMECARD(SCH_1):PAGE162_I228@PLD.XC7A200T_2FBG484C_FBG484(CHIPS)':
 'IO_L11P_T1_SRCC_16': CDS_PINID='IO_L11P_T1_SRCC_16';
NODE_NAME     U24 K19
 '@TIMECARD_LIB.TIMECARD(SCH_1):PAGE162_I228@PLD.XC7A200T_2FBG484C_FBG484(CHIPS)':
 'IO_L13N_T2_MRCC_15': CDS_PINID='IO_L13N_T2_MRCC_15';
NODE_NAME     U24 C19
 '@TIMECARD_LIB.TIMECARD(SCH_1):PAGE162_I228@PLD.XC7A200T_2FBG484C_FBG484(CHIPS)':
 'IO_L13N_T2_MRCC_16': CDS_PINID='IO_L13N_T2_MRCC_16';
NODE_NAME     U24 K18
 '@TIMECARD_LIB.TIMECARD(SCH_1):PAGE162_I228@PLD.XC7A200T_2FBG484C_FBG484(CHIPS)':
 'IO_L13P_T2_MRCC_15': CDS_PINID='IO_L13P_T2_MRCC_15';
NODE_NAME     U24 L20
 '@TIMECARD_LIB.TIMECARD(SCH_1):PAGE162_I228@PLD.XC7A200T_2FBG484C_FBG484(CHIPS)':
 'IO_L14N_T2_SRCC_15': CDS_PINID='IO_L14N_T2_SRCC_15';
NODE_NAME     U24 L19
 '@TIMECARD_LIB.TIMECARD(SCH_1):PAGE162_I228@PLD.XC7A200T_2FBG484C_FBG484(CHIPS)':
 'IO_L14P_T2_SRCC_15': CDS_PINID='IO_L14P_T2_SRCC_15';
NODE_NAME     U24 E18
 '@TIMECARD_LIB.TIMECARD(SCH_1):PAGE162_I228@PLD.XC7A200T_2FBG484C_FBG484(CHIPS)':
 'IO_L15N_T2_DQS_16': CDS_PINID='IO_L15N_T2_DQS_16';
NODE_NAME     U24 L18
 '@TIMECARD_LIB.TIMECARD(SCH_1):PAGE162_I228@PLD.XC7A200T_2FBG484C_FBG484(CHIPS)':
 'IO_L16N_T2_A27_15': CDS_PINID='IO_L16N_T2_A27_15';
NODE_NAME     U24 A19
 '@TIMECARD_LIB.TIMECARD(SCH_1):PAGE162_I228@PLD.XC7A200T_2FBG484C_FBG484(CHIPS)':
 'IO_L17N_T2_16': CDS_PINID='IO_L17N_T2_16';
NODE_NAME     U24 F20
 '@TIMECARD_LIB.TIMECARD(SCH_1):PAGE162_I228@PLD.XC7A200T_2FBG484C_FBG484(CHIPS)':
 'IO_L18N_T2_16': CDS_PINID='IO_L18N_T2_16';
NODE_NAME     U24 M20
 '@TIMECARD_LIB.TIMECARD(SCH_1):PAGE162_I228@PLD.XC7A200T_2FBG484C_FBG484(CHIPS)':
 'IO_L18N_T2_A23_15': CDS_PINID='IO_L18N_T2_A23_15';
NODE_NAME     U24 F19
 '@TIMECARD_LIB.TIMECARD(SCH_1):PAGE162_I228@PLD.XC7A200T_2FBG484C_FBG484(CHIPS)':
 'IO_L18P_T2_16': CDS_PINID='IO_L18P_T2_16';
NODE_NAME     U24 C20
 '@TIMECARD_LIB.TIMECARD(SCH_1):PAGE162_I228@PLD.XC7A200T_2FBG484C_FBG484(CHIPS)':
 'IO_L19N_T3_VREF_16': CDS_PINID='IO_L19N_T3_VREF_16';
NODE_NAME     U24 D20
 '@TIMECARD_LIB.TIMECARD(SCH_1):PAGE162_I228@PLD.XC7A200T_2FBG484C_FBG484(CHIPS)':
 'IO_L19P_T3_16': CDS_PINID='IO_L19P_T3_16';
NODE_NAME     U24 K17
 '@TIMECARD_LIB.TIMECARD(SCH_1):PAGE162_I228@PLD.XC7A200T_2FBG484C_FBG484(CHIPS)':
 'IO_L21P_T3_DQS_15': CDS_PINID='IO_L21P_T3_DQS_15';
NODE_NAME     U24 L16
 '@TIMECARD_LIB.TIMECARD(SCH_1):PAGE162_I228@PLD.XC7A200T_2FBG484C_FBG484(CHIPS)':
 'IO_L23P_T3_FOE_B_15': CDS_PINID='IO_L23P_T3_FOE_B_15';
NODE_NAME     U24 T3
 '@TIMECARD_LIB.TIMECARD(SCH_1):PAGE163_I1@PLD.XC7A200T_2FBG484C_FBG484(CHIPS)':
 'IO_0_34': CDS_PINID='IO_0_34';
NODE_NAME     U24 F4
 '@TIMECARD_LIB.TIMECARD(SCH_1):PAGE163_I1@PLD.XC7A200T_2FBG484C_FBG484(CHIPS)':
 'IO_0_35': CDS_PINID='IO_0_35';
NODE_NAME     U24 U7
 '@TIMECARD_LIB.TIMECARD(SCH_1):PAGE163_I1@PLD.XC7A200T_2FBG484C_FBG484(CHIPS)':
 'IO_25_34': CDS_PINID='IO_25_34';
NODE_NAME     U24 L6
 '@TIMECARD_LIB.TIMECARD(SCH_1):PAGE163_I1@PLD.XC7A200T_2FBG484C_FBG484(CHIPS)':
 'IO_25_35': CDS_PINID='IO_25_35';
NODE_NAME     U24 U1
 '@TIMECARD_LIB.TIMECARD(SCH_1):PAGE163_I1@PLD.XC7A200T_2FBG484C_FBG484(CHIPS)':
 'IO_L1N_T0_34': CDS_PINID='IO_L1N_T0_34';
NODE_NAME     U24 A1
 '@TIMECARD_LIB.TIMECARD(SCH_1):PAGE163_I1@PLD.XC7A200T_2FBG484C_FBG484(CHIPS)':
 'IO_L1N_T0_AD4N_35': CDS_PINID='IO_L1N_T0_AD4N_35';
NODE_NAME     U24 T1
 '@TIMECARD_LIB.TIMECARD(SCH_1):PAGE163_I1@PLD.XC7A200T_2FBG484C_FBG484(CHIPS)':
 'IO_L1P_T0_34': CDS_PINID='IO_L1P_T0_34';
NODE_NAME     U24 B1
 '@TIMECARD_LIB.TIMECARD(SCH_1):PAGE163_I1@PLD.XC7A200T_2FBG484C_FBG484(CHIPS)':
 'IO_L1P_T0_AD4P_35': CDS_PINID='IO_L1P_T0_AD4P_35';
NODE_NAME     U24 V2
 '@TIMECARD_LIB.TIMECARD(SCH_1):PAGE163_I1@PLD.XC7A200T_2FBG484C_FBG484(CHIPS)':
 'IO_L2N_T0_34': CDS_PINID='IO_L2N_T0_34';
NODE_NAME     U24 B2
 '@TIMECARD_LIB.TIMECARD(SCH_1):PAGE163_I1@PLD.XC7A200T_2FBG484C_FBG484(CHIPS)':
 'IO_L2N_T0_AD12N_35': CDS_PINID='IO_L2N_T0_AD12N_35';
NODE_NAME     U24 U2
 '@TIMECARD_LIB.TIMECARD(SCH_1):PAGE163_I1@PLD.XC7A200T_2FBG484C_FBG484(CHIPS)':
 'IO_L2P_T0_34': CDS_PINID='IO_L2P_T0_34';
NODE_NAME     U24 C2
 '@TIMECARD_LIB.TIMECARD(SCH_1):PAGE163_I1@PLD.XC7A200T_2FBG484C_FBG484(CHIPS)':
 'IO_L2P_T0_AD12P_35': CDS_PINID='IO_L2P_T0_AD12P_35';
NODE_NAME     U24 R2
 '@TIMECARD_LIB.TIMECARD(SCH_1):PAGE163_I1@PLD.XC7A200T_2FBG484C_FBG484(CHIPS)':
 'IO_L3N_T0_DQS_34': CDS_PINID='IO_L3N_T0_DQS_34';
NODE_NAME     U24 D1
 '@TIMECARD_LIB.TIMECARD(SCH_1):PAGE163_I1@PLD.XC7A200T_2FBG484C_FBG484(CHIPS)':
 'IO_L3N_T0_DQS_AD5N_35': CDS_PINID='IO_L3N_T0_DQS_AD5N_35';
NODE_NAME     U24 R3
 '@TIMECARD_LIB.TIMECARD(SCH_1):PAGE163_I1@PLD.XC7A200T_2FBG484C_FBG484(CHIPS)':
 'IO_L3P_T0_DQS_34': CDS_PINID='IO_L3P_T0_DQS_34';
NODE_NAME     U24 E1
 '@TIMECARD_LIB.TIMECARD(SCH_1):PAGE163_I1@PLD.XC7A200T_2FBG484C_FBG484(CHIPS)':
 'IO_L3P_T0_DQS_AD5P_35': CDS_PINID='IO_L3P_T0_DQS_AD5P_35';
NODE_NAME     U24 Y2
 '@TIMECARD_LIB.TIMECARD(SCH_1):PAGE163_I1@PLD.XC7A200T_2FBG484C_FBG484(CHIPS)':
 'IO_L4N_T0_34': CDS_PINID='IO_L4N_T0_34';
NODE_NAME     U24 D2
 '@TIMECARD_LIB.TIMECARD(SCH_1):PAGE163_I1@PLD.XC7A200T_2FBG484C_FBG484(CHIPS)':
 'IO_L4N_T0_35': CDS_PINID='IO_L4N_T0_35';
NODE_NAME     U24 W2
 '@TIMECARD_LIB.TIMECARD(SCH_1):PAGE163_I1@PLD.XC7A200T_2FBG484C_FBG484(CHIPS)':
 'IO_L4P_T0_34': CDS_PINID='IO_L4P_T0_34';
NODE_NAME     U24 E2
 '@TIMECARD_LIB.TIMECARD(SCH_1):PAGE163_I1@PLD.XC7A200T_2FBG484C_FBG484(CHIPS)':
 'IO_L4P_T0_35': CDS_PINID='IO_L4P_T0_35';
NODE_NAME     U24 F1
 '@TIMECARD_LIB.TIMECARD(SCH_1):PAGE163_I1@PLD.XC7A200T_2FBG484C_FBG484(CHIPS)':
 'IO_L5N_T0_AD13N_35': CDS_PINID='IO_L5N_T0_AD13N_35';
NODE_NAME     U24 G1
 '@TIMECARD_LIB.TIMECARD(SCH_1):PAGE163_I1@PLD.XC7A200T_2FBG484C_FBG484(CHIPS)':
 'IO_L5P_T0_AD13P_35': CDS_PINID='IO_L5P_T0_AD13P_35';
NODE_NAME     U24 V3
 '@TIMECARD_LIB.TIMECARD(SCH_1):PAGE163_I1@PLD.XC7A200T_2FBG484C_FBG484(CHIPS)':
 'IO_L6N_T0_VREF_34': CDS_PINID='IO_L6N_T0_VREF_34';
NODE_NAME     U24 E3
 '@TIMECARD_LIB.TIMECARD(SCH_1):PAGE163_I1@PLD.XC7A200T_2FBG484C_FBG484(CHIPS)':
 'IO_L6N_T0_VREF_35': CDS_PINID='IO_L6N_T0_VREF_35';
NODE_NAME     U24 U3
 '@TIMECARD_LIB.TIMECARD(SCH_1):PAGE163_I1@PLD.XC7A200T_2FBG484C_FBG484(CHIPS)':
 'IO_L6P_T0_34': CDS_PINID='IO_L6P_T0_34';
NODE_NAME     U24 F3
 '@TIMECARD_LIB.TIMECARD(SCH_1):PAGE163_I1@PLD.XC7A200T_2FBG484C_FBG484(CHIPS)':
 'IO_L6P_T0_35': CDS_PINID='IO_L6P_T0_35';
NODE_NAME     U24 AB1
 '@TIMECARD_LIB.TIMECARD(SCH_1):PAGE163_I1@PLD.XC7A200T_2FBG484C_FBG484(CHIPS)':
 'IO_L7N_T1_34': CDS_PINID='IO_L7N_T1_34';
NODE_NAME     U24 J1
 '@TIMECARD_LIB.TIMECARD(SCH_1):PAGE163_I1@PLD.XC7A200T_2FBG484C_FBG484(CHIPS)':
 'IO_L7N_T1_AD6N_35': CDS_PINID='IO_L7N_T1_AD6N_35';
NODE_NAME     U24 AA1
 '@TIMECARD_LIB.TIMECARD(SCH_1):PAGE163_I1@PLD.XC7A200T_2FBG484C_FBG484(CHIPS)':
 'IO_L7P_T1_34': CDS_PINID='IO_L7P_T1_34';
NODE_NAME     U24 K1
 '@TIMECARD_LIB.TIMECARD(SCH_1):PAGE163_I1@PLD.XC7A200T_2FBG484C_FBG484(CHIPS)':
 'IO_L7P_T1_AD6P_35': CDS_PINID='IO_L7P_T1_AD6P_35';
NODE_NAME     U24 G2
 '@TIMECARD_LIB.TIMECARD(SCH_1):PAGE163_I1@PLD.XC7A200T_2FBG484C_FBG484(CHIPS)':
 'IO_L8N_T1_AD14N_35': CDS_PINID='IO_L8N_T1_AD14N_35';
NODE_NAME     U24 H2
 '@TIMECARD_LIB.TIMECARD(SCH_1):PAGE163_I1@PLD.XC7A200T_2FBG484C_FBG484(CHIPS)':
 'IO_L8P_T1_AD14P_35': CDS_PINID='IO_L8P_T1_AD14P_35';
NODE_NAME     U24 AA3
 '@TIMECARD_LIB.TIMECARD(SCH_1):PAGE163_I1@PLD.XC7A200T_2FBG484C_FBG484(CHIPS)':
 'IO_L9N_T1_DQS_34': CDS_PINID='IO_L9N_T1_DQS_34';
NODE_NAME     U24 J2
 '@TIMECARD_LIB.TIMECARD(SCH_1):PAGE163_I1@PLD.XC7A200T_2FBG484C_FBG484(CHIPS)':
 'IO_L9N_T1_DQS_AD7N_35': CDS_PINID='IO_L9N_T1_DQS_AD7N_35';
NODE_NAME     U24 Y3
 '@TIMECARD_LIB.TIMECARD(SCH_1):PAGE163_I1@PLD.XC7A200T_2FBG484C_FBG484(CHIPS)':
 'IO_L9P_T1_DQS_34': CDS_PINID='IO_L9P_T1_DQS_34';
NODE_NAME     U24 K2
 '@TIMECARD_LIB.TIMECARD(SCH_1):PAGE163_I1@PLD.XC7A200T_2FBG484C_FBG484(CHIPS)':
 'IO_L9P_T1_DQS_AD7P_35': CDS_PINID='IO_L9P_T1_DQS_AD7P_35';
NODE_NAME     U24 H5
 '@TIMECARD_LIB.TIMECARD(SCH_1):PAGE163_I1@PLD.XC7A200T_2FBG484C_FBG484(CHIPS)':
 'IO_L10N_T1_AD15N_35': CDS_PINID='IO_L10N_T1_AD15N_35';
NODE_NAME     U24 J5
 '@TIMECARD_LIB.TIMECARD(SCH_1):PAGE163_I1@PLD.XC7A200T_2FBG484C_FBG484(CHIPS)':
 'IO_L10P_T1_AD15P_35': CDS_PINID='IO_L10P_T1_AD15P_35';
NODE_NAME     U24 AA4
 '@TIMECARD_LIB.TIMECARD(SCH_1):PAGE163_I1@PLD.XC7A200T_2FBG484C_FBG484(CHIPS)':
 'IO_L11N_T1_SRCC_34': CDS_PINID='IO_L11N_T1_SRCC_34';
NODE_NAME     U24 G3
 '@TIMECARD_LIB.TIMECARD(SCH_1):PAGE163_I1@PLD.XC7A200T_2FBG484C_FBG484(CHIPS)':
 'IO_L11N_T1_SRCC_35': CDS_PINID='IO_L11N_T1_SRCC_35';
NODE_NAME     U24 Y4
 '@TIMECARD_LIB.TIMECARD(SCH_1):PAGE163_I1@PLD.XC7A200T_2FBG484C_FBG484(CHIPS)':
 'IO_L11P_T1_SRCC_34': CDS_PINID='IO_L11P_T1_SRCC_34';
NODE_NAME     U24 H3
 '@TIMECARD_LIB.TIMECARD(SCH_1):PAGE163_I1@PLD.XC7A200T_2FBG484C_FBG484(CHIPS)':
 'IO_L11P_T1_SRCC_35': CDS_PINID='IO_L11P_T1_SRCC_35';
NODE_NAME     U24 W4
 '@TIMECARD_LIB.TIMECARD(SCH_1):PAGE163_I1@PLD.XC7A200T_2FBG484C_FBG484(CHIPS)':
 'IO_L12N_T1_MRCC_34': CDS_PINID='IO_L12N_T1_MRCC_34';
NODE_NAME     U24 G4
 '@TIMECARD_LIB.TIMECARD(SCH_1):PAGE163_I1@PLD.XC7A200T_2FBG484C_FBG484(CHIPS)':
 'IO_L12N_T1_MRCC_35': CDS_PINID='IO_L12N_T1_MRCC_35';
NODE_NAME     U24 V4
 '@TIMECARD_LIB.TIMECARD(SCH_1):PAGE163_I1@PLD.XC7A200T_2FBG484C_FBG484(CHIPS)':
 'IO_L12P_T1_MRCC_34': CDS_PINID='IO_L12P_T1_MRCC_34';
NODE_NAME     U24 H4
 '@TIMECARD_LIB.TIMECARD(SCH_1):PAGE163_I1@PLD.XC7A200T_2FBG484C_FBG484(CHIPS)':
 'IO_L12P_T1_MRCC_35': CDS_PINID='IO_L12P_T1_MRCC_35';
NODE_NAME     U24 J4
 '@TIMECARD_LIB.TIMECARD(SCH_1):PAGE163_I1@PLD.XC7A200T_2FBG484C_FBG484(CHIPS)':
 'IO_L13N_T2_MRCC_35': CDS_PINID='IO_L13N_T2_MRCC_35';
NODE_NAME     U24 K4
 '@TIMECARD_LIB.TIMECARD(SCH_1):PAGE163_I1@PLD.XC7A200T_2FBG484C_FBG484(CHIPS)':
 'IO_L13P_T2_MRCC_35': CDS_PINID='IO_L13P_T2_MRCC_35';
NODE_NAME     U24 U5
 '@TIMECARD_LIB.TIMECARD(SCH_1):PAGE163_I1@PLD.XC7A200T_2FBG484C_FBG484(CHIPS)':
 'IO_L14N_T2_SRCC_34': CDS_PINID='IO_L14N_T2_SRCC_34';
NODE_NAME     U24 K3
 '@TIMECARD_LIB.TIMECARD(SCH_1):PAGE163_I1@PLD.XC7A200T_2FBG484C_FBG484(CHIPS)':
 'IO_L14N_T2_SRCC_35': CDS_PINID='IO_L14N_T2_SRCC_35';
NODE_NAME     U24 T5
 '@TIMECARD_LIB.TIMECARD(SCH_1):PAGE163_I1@PLD.XC7A200T_2FBG484C_FBG484(CHIPS)':
 'IO_L14P_T2_SRCC_34': CDS_PINID='IO_L14P_T2_SRCC_34';
NODE_NAME     U24 L3
 '@TIMECARD_LIB.TIMECARD(SCH_1):PAGE163_I1@PLD.XC7A200T_2FBG484C_FBG484(CHIPS)':
 'IO_L14P_T2_SRCC_35': CDS_PINID='IO_L14P_T2_SRCC_35';
NODE_NAME     U24 W5
 '@TIMECARD_LIB.TIMECARD(SCH_1):PAGE163_I1@PLD.XC7A200T_2FBG484C_FBG484(CHIPS)':
 'IO_L15N_T2_DQS_34': CDS_PINID='IO_L15N_T2_DQS_34';
NODE_NAME     U24 L1
 '@TIMECARD_LIB.TIMECARD(SCH_1):PAGE163_I1@PLD.XC7A200T_2FBG484C_FBG484(CHIPS)':
 'IO_L15N_T2_DQS_35': CDS_PINID='IO_L15N_T2_DQS_35';
NODE_NAME     U24 W6
 '@TIMECARD_LIB.TIMECARD(SCH_1):PAGE163_I1@PLD.XC7A200T_2FBG484C_FBG484(CHIPS)':
 'IO_L15P_T2_DQS_34': CDS_PINID='IO_L15P_T2_DQS_34';
NODE_NAME     U24 M1
 '@TIMECARD_LIB.TIMECARD(SCH_1):PAGE163_I1@PLD.XC7A200T_2FBG484C_FBG484(CHIPS)':
 'IO_L15P_T2_DQS_35': CDS_PINID='IO_L15P_T2_DQS_35';
NODE_NAME     U24 V5
 '@TIMECARD_LIB.TIMECARD(SCH_1):PAGE163_I1@PLD.XC7A200T_2FBG484C_FBG484(CHIPS)':
 'IO_L16N_T2_34': CDS_PINID='IO_L16N_T2_34';
NODE_NAME     U24 M2
 '@TIMECARD_LIB.TIMECARD(SCH_1):PAGE163_I1@PLD.XC7A200T_2FBG484C_FBG484(CHIPS)':
 'IO_L16N_T2_35': CDS_PINID='IO_L16N_T2_35';
NODE_NAME     U24 U6
 '@TIMECARD_LIB.TIMECARD(SCH_1):PAGE163_I1@PLD.XC7A200T_2FBG484C_FBG484(CHIPS)':
 'IO_L16P_T2_34': CDS_PINID='IO_L16P_T2_34';
NODE_NAME     U24 M3
 '@TIMECARD_LIB.TIMECARD(SCH_1):PAGE163_I1@PLD.XC7A200T_2FBG484C_FBG484(CHIPS)':
 'IO_L16P_T2_35': CDS_PINID='IO_L16P_T2_35';
NODE_NAME     U24 T6
 '@TIMECARD_LIB.TIMECARD(SCH_1):PAGE163_I1@PLD.XC7A200T_2FBG484C_FBG484(CHIPS)':
 'IO_L17N_T2_34': CDS_PINID='IO_L17N_T2_34';
NODE_NAME     U24 J6
 '@TIMECARD_LIB.TIMECARD(SCH_1):PAGE163_I1@PLD.XC7A200T_2FBG484C_FBG484(CHIPS)':
 'IO_L17N_T2_35': CDS_PINID='IO_L17N_T2_35';
NODE_NAME     U24 R6
 '@TIMECARD_LIB.TIMECARD(SCH_1):PAGE163_I1@PLD.XC7A200T_2FBG484C_FBG484(CHIPS)':
 'IO_L17P_T2_34': CDS_PINID='IO_L17P_T2_34';
NODE_NAME     U24 K6
 '@TIMECARD_LIB.TIMECARD(SCH_1):PAGE163_I1@PLD.XC7A200T_2FBG484C_FBG484(CHIPS)':
 'IO_L17P_T2_35': CDS_PINID='IO_L17P_T2_35';
NODE_NAME     U24 AA6
 '@TIMECARD_LIB.TIMECARD(SCH_1):PAGE163_I1@PLD.XC7A200T_2FBG484C_FBG484(CHIPS)':
 'IO_L18N_T2_34': CDS_PINID='IO_L18N_T2_34';
NODE_NAME     U24 L4
 '@TIMECARD_LIB.TIMECARD(SCH_1):PAGE163_I1@PLD.XC7A200T_2FBG484C_FBG484(CHIPS)':
 'IO_L18N_T2_35': CDS_PINID='IO_L18N_T2_35';
NODE_NAME     U24 Y6
 '@TIMECARD_LIB.TIMECARD(SCH_1):PAGE163_I1@PLD.XC7A200T_2FBG484C_FBG484(CHIPS)':
 'IO_L18P_T2_34': CDS_PINID='IO_L18P_T2_34';
NODE_NAME     U24 L5
 '@TIMECARD_LIB.TIMECARD(SCH_1):PAGE163_I1@PLD.XC7A200T_2FBG484C_FBG484(CHIPS)':
 'IO_L18P_T2_35': CDS_PINID='IO_L18P_T2_35';
NODE_NAME     U24 W7
 '@TIMECARD_LIB.TIMECARD(SCH_1):PAGE163_I1@PLD.XC7A200T_2FBG484C_FBG484(CHIPS)':
 'IO_L19N_T3_VREF_34': CDS_PINID='IO_L19N_T3_VREF_34';
NODE_NAME     U24 N3
 '@TIMECARD_LIB.TIMECARD(SCH_1):PAGE163_I1@PLD.XC7A200T_2FBG484C_FBG484(CHIPS)':
 'IO_L19N_T3_VREF_35': CDS_PINID='IO_L19N_T3_VREF_35';
NODE_NAME     U24 V7
 '@TIMECARD_LIB.TIMECARD(SCH_1):PAGE163_I1@PLD.XC7A200T_2FBG484C_FBG484(CHIPS)':
 'IO_L19P_T3_34': CDS_PINID='IO_L19P_T3_34';
NODE_NAME     U24 N4
 '@TIMECARD_LIB.TIMECARD(SCH_1):PAGE163_I1@PLD.XC7A200T_2FBG484C_FBG484(CHIPS)':
 'IO_L19P_T3_35': CDS_PINID='IO_L19P_T3_35';
NODE_NAME     U25 8
 '@TIMECARD_LIB.TIMECARD(SCH_1):PAGE515_I151@ANALOG.ISL80101IRAJZ_DFN10(CHIPS)':
 'NC': CDS_PINID='NC';
NODE_NAME     Y3 2
 '@TIMECARD_LIB.TIMECARD(SCH_1):PAGE522_I144@CLOCK.OSC6P_V2(CHIPS)':
 'NC': CDS_PINID='NC';
NODE_NAME     Y4 2
 '@TIMECARD_LIB.TIMECARD(SCH_1):PAGE522_I145@CLOCK.OSC6P_V2(CHIPS)':
 'NC': CDS_PINID='NC';
NODE_NAME     U29 1
 '@TIMECARD_LIB.TIMECARD(SCH_1):PAGE9_I29@LSI.BNO080_LGA_28(CHIPS)':
 'RESV_NC_1': CDS_PINID='RESV_NC_1';
NODE_NAME     U29 7
 '@TIMECARD_LIB.TIMECARD(SCH_1):PAGE9_I29@LSI.BNO080_LGA_28(CHIPS)':
 'RESV_NC_2': CDS_PINID='RESV_NC_2';
NODE_NAME     U29 8
 '@TIMECARD_LIB.TIMECARD(SCH_1):PAGE9_I29@LSI.BNO080_LGA_28(CHIPS)':
 'RESV_NC_3': CDS_PINID='RESV_NC_3';
NODE_NAME     U29 12
 '@TIMECARD_LIB.TIMECARD(SCH_1):PAGE9_I29@LSI.BNO080_LGA_28(CHIPS)':
 'RESV_NC_4': CDS_PINID='RESV_NC_4';
NODE_NAME     U29 13
 '@TIMECARD_LIB.TIMECARD(SCH_1):PAGE9_I29@LSI.BNO080_LGA_28(CHIPS)':
 'RESV_NC_5': CDS_PINID='RESV_NC_5';
NODE_NAME     U29 21
 '@TIMECARD_LIB.TIMECARD(SCH_1):PAGE9_I29@LSI.BNO080_LGA_28(CHIPS)':
 'RESV_NC_6': CDS_PINID='RESV_NC_6';
NODE_NAME     U29 22
 '@TIMECARD_LIB.TIMECARD(SCH_1):PAGE9_I29@LSI.BNO080_LGA_28(CHIPS)':
 'RESV_NC_7': CDS_PINID='RESV_NC_7';
NODE_NAME     U29 23
 '@TIMECARD_LIB.TIMECARD(SCH_1):PAGE9_I29@LSI.BNO080_LGA_28(CHIPS)':
 'RESV_NC_8': CDS_PINID='RESV_NC_8';
NODE_NAME     U29 24
 '@TIMECARD_LIB.TIMECARD(SCH_1):PAGE9_I29@LSI.BNO080_LGA_28(CHIPS)':
 'RESV_NC_9': CDS_PINID='RESV_NC_9';
NODE_NAME     CR4 4
 '@TIMECARD_LIB.TIMECARD(SCH_1):PAGE12_I179@DISCRETE.DIODE_4_V1(CHIPS)':
 'VDD': CDS_PINID='VDD';
NODE_NAME     J14 6
 '@TIMECARD_LIB.TIMECARD(SCH_1):PAGE127_I427@CONNECTOR.G200_10283_01(CHIPS)':
 '6': CDS_PINID='\6\';
NODE_NAME     J14 7
 '@TIMECARD_LIB.TIMECARD(SCH_1):PAGE127_I427@CONNECTOR.G200_10283_01(CHIPS)':
 '7': CDS_PINID='\7\';
NODE_NAME     J14 8
 '@TIMECARD_LIB.TIMECARD(SCH_1):PAGE127_I427@CONNECTOR.G200_10283_01(CHIPS)':
 '8': CDS_PINID='\8\';
NODE_NAME     CR7 4
 '@TIMECARD_LIB.TIMECARD(SCH_1):PAGE127_I442@DISCRETE.DIODE_4_V1(CHIPS)':
 'VDD': CDS_PINID='VDD';
NODE_NAME     CR6 4
 '@TIMECARD_LIB.TIMECARD(SCH_1):PAGE127_I443@DISCRETE.DIODE_4_V1(CHIPS)':
 'VDD': CDS_PINID='VDD';
NODE_NAME     U33 26
 '@TIMECARD_LIB.TIMECARD(SCH_1):PAGE14_I219@INTERFACE.IS32FL3207_QWLA3_TR_QFN29(CHIPS)':
 'OUT16': CDS_PINID='OUT16';
NODE_NAME     U33 27
 '@TIMECARD_LIB.TIMECARD(SCH_1):PAGE14_I219@INTERFACE.IS32FL3207_QWLA3_TR_QFN29(CHIPS)':
 'OUT17': CDS_PINID='OUT17';
NODE_NAME     U33 28
 '@TIMECARD_LIB.TIMECARD(SCH_1):PAGE14_I219@INTERFACE.IS32FL3207_QWLA3_TR_QFN29(CHIPS)':
 'OUT18': CDS_PINID='OUT18';
NODE_NAME     U3 1
 '@TIMECARD_LIB.TIMECARD(SCH_1):PAGE3_I134@STDLOGIC.74LVC1G07_SC70_5(CHIPS)':
 'NC': CDS_PINID='NC';
NODE_NAME     U17 1
 '@TIMECARD_LIB.TIMECARD(SCH_1):PAGE524_I3@OTHER.CL1001485A(CHIPS)':
 '1': CDS_PINID='\1\';
NODE_NAME     U17 3
 '@TIMECARD_LIB.TIMECARD(SCH_1):PAGE524_I3@OTHER.CL1001485A(CHIPS)':
 '3': CDS_PINID='\3\';
NODE_NAME     U18 40
 '@TIMECARD_LIB.TIMECARD(SCH_1):PAGE524_I64@INTERFACE.FT4232HL_REEL_QFP64(CHIPS)':
 'CDBUS2': CDS_PINID='CDBUS2';
NODE_NAME     U18 41
 '@TIMECARD_LIB.TIMECARD(SCH_1):PAGE524_I64@INTERFACE.FT4232HL_REEL_QFP64(CHIPS)':
 'CDBUS3': CDS_PINID='CDBUS3';
NODE_NAME     U18 43
 '@TIMECARD_LIB.TIMECARD(SCH_1):PAGE524_I64@INTERFACE.FT4232HL_REEL_QFP64(CHIPS)':
 'CDBUS4': CDS_PINID='CDBUS4';
NODE_NAME     U18 44
 '@TIMECARD_LIB.TIMECARD(SCH_1):PAGE524_I64@INTERFACE.FT4232HL_REEL_QFP64(CHIPS)':
 'CDBUS5': CDS_PINID='CDBUS5';
NODE_NAME     U18 45
 '@TIMECARD_LIB.TIMECARD(SCH_1):PAGE524_I64@INTERFACE.FT4232HL_REEL_QFP64(CHIPS)':
 'CDBUS6': CDS_PINID='CDBUS6';
NODE_NAME     U18 46
 '@TIMECARD_LIB.TIMECARD(SCH_1):PAGE524_I64@INTERFACE.FT4232HL_REEL_QFP64(CHIPS)':
 'CDBUS7': CDS_PINID='CDBUS7';
NODE_NAME     U18 53
 '@TIMECARD_LIB.TIMECARD(SCH_1):PAGE524_I64@INTERFACE.FT4232HL_REEL_QFP64(CHIPS)':
 'DDBUS2': CDS_PINID='DDBUS2';
NODE_NAME     U18 54
 '@TIMECARD_LIB.TIMECARD(SCH_1):PAGE524_I64@INTERFACE.FT4232HL_REEL_QFP64(CHIPS)':
 'DDBUS3': CDS_PINID='DDBUS3';
NODE_NAME     U18 55
 '@TIMECARD_LIB.TIMECARD(SCH_1):PAGE524_I64@INTERFACE.FT4232HL_REEL_QFP64(CHIPS)':
 'DDBUS4': CDS_PINID='DDBUS4';
NODE_NAME     U18 57
 '@TIMECARD_LIB.TIMECARD(SCH_1):PAGE524_I64@INTERFACE.FT4232HL_REEL_QFP64(CHIPS)':
 'DDBUS5': CDS_PINID='DDBUS5';
NODE_NAME     U18 58
 '@TIMECARD_LIB.TIMECARD(SCH_1):PAGE524_I64@INTERFACE.FT4232HL_REEL_QFP64(CHIPS)':
 'DDBUS6': CDS_PINID='DDBUS6';
NODE_NAME     U18 59
 '@TIMECARD_LIB.TIMECARD(SCH_1):PAGE524_I64@INTERFACE.FT4232HL_REEL_QFP64(CHIPS)':
 'DDBUS7': CDS_PINID='DDBUS7';
NODE_NAME     U18 60
 '@TIMECARD_LIB.TIMECARD(SCH_1):PAGE524_I64@INTERFACE.FT4232HL_REEL_QFP64(CHIPS)':
 'PWREN*': CDS_PINID='\pwren*\';
NODE_NAME     U18 36
 '@TIMECARD_LIB.TIMECARD(SCH_1):PAGE524_I64@INTERFACE.FT4232HL_REEL_QFP64(CHIPS)':
 'SUSPEND*': CDS_PINID='\suspend*\';
NODE_NAME     U31 7
 '@TIMECARD_LIB.TIMECARD(SCH_1):PAGE524_I200@MEMORY.CAT93C46VI_GT3_SOIC8(CHIPS)':
 'NC': CDS_PINID='NC';
NODE_NAME     U41 8
 '@TIMECARD_LIB.TIMECARD(SCH_1):PAGE525_I29@ANALOG.ISL80101IRAJZ_DFN10(CHIPS)':
 'NC': CDS_PINID='NC';
NODE_NAME     J11 4
 '@TIMECARD_LIB.TIMECARD(SCH_1):PAGE527_I2@CONNECTOR.CONN_USB_1X5_G2_GH4_F_RA_SMT(CHIPS)':
 '4': CDS_PINID='\4\';
NODE_NAME     U9 1
 '@TIMECARD_LIB.TIMECARD(SCH_1):PAGE527_I4@OTHER.CL1001485A(CHIPS)':
 '1': CDS_PINID='\1\';
NODE_NAME     U9 3
 '@TIMECARD_LIB.TIMECARD(SCH_1):PAGE527_I4@OTHER.CL1001485A(CHIPS)':
 '3': CDS_PINID='\3\';
NODE_NAME     U11 8
 '@TIMECARD_LIB.TIMECARD(SCH_1):PAGE527_I108@STDLOGIC.TS3USB3031RMGR_WQFN12(CHIPS)':
 'MHL_N': CDS_PINID='MHL_N';
NODE_NAME     U11 7
 '@TIMECARD_LIB.TIMECARD(SCH_1):PAGE527_I108@STDLOGIC.TS3USB3031RMGR_WQFN12(CHIPS)':
 'MHL_P': CDS_PINID='MHL_P';
NODE_NAME     P1 10
 '@TIMECARD_LIB.TIMECARD(SCH_1):PAGE527_I193@CONNECTOR.CONN_HDR_2X10_M_S_SMT(CHIPS)':
 '10': CDS_PINID='\10\';
NODE_NAME     P1 11
 '@TIMECARD_LIB.TIMECARD(SCH_1):PAGE527_I193@CONNECTOR.CONN_HDR_2X10_M_S_SMT(CHIPS)':
 '11': CDS_PINID='\11\';
NODE_NAME     P1 12
 '@TIMECARD_LIB.TIMECARD(SCH_1):PAGE527_I193@CONNECTOR.CONN_HDR_2X10_M_S_SMT(CHIPS)':
 '12': CDS_PINID='\12\';
NODE_NAME     P1 13
 '@TIMECARD_LIB.TIMECARD(SCH_1):PAGE527_I193@CONNECTOR.CONN_HDR_2X10_M_S_SMT(CHIPS)':
 '13': CDS_PINID='\13\';
NODE_NAME     P1 14
 '@TIMECARD_LIB.TIMECARD(SCH_1):PAGE527_I193@CONNECTOR.CONN_HDR_2X10_M_S_SMT(CHIPS)':
 '14': CDS_PINID='\14\';
NODE_NAME     P1 16
 '@TIMECARD_LIB.TIMECARD(SCH_1):PAGE527_I193@CONNECTOR.CONN_HDR_2X10_M_S_SMT(CHIPS)':
 '16': CDS_PINID='\16\';
NODE_NAME     P1 18
 '@TIMECARD_LIB.TIMECARD(SCH_1):PAGE527_I193@CONNECTOR.CONN_HDR_2X10_M_S_SMT(CHIPS)':
 '18': CDS_PINID='\18\';
NODE_NAME     U39 1
 '@TIMECARD_LIB.TIMECARD(SCH_1):PAGE524_I407@INTERFACE.NLASB3157DFT2G_SC88(CHIPS)':
 'B1': CDS_PINID='B1';
NODE_NAME     U40 1
 '@TIMECARD_LIB.TIMECARD(SCH_1):PAGE524_I408@INTERFACE.NLASB3157DFT2G_SC88(CHIPS)':
 'B1': CDS_PINID='B1';
NODE_NAME     SP4 1
 '@TIMECARD_LIB.TIMECARD(SCH_1):PAGE33_I130@MECH.SOLDER_PREFORM(CHIPS)':
 '1': CDS_PINID='\1\';
NODE_NAME     SP4 2
 '@TIMECARD_LIB.TIMECARD(SCH_1):PAGE33_I130@MECH.SOLDER_PREFORM(CHIPS)':
 '2': CDS_PINID='\2\';
NODE_NAME     SP5 1
 '@TIMECARD_LIB.TIMECARD(SCH_1):PAGE33_I131@MECH.SOLDER_PREFORM(CHIPS)':
 '1': CDS_PINID='\1\';
NODE_NAME     SP5 2
 '@TIMECARD_LIB.TIMECARD(SCH_1):PAGE33_I131@MECH.SOLDER_PREFORM(CHIPS)':
 '2': CDS_PINID='\2\';
NODE_NAME     SP7 1
 '@TIMECARD_LIB.TIMECARD(SCH_1):PAGE33_I132@MECH.SOLDER_PREFORM(CHIPS)':
 '1': CDS_PINID='\1\';
NODE_NAME     SP7 2
 '@TIMECARD_LIB.TIMECARD(SCH_1):PAGE33_I132@MECH.SOLDER_PREFORM(CHIPS)':
 '2': CDS_PINID='\2\';
NODE_NAME     SP6 1
 '@TIMECARD_LIB.TIMECARD(SCH_1):PAGE33_I133@MECH.SOLDER_PREFORM(CHIPS)':
 '1': CDS_PINID='\1\';
NODE_NAME     SP6 2
 '@TIMECARD_LIB.TIMECARD(SCH_1):PAGE33_I133@MECH.SOLDER_PREFORM(CHIPS)':
 '2': CDS_PINID='\2\';
NODE_NAME     SP8 1
 '@TIMECARD_LIB.TIMECARD(SCH_1):PAGE33_I134@MECH.SOLDER_PREFORM(CHIPS)':
 '1': CDS_PINID='\1\';
NODE_NAME     SP8 2
 '@TIMECARD_LIB.TIMECARD(SCH_1):PAGE33_I134@MECH.SOLDER_PREFORM(CHIPS)':
 '2': CDS_PINID='\2\';
NODE_NAME     SP9 1
 '@TIMECARD_LIB.TIMECARD(SCH_1):PAGE33_I135@MECH.SOLDER_PREFORM(CHIPS)':
 '1': CDS_PINID='\1\';
NODE_NAME     SP9 2
 '@TIMECARD_LIB.TIMECARD(SCH_1):PAGE33_I135@MECH.SOLDER_PREFORM(CHIPS)':
 '2': CDS_PINID='\2\';
NODE_NAME     SP11 1
 '@TIMECARD_LIB.TIMECARD(SCH_1):PAGE33_I136@MECH.SOLDER_PREFORM(CHIPS)':
 '1': CDS_PINID='\1\';
NODE_NAME     SP11 2
 '@TIMECARD_LIB.TIMECARD(SCH_1):PAGE33_I136@MECH.SOLDER_PREFORM(CHIPS)':
 '2': CDS_PINID='\2\';
NODE_NAME     SP10 1
 '@TIMECARD_LIB.TIMECARD(SCH_1):PAGE33_I137@MECH.SOLDER_PREFORM(CHIPS)':
 '1': CDS_PINID='\1\';
NODE_NAME     SP10 2
 '@TIMECARD_LIB.TIMECARD(SCH_1):PAGE33_I137@MECH.SOLDER_PREFORM(CHIPS)':
 '2': CDS_PINID='\2\';
NODE_NAME     SP15 1
 '@TIMECARD_LIB.TIMECARD(SCH_1):PAGE33_I138@MECH.SOLDER_PREFORM(CHIPS)':
 '1': CDS_PINID='\1\';
NODE_NAME     SP15 2
 '@TIMECARD_LIB.TIMECARD(SCH_1):PAGE33_I138@MECH.SOLDER_PREFORM(CHIPS)':
 '2': CDS_PINID='\2\';
NODE_NAME     SP14 1
 '@TIMECARD_LIB.TIMECARD(SCH_1):PAGE33_I139@MECH.SOLDER_PREFORM(CHIPS)':
 '1': CDS_PINID='\1\';
NODE_NAME     SP14 2
 '@TIMECARD_LIB.TIMECARD(SCH_1):PAGE33_I139@MECH.SOLDER_PREFORM(CHIPS)':
 '2': CDS_PINID='\2\';
NODE_NAME     SP13 1
 '@TIMECARD_LIB.TIMECARD(SCH_1):PAGE33_I140@MECH.SOLDER_PREFORM(CHIPS)':
 '1': CDS_PINID='\1\';
NODE_NAME     SP13 2
 '@TIMECARD_LIB.TIMECARD(SCH_1):PAGE33_I140@MECH.SOLDER_PREFORM(CHIPS)':
 '2': CDS_PINID='\2\';
NODE_NAME     SP12 1
 '@TIMECARD_LIB.TIMECARD(SCH_1):PAGE33_I141@MECH.SOLDER_PREFORM(CHIPS)':
 '1': CDS_PINID='\1\';
NODE_NAME     SP12 2
 '@TIMECARD_LIB.TIMECARD(SCH_1):PAGE33_I141@MECH.SOLDER_PREFORM(CHIPS)':
 '2': CDS_PINID='\2\';
NODE_NAME     SP17 1
 '@TIMECARD_LIB.TIMECARD(SCH_1):PAGE33_I142@MECH.SOLDER_PREFORM(CHIPS)':
 '1': CDS_PINID='\1\';
NODE_NAME     SP17 2
 '@TIMECARD_LIB.TIMECARD(SCH_1):PAGE33_I142@MECH.SOLDER_PREFORM(CHIPS)':
 '2': CDS_PINID='\2\';
NODE_NAME     SP27 1
 '@TIMECARD_LIB.TIMECARD(SCH_1):PAGE33_I143@MECH.SOLDER_PREFORM(CHIPS)':
 '1': CDS_PINID='\1\';
NODE_NAME     SP27 2
 '@TIMECARD_LIB.TIMECARD(SCH_1):PAGE33_I143@MECH.SOLDER_PREFORM(CHIPS)':
 '2': CDS_PINID='\2\';
NODE_NAME     SP26 1
 '@TIMECARD_LIB.TIMECARD(SCH_1):PAGE33_I144@MECH.SOLDER_PREFORM(CHIPS)':
 '1': CDS_PINID='\1\';
NODE_NAME     SP26 2
 '@TIMECARD_LIB.TIMECARD(SCH_1):PAGE33_I144@MECH.SOLDER_PREFORM(CHIPS)':
 '2': CDS_PINID='\2\';
NODE_NAME     SP25 1
 '@TIMECARD_LIB.TIMECARD(SCH_1):PAGE33_I145@MECH.SOLDER_PREFORM(CHIPS)':
 '1': CDS_PINID='\1\';
NODE_NAME     SP25 2
 '@TIMECARD_LIB.TIMECARD(SCH_1):PAGE33_I145@MECH.SOLDER_PREFORM(CHIPS)':
 '2': CDS_PINID='\2\';
NODE_NAME     SP24 1
 '@TIMECARD_LIB.TIMECARD(SCH_1):PAGE33_I146@MECH.SOLDER_PREFORM(CHIPS)':
 '1': CDS_PINID='\1\';
NODE_NAME     SP24 2
 '@TIMECARD_LIB.TIMECARD(SCH_1):PAGE33_I146@MECH.SOLDER_PREFORM(CHIPS)':
 '2': CDS_PINID='\2\';
NODE_NAME     SP23 1
 '@TIMECARD_LIB.TIMECARD(SCH_1):PAGE33_I147@MECH.SOLDER_PREFORM(CHIPS)':
 '1': CDS_PINID='\1\';
NODE_NAME     SP23 2
 '@TIMECARD_LIB.TIMECARD(SCH_1):PAGE33_I147@MECH.SOLDER_PREFORM(CHIPS)':
 '2': CDS_PINID='\2\';
NODE_NAME     SP22 1
 '@TIMECARD_LIB.TIMECARD(SCH_1):PAGE33_I148@MECH.SOLDER_PREFORM(CHIPS)':
 '1': CDS_PINID='\1\';
NODE_NAME     SP22 2
 '@TIMECARD_LIB.TIMECARD(SCH_1):PAGE33_I148@MECH.SOLDER_PREFORM(CHIPS)':
 '2': CDS_PINID='\2\';
NODE_NAME     SP20 1
 '@TIMECARD_LIB.TIMECARD(SCH_1):PAGE33_I149@MECH.SOLDER_PREFORM(CHIPS)':
 '1': CDS_PINID='\1\';
NODE_NAME     SP20 2
 '@TIMECARD_LIB.TIMECARD(SCH_1):PAGE33_I149@MECH.SOLDER_PREFORM(CHIPS)':
 '2': CDS_PINID='\2\';
NODE_NAME     SP21 1
 '@TIMECARD_LIB.TIMECARD(SCH_1):PAGE33_I150@MECH.SOLDER_PREFORM(CHIPS)':
 '1': CDS_PINID='\1\';
NODE_NAME     SP21 2
 '@TIMECARD_LIB.TIMECARD(SCH_1):PAGE33_I150@MECH.SOLDER_PREFORM(CHIPS)':
 '2': CDS_PINID='\2\';
NODE_NAME     SP19 1
 '@TIMECARD_LIB.TIMECARD(SCH_1):PAGE33_I151@MECH.SOLDER_PREFORM(CHIPS)':
 '1': CDS_PINID='\1\';
NODE_NAME     SP19 2
 '@TIMECARD_LIB.TIMECARD(SCH_1):PAGE33_I151@MECH.SOLDER_PREFORM(CHIPS)':
 '2': CDS_PINID='\2\';
NODE_NAME     SP18 1
 '@TIMECARD_LIB.TIMECARD(SCH_1):PAGE33_I152@MECH.SOLDER_PREFORM(CHIPS)':
 '1': CDS_PINID='\1\';
NODE_NAME     SP18 2
 '@TIMECARD_LIB.TIMECARD(SCH_1):PAGE33_I152@MECH.SOLDER_PREFORM(CHIPS)':
 '2': CDS_PINID='\2\';
NODE_NAME     SP16 1
 '@TIMECARD_LIB.TIMECARD(SCH_1):PAGE33_I153@MECH.SOLDER_PREFORM(CHIPS)':
 '1': CDS_PINID='\1\';
NODE_NAME     SP16 2
 '@TIMECARD_LIB.TIMECARD(SCH_1):PAGE33_I153@MECH.SOLDER_PREFORM(CHIPS)':
 '2': CDS_PINID='\2\';
NODE_NAME     SP41 1
 '@TIMECARD_LIB.TIMECARD(SCH_1):PAGE33_I155@MECH.SOLDER_PREFORM(CHIPS)':
 '1': CDS_PINID='\1\';
NODE_NAME     SP41 2
 '@TIMECARD_LIB.TIMECARD(SCH_1):PAGE33_I155@MECH.SOLDER_PREFORM(CHIPS)':
 '2': CDS_PINID='\2\';
NODE_NAME     SP38 1
 '@TIMECARD_LIB.TIMECARD(SCH_1):PAGE33_I159@MECH.SOLDER_PREFORM(CHIPS)':
 '1': CDS_PINID='\1\';
NODE_NAME     SP38 2
 '@TIMECARD_LIB.TIMECARD(SCH_1):PAGE33_I159@MECH.SOLDER_PREFORM(CHIPS)':
 '2': CDS_PINID='\2\';
NODE_NAME     SP37 1
 '@TIMECARD_LIB.TIMECARD(SCH_1):PAGE33_I161@MECH.SOLDER_PREFORM(CHIPS)':
 '1': CDS_PINID='\1\';
NODE_NAME     SP37 2
 '@TIMECARD_LIB.TIMECARD(SCH_1):PAGE33_I161@MECH.SOLDER_PREFORM(CHIPS)':
 '2': CDS_PINID='\2\';
NODE_NAME     SP36 1
 '@TIMECARD_LIB.TIMECARD(SCH_1):PAGE33_I163@MECH.SOLDER_PREFORM(CHIPS)':
 '1': CDS_PINID='\1\';
NODE_NAME     SP36 2
 '@TIMECARD_LIB.TIMECARD(SCH_1):PAGE33_I163@MECH.SOLDER_PREFORM(CHIPS)':
 '2': CDS_PINID='\2\';
NODE_NAME     SP35 1
 '@TIMECARD_LIB.TIMECARD(SCH_1):PAGE33_I165@MECH.SOLDER_PREFORM(CHIPS)':
 '1': CDS_PINID='\1\';
NODE_NAME     SP35 2
 '@TIMECARD_LIB.TIMECARD(SCH_1):PAGE33_I165@MECH.SOLDER_PREFORM(CHIPS)':
 '2': CDS_PINID='\2\';
NODE_NAME     SP34 1
 '@TIMECARD_LIB.TIMECARD(SCH_1):PAGE33_I167@MECH.SOLDER_PREFORM(CHIPS)':
 '1': CDS_PINID='\1\';
NODE_NAME     SP34 2
 '@TIMECARD_LIB.TIMECARD(SCH_1):PAGE33_I167@MECH.SOLDER_PREFORM(CHIPS)':
 '2': CDS_PINID='\2\';
NODE_NAME     SP33 1
 '@TIMECARD_LIB.TIMECARD(SCH_1):PAGE33_I169@MECH.SOLDER_PREFORM(CHIPS)':
 '1': CDS_PINID='\1\';
NODE_NAME     SP33 2
 '@TIMECARD_LIB.TIMECARD(SCH_1):PAGE33_I169@MECH.SOLDER_PREFORM(CHIPS)':
 '2': CDS_PINID='\2\';
NODE_NAME     SP32 1
 '@TIMECARD_LIB.TIMECARD(SCH_1):PAGE33_I171@MECH.SOLDER_PREFORM(CHIPS)':
 '1': CDS_PINID='\1\';
NODE_NAME     SP32 2
 '@TIMECARD_LIB.TIMECARD(SCH_1):PAGE33_I171@MECH.SOLDER_PREFORM(CHIPS)':
 '2': CDS_PINID='\2\';
NODE_NAME     SP31 1
 '@TIMECARD_LIB.TIMECARD(SCH_1):PAGE33_I172@MECH.SOLDER_PREFORM(CHIPS)':
 '1': CDS_PINID='\1\';
NODE_NAME     SP31 2
 '@TIMECARD_LIB.TIMECARD(SCH_1):PAGE33_I172@MECH.SOLDER_PREFORM(CHIPS)':
 '2': CDS_PINID='\2\';
NODE_NAME     SP30 1
 '@TIMECARD_LIB.TIMECARD(SCH_1):PAGE33_I173@MECH.SOLDER_PREFORM(CHIPS)':
 '1': CDS_PINID='\1\';
NODE_NAME     SP30 2
 '@TIMECARD_LIB.TIMECARD(SCH_1):PAGE33_I173@MECH.SOLDER_PREFORM(CHIPS)':
 '2': CDS_PINID='\2\';
NODE_NAME     SP29 1
 '@TIMECARD_LIB.TIMECARD(SCH_1):PAGE33_I174@MECH.SOLDER_PREFORM(CHIPS)':
 '1': CDS_PINID='\1\';
NODE_NAME     SP29 2
 '@TIMECARD_LIB.TIMECARD(SCH_1):PAGE33_I174@MECH.SOLDER_PREFORM(CHIPS)':
 '2': CDS_PINID='\2\';
NODE_NAME     SP28 1
 '@TIMECARD_LIB.TIMECARD(SCH_1):PAGE33_I175@MECH.SOLDER_PREFORM(CHIPS)':
 '1': CDS_PINID='\1\';
NODE_NAME     SP28 2
 '@TIMECARD_LIB.TIMECARD(SCH_1):PAGE33_I175@MECH.SOLDER_PREFORM(CHIPS)':
 '2': CDS_PINID='\2\';
NODE_NAME     SP40 1
 '@TIMECARD_LIB.TIMECARD(SCH_1):PAGE33_I176@MECH.SOLDER_PREFORM(CHIPS)':
 '1': CDS_PINID='\1\';
NODE_NAME     SP40 2
 '@TIMECARD_LIB.TIMECARD(SCH_1):PAGE33_I176@MECH.SOLDER_PREFORM(CHIPS)':
 '2': CDS_PINID='\2\';
NODE_NAME     SP39 1
 '@TIMECARD_LIB.TIMECARD(SCH_1):PAGE33_I177@MECH.SOLDER_PREFORM(CHIPS)':
 '1': CDS_PINID='\1\';
NODE_NAME     SP39 2
 '@TIMECARD_LIB.TIMECARD(SCH_1):PAGE33_I177@MECH.SOLDER_PREFORM(CHIPS)':
 '2': CDS_PINID='\2\';
NET_NAME
'OSC_125M_CLKN'
 '@TIMECARD_LIB.TIMECARD(SCH_1):OSC_125M_CLKN':
 C_SIGNAL='@timecard_lib.timecard(sch_1):osc_125m_clkn';
NODE_NAME     C254 1
 '@TIMECARD_LIB.TIMECARD(SCH_1):PAGE522_I142@PASSIVE.CAPACITOR(CHIPS)':
 '1': CDS_PINID='\1\';
NODE_NAME     Y4 5
 '@TIMECARD_LIB.TIMECARD(SCH_1):PAGE522_I145@CLOCK.OSC6P_V2(CHIPS)':
 'OUT_N': CDS_PINID='OUT_N';
NODE_NAME     R240 1
 '@TIMECARD_LIB.TIMECARD(SCH_1):PAGE522_I172@PASSIVE.RESISTOR(CHIPS)':
 '1': CDS_PINID='\1\';
NET_NAME
'OSC_125M_CLKP'
 '@TIMECARD_LIB.TIMECARD(SCH_1):OSC_125M_CLKP':
 C_SIGNAL='@timecard_lib.timecard(sch_1):osc_125m_clkp';
NODE_NAME     C253 1
 '@TIMECARD_LIB.TIMECARD(SCH_1):PAGE522_I143@PASSIVE.CAPACITOR(CHIPS)':
 '1': CDS_PINID='\1\';
NODE_NAME     Y4 4
 '@TIMECARD_LIB.TIMECARD(SCH_1):PAGE522_I145@CLOCK.OSC6P_V2(CHIPS)':
 'OUT_P': CDS_PINID='OUT_P';
NODE_NAME     R242 1
 '@TIMECARD_LIB.TIMECARD(SCH_1):PAGE522_I174@PASSIVE.RESISTOR(CHIPS)':
 '1': CDS_PINID='\1\';
NET_NAME
'OSC_200M_CLKN'
 '@TIMECARD_LIB.TIMECARD(SCH_1):OSC_200M_CLKN':
 C_SIGNAL='@timecard_lib.timecard(sch_1):osc_200m_clkn';
NODE_NAME     Y3 5
 '@TIMECARD_LIB.TIMECARD(SCH_1):PAGE522_I144@CLOCK.OSC6P_V2(CHIPS)':
 'OUT_N': CDS_PINID='OUT_N';
NODE_NAME     C252 1
 '@TIMECARD_LIB.TIMECARD(SCH_1):PAGE522_I160@PASSIVE.CAPACITOR(CHIPS)':
 '1': CDS_PINID='\1\';
NODE_NAME     R239 1
 '@TIMECARD_LIB.TIMECARD(SCH_1):PAGE522_I169@PASSIVE.RESISTOR(CHIPS)':
 '1': CDS_PINID='\1\';
NET_NAME
'OSC_200M_CLKP'
 '@TIMECARD_LIB.TIMECARD(SCH_1):OSC_200M_CLKP':
 C_SIGNAL='@timecard_lib.timecard(sch_1):osc_200m_clkp';
NODE_NAME     Y3 4
 '@TIMECARD_LIB.TIMECARD(SCH_1):PAGE522_I144@CLOCK.OSC6P_V2(CHIPS)':
 'OUT_P': CDS_PINID='OUT_P';
NODE_NAME     C251 1
 '@TIMECARD_LIB.TIMECARD(SCH_1):PAGE522_I161@PASSIVE.CAPACITOR(CHIPS)':
 '1': CDS_PINID='\1\';
NODE_NAME     R241 1
 '@TIMECARD_LIB.TIMECARD(SCH_1):PAGE522_I170@PASSIVE.RESISTOR(CHIPS)':
 '1': CDS_PINID='\1\';
NET_NAME
'PCA9546_I2C_SCL'
 '@TIMECARD_LIB.TIMECARD(SCH_1):PCA9546_I2C_SCL':
 C_SIGNAL='@timecard_lib.timecard(sch_1):pca9546_i2c_scl';
NODE_NAME     R145 1
 '@TIMECARD_LIB.TIMECARD(SCH_1):PAGE5_I67@PASSIVE.RESISTOR(CHIPS)':
 '1': CDS_PINID='\1\';
NODE_NAME     U37 7
 '@TIMECARD_LIB.TIMECARD(SCH_1):PAGE524_I448@STDLOGIC.TS3A5018PWR_TSSOP16(CHIPS)':
 'COM2': CDS_PINID='COM2';
NET_NAME
'PCA9546_I2C_SDA'
 '@TIMECARD_LIB.TIMECARD(SCH_1):PCA9546_I2C_SDA':
 C_SIGNAL='@timecard_lib.timecard(sch_1):pca9546_i2c_sda';
NODE_NAME     R144 1
 '@TIMECARD_LIB.TIMECARD(SCH_1):PAGE5_I68@PASSIVE.RESISTOR(CHIPS)':
 '1': CDS_PINID='\1\';
NODE_NAME     U37 4
 '@TIMECARD_LIB.TIMECARD(SCH_1):PAGE524_I448@STDLOGIC.TS3A5018PWR_TSSOP16(CHIPS)':
 'COM1': CDS_PINID='COM1';
NET_NAME
'PCA9546_RST_N'
 '@TIMECARD_LIB.TIMECARD(SCH_1):PCA9546_RST_N':
 C_SIGNAL='@timecard_lib.timecard(sch_1):pca9546_rst_n';
NODE_NAME     U4 3
 '@TIMECARD_LIB.TIMECARD(SCH_1):PAGE5_I33@INTERFACE.PCA9546APW_TSSOP16(CHIPS)':
 'RESET*': CDS_PINID='\reset*\';
NODE_NAME     R146 2
 '@TIMECARD_LIB.TIMECARD(SCH_1):PAGE5_I60@PASSIVE.RESISTOR(CHIPS)':
 '2': CDS_PINID='\2\';
NODE_NAME     R155 2
 '@TIMECARD_LIB.TIMECARD(SCH_1):PAGE5_I66@PASSIVE.RESISTOR(CHIPS)':
 '2': CDS_PINID='\2\';
NODE_NAME     R60 2
 '@TIMECARD_LIB.TIMECARD(SCH_1):PAGE5_I125@PASSIVE.RESISTOR(CHIPS)':
 '2': CDS_PINID='\2\';
NODE_NAME     TP21 1
 '@TIMECARD_LIB.TIMECARD(SCH_1):PAGE16_I1645@CLS.TP_PIONT(CHIPS)':
 '1': CDS_PINID='\1\';
NET_NAME
'PCIE_CONN_PERST_N'
 '@TIMECARD_LIB.TIMECARD(SCH_1):PCIE_CONN_PERST_N':
 C_SIGNAL='@timecard_lib.timecard(sch_1):pcie_conn_perst_n';
NODE_NAME     GF1 A11
 '@TIMECARD_LIB.TIMECARD(SCH_1):PAGE3_I61@CONNECTOR.CONN_64P_GF(CHIPS)':
 'PERST*': CDS_PINID='\perst*\';
NODE_NAME     R55 1
 '@TIMECARD_LIB.TIMECARD(SCH_1):PAGE3_I62@PASSIVE.RESISTOR(CHIPS)':
 '1': CDS_PINID='\1\';
NODE_NAME     R56 2
 '@TIMECARD_LIB.TIMECARD(SCH_1):PAGE3_I63@PASSIVE.RESISTOR(CHIPS)':
 '2': CDS_PINID='\2\';
NODE_NAME     U3 2
 '@TIMECARD_LIB.TIMECARD(SCH_1):PAGE3_I134@STDLOGIC.74LVC1G07_SC70_5(CHIPS)':
 'A': CDS_PINID='A';
NODE_NAME     TP48 1
 '@TIMECARD_LIB.TIMECARD(SCH_1):PAGE16_I1695@CLS.TP_PIONT(CHIPS)':
 '1': CDS_PINID='\1\';
NET_NAME
'PCIE_CONN_SMCLK'
 '@TIMECARD_LIB.TIMECARD(SCH_1):PCIE_CONN_SMCLK':
 C_SIGNAL='@timecard_lib.timecard(sch_1):pcie_conn_smclk';
NODE_NAME     GF1 B5
 '@TIMECARD_LIB.TIMECARD(SCH_1):PAGE3_I61@CONNECTOR.CONN_64P_GF(CHIPS)':
 'SMCLK': CDS_PINID='SMCLK';
NODE_NAME     U2 3
 '@TIMECARD_LIB.TIMECARD(SCH_1):PAGE3_I100@STDLOGIC.G220_10198_01(CHIPS)':
 'SCLIN': CDS_PINID='SCLIN';
NET_NAME
'PCIE_CONN_SMDAT'
 '@TIMECARD_LIB.TIMECARD(SCH_1):PCIE_CONN_SMDAT':
 C_SIGNAL='@timecard_lib.timecard(sch_1):pcie_conn_smdat';
NODE_NAME     GF1 B6
 '@TIMECARD_LIB.TIMECARD(SCH_1):PAGE3_I61@CONNECTOR.CONN_64P_GF(CHIPS)':
 'SMDAT': CDS_PINID='SMDAT';
NODE_NAME     U2 6
 '@TIMECARD_LIB.TIMECARD(SCH_1):PAGE3_I100@STDLOGIC.G220_10198_01(CHIPS)':
 'SDAIN': CDS_PINID='SDAIN';
NET_NAME
'PCIE_CONN_TCK'
 '@TIMECARD_LIB.TIMECARD(SCH_1):PCIE_CONN_TCK':
 C_SIGNAL='@timecard_lib.timecard(sch_1):pcie_conn_tck';
NODE_NAME     R28 1
 '@TIMECARD_LIB.TIMECARD(SCH_1):PAGE3_I54@PASSIVE.RESISTOR(CHIPS)':
 '1': CDS_PINID='\1\';
NODE_NAME     GF1 A5
 '@TIMECARD_LIB.TIMECARD(SCH_1):PAGE3_I61@CONNECTOR.CONN_64P_GF(CHIPS)':
 'JTAG2': CDS_PINID='JTAG2';
NET_NAME
'PCIE_CONN_TDI'
 '@TIMECARD_LIB.TIMECARD(SCH_1):PCIE_CONN_TDI':
 C_SIGNAL='@timecard_lib.timecard(sch_1):pcie_conn_tdi';
NODE_NAME     R41 1
 '@TIMECARD_LIB.TIMECARD(SCH_1):PAGE3_I53@PASSIVE.RESISTOR(CHIPS)':
 '1': CDS_PINID='\1\';
NODE_NAME     GF1 A6
 '@TIMECARD_LIB.TIMECARD(SCH_1):PAGE3_I61@CONNECTOR.CONN_64P_GF(CHIPS)':
 'JTAG3': CDS_PINID='JTAG3';
NET_NAME
'PCIE_CONN_TDO'
 '@TIMECARD_LIB.TIMECARD(SCH_1):PCIE_CONN_TDO':
 C_SIGNAL='@timecard_lib.timecard(sch_1):pcie_conn_tdo';
NODE_NAME     R42 1
 '@TIMECARD_LIB.TIMECARD(SCH_1):PAGE3_I52@PASSIVE.RESISTOR(CHIPS)':
 '1': CDS_PINID='\1\';
NODE_NAME     GF1 A7
 '@TIMECARD_LIB.TIMECARD(SCH_1):PAGE3_I61@CONNECTOR.CONN_64P_GF(CHIPS)':
 'JTAG4': CDS_PINID='JTAG4';
NET_NAME
'PCIE_CONN_TMS'
 '@TIMECARD_LIB.TIMECARD(SCH_1):PCIE_CONN_TMS':
 C_SIGNAL='@timecard_lib.timecard(sch_1):pcie_conn_tms';
NODE_NAME     R43 1
 '@TIMECARD_LIB.TIMECARD(SCH_1):PAGE3_I51@PASSIVE.RESISTOR(CHIPS)':
 '1': CDS_PINID='\1\';
NODE_NAME     GF1 A8
 '@TIMECARD_LIB.TIMECARD(SCH_1):PAGE3_I61@CONNECTOR.CONN_64P_GF(CHIPS)':
 'JTAG5': CDS_PINID='JTAG5';
NET_NAME
'PCIE_PERST_N'
 '@TIMECARD_LIB.TIMECARD(SCH_1):PCIE_PERST_N':
 C_SIGNAL='@timecard_lib.timecard(sch_1):pcie_perst_n';
NODE_NAME     U34 3
 '@TIMECARD_LIB.TIMECARD(SCH_1):PAGE3_I139@ANALOG.TPS3808G18DBVR_SOT23_6(CHIPS)':
 'MR*': CDS_PINID='\mr*\';
NODE_NAME     R63 2
 '@TIMECARD_LIB.TIMECARD(SCH_1):PAGE3_I144@PASSIVE.RESISTOR(CHIPS)':
 '2': CDS_PINID='\2\';
NODE_NAME     R57 2
 '@TIMECARD_LIB.TIMECARD(SCH_1):PAGE3_I153@PASSIVE.RESISTOR(CHIPS)':
 '2': CDS_PINID='\2\';
NET_NAME
'PCIE_REFCLKN'
 '@TIMECARD_LIB.TIMECARD(SCH_1):PCIE_REFCLKN':
 C_SIGNAL='@timecard_lib.timecard(sch_1):pcie_refclkn';
NODE_NAME     C23 2
 '@TIMECARD_LIB.TIMECARD(SCH_1):PAGE3_I37@PASSIVE.CAPACITOR(CHIPS)':
 '2': CDS_PINID='\2\';
NODE_NAME     U24 E10
 '@TIMECARD_LIB.TIMECARD(SCH_1):PAGE127_I232@PLD.XC7A200T_2FBG484C_FBG484(CHIPS)':
 'MGTREFCLK1N_216': CDS_PINID='MGTREFCLK1N_216';
NODE_NAME     R198 2
 '@TIMECARD_LIB.TIMECARD(SCH_1):PAGE127_I334@PASSIVE.RESISTOR(CHIPS)':
 '2': CDS_PINID='\2\';
NET_NAME
'PCIE_REFCLKP'
 '@TIMECARD_LIB.TIMECARD(SCH_1):PCIE_REFCLKP':
 C_SIGNAL='@timecard_lib.timecard(sch_1):pcie_refclkp';
NODE_NAME     C19 2
 '@TIMECARD_LIB.TIMECARD(SCH_1):PAGE3_I36@PASSIVE.CAPACITOR(CHIPS)':
 '2': CDS_PINID='\2\';
NODE_NAME     U24 F10
 '@TIMECARD_LIB.TIMECARD(SCH_1):PAGE127_I232@PLD.XC7A200T_2FBG484C_FBG484(CHIPS)':
 'MGTREFCLK1P_216': CDS_PINID='MGTREFCLK1P_216';
NODE_NAME     R198 1
 '@TIMECARD_LIB.TIMECARD(SCH_1):PAGE127_I334@PASSIVE.RESISTOR(CHIPS)':
 '1': CDS_PINID='\1\';
NET_NAME
'PCIE_SMCLK'
 '@TIMECARD_LIB.TIMECARD(SCH_1):PCIE_SMCLK':
 C_SIGNAL='@timecard_lib.timecard(sch_1):pcie_smclk';
NODE_NAME     U2 2
 '@TIMECARD_LIB.TIMECARD(SCH_1):PAGE3_I100@STDLOGIC.G220_10198_01(CHIPS)':
 'SCLOUT': CDS_PINID='SCLOUT';
NODE_NAME     R27 1
 '@TIMECARD_LIB.TIMECARD(SCH_1):PAGE5_I72@PASSIVE.RESISTOR(CHIPS)':
 '1': CDS_PINID='\1\';
NODE_NAME     R176 1
 '@TIMECARD_LIB.TIMECARD(SCH_1):PAGE5_I102@PASSIVE.RESISTOR(CHIPS)':
 '1': CDS_PINID='\1\';
NET_NAME
'PCIE_SMDAT'
 '@TIMECARD_LIB.TIMECARD(SCH_1):PCIE_SMDAT':
 C_SIGNAL='@timecard_lib.timecard(sch_1):pcie_smdat';
NODE_NAME     U2 7
 '@TIMECARD_LIB.TIMECARD(SCH_1):PAGE3_I100@STDLOGIC.G220_10198_01(CHIPS)':
 'SDAOUT': CDS_PINID='SDAOUT';
NODE_NAME     R26 1
 '@TIMECARD_LIB.TIMECARD(SCH_1):PAGE5_I69@PASSIVE.RESISTOR(CHIPS)':
 '1': CDS_PINID='\1\';
NODE_NAME     R175 1
 '@TIMECARD_LIB.TIMECARD(SCH_1):PAGE5_I100@PASSIVE.RESISTOR(CHIPS)':
 '1': CDS_PINID='\1\';
NET_NAME
'PRI_EEPROM_SDA'
 '@TIMECARD_LIB.TIMECARD(SCH_1):PRI_EEPROM_SDA':
 C_SIGNAL='@timecard_lib.timecard(sch_1):pri_eeprom_sda';
NODE_NAME     U7 3
 '@TIMECARD_LIB.TIMECARD(SCH_1):PAGE5_I89@MEMORY.AT24MAC402_SOT23_5(CHIPS)':
 'SDA': CDS_PINID='SDA';
NODE_NAME     R345 2
 '@TIMECARD_LIB.TIMECARD(SCH_1):PAGE5_I90@PASSIVE.RESISTOR(CHIPS)':
 '2': CDS_PINID='\2\';
NET_NAME
'PUDC'
 '@TIMECARD_LIB.TIMECARD(SCH_1):PUDC':
 C_SIGNAL='@timecard_lib.timecard(sch_1):pudc';
NODE_NAME     U24 U22
 '@TIMECARD_LIB.TIMECARD(SCH_1):PAGE161_I2@PLD.XC7A200T_2FBG484C_FBG484(CHIPS)':
 'IO_L3P_T0_DQS_PUDC_14*': CDS_PINID='\io_l3p_t0_dqs_pudc_14*\';
NODE_NAME     R223 1
 '@TIMECARD_LIB.TIMECARD(SCH_1):PAGE161_I252@PASSIVE.RESISTOR(CHIPS)':
 '1': CDS_PINID='\1\';
NODE_NAME     R224 2
 '@TIMECARD_LIB.TIMECARD(SCH_1):PAGE161_I253@PASSIVE.RESISTOR(CHIPS)':
 '2': CDS_PINID='\2\';
NET_NAME
'RGB_LED_I2C_SCL'
 '@TIMECARD_LIB.TIMECARD(SCH_1):RGB_LED_I2C_SCL':
 C_SIGNAL='@timecard_lib.timecard(sch_1):rgb_led_i2c_scl';
NODE_NAME     R313 1
 '@TIMECARD_LIB.TIMECARD(SCH_1):PAGE5_I111@PASSIVE.RESISTOR(CHIPS)':
 '1': CDS_PINID='\1\';
NODE_NAME     R311 1
 '@TIMECARD_LIB.TIMECARD(SCH_1):PAGE5_I115@PASSIVE.RESISTOR(CHIPS)':
 '1': CDS_PINID='\1\';
NODE_NAME     R366 1
 '@TIMECARD_LIB.TIMECARD(SCH_1):PAGE14_I299@PASSIVE.RESISTOR(CHIPS)':
 '1': CDS_PINID='\1\';
NET_NAME
'RGB_LED_I2C_SDA'
 '@TIMECARD_LIB.TIMECARD(SCH_1):RGB_LED_I2C_SDA':
 C_SIGNAL='@timecard_lib.timecard(sch_1):rgb_led_i2c_sda';
NODE_NAME     R312 1
 '@TIMECARD_LIB.TIMECARD(SCH_1):PAGE5_I112@PASSIVE.RESISTOR(CHIPS)':
 '1': CDS_PINID='\1\';
NODE_NAME     R310 1
 '@TIMECARD_LIB.TIMECARD(SCH_1):PAGE5_I116@PASSIVE.RESISTOR(CHIPS)':
 '1': CDS_PINID='\1\';
NODE_NAME     R364 1
 '@TIMECARD_LIB.TIMECARD(SCH_1):PAGE14_I298@PASSIVE.RESISTOR(CHIPS)':
 '1': CDS_PINID='\1\';
NET_NAME
'RGB_LED_SHUTDOWN_N'
 '@TIMECARD_LIB.TIMECARD(SCH_1):RGB_LED_SHUTDOWN_N':
 C_SIGNAL='@timecard_lib.timecard(sch_1):rgb_led_shutdown_n';
NODE_NAME     U33 1
 '@TIMECARD_LIB.TIMECARD(SCH_1):PAGE14_I219@INTERFACE.IS32FL3207_QWLA3_TR_QFN29(CHIPS)':
 'SDB*': CDS_PINID='\sdb*\';
NODE_NAME     R319 2
 '@TIMECARD_LIB.TIMECARD(SCH_1):PAGE14_I249@PASSIVE.RESISTOR(CHIPS)':
 '2': CDS_PINID='\2\';
NODE_NAME     C316 1
 '@TIMECARD_LIB.TIMECARD(SCH_1):PAGE14_I250@PASSIVE.CAPACITOR(CHIPS)':
 '1': CDS_PINID='\1\';
NODE_NAME     R320 2
 '@TIMECARD_LIB.TIMECARD(SCH_1):PAGE14_I264@PASSIVE.RESISTOR(CHIPS)':
 '2': CDS_PINID='\2\';
NODE_NAME     TP25 1
 '@TIMECARD_LIB.TIMECARD(SCH_1):PAGE16_I1649@CLS.TP_PIONT(CHIPS)':
 '1': CDS_PINID='\1\';
NET_NAME
'RSVD_DBG_USB_MUX_SEL'
 '@TIMECARD_LIB.TIMECARD(SCH_1):RSVD_DBG_USB_MUX_SEL':
 C_SIGNAL='@timecard_lib.timecard(sch_1):rsvd_dbg_usb_mux_sel';
NODE_NAME     U24 M16
 '@TIMECARD_LIB.TIMECARD(SCH_1):PAGE162_I228@PLD.XC7A200T_2FBG484C_FBG484(CHIPS)':
 'IO_L24N_T3_RS0_15': CDS_PINID='IO_L24N_T3_RS0_15';
NODE_NAME     R266 1
 '@TIMECARD_LIB.TIMECARD(SCH_1):PAGE527_I204@PASSIVE.RESISTOR(CHIPS)':
 '1': CDS_PINID='\1\';
NET_NAME
'R_BNO080_BOOT_N'
 '@TIMECARD_LIB.TIMECARD(SCH_1):R_BNO080_BOOT_N':
 C_SIGNAL='@timecard_lib.timecard(sch_1):r_bno080_boot_n';
NODE_NAME     U29 4
 '@TIMECARD_LIB.TIMECARD(SCH_1):PAGE9_I29@LSI.BNO080_LGA_28(CHIPS)':
 'BOOTN': CDS_PINID='BOOTN';
NODE_NAME     R80 2
 '@TIMECARD_LIB.TIMECARD(SCH_1):PAGE9_I32@PASSIVE.RESISTOR(CHIPS)':
 '2': CDS_PINID='\2\';
NODE_NAME     R304 2
 '@TIMECARD_LIB.TIMECARD(SCH_1):PAGE9_I37@PASSIVE.RESISTOR(CHIPS)':
 '2': CDS_PINID='\2\';
NODE_NAME     TP18 1
 '@TIMECARD_LIB.TIMECARD(SCH_1):PAGE16_I1633@CLS.TP_PIONT(CHIPS)':
 '1': CDS_PINID='\1\';
NET_NAME
'R_BNO080_EVN_SCL'
 '@TIMECARD_LIB.TIMECARD(SCH_1):R_BNO080_EVN_SCL':
 C_SIGNAL='@timecard_lib.timecard(sch_1):r_bno080_evn_scl';
NODE_NAME     U29 15
 '@TIMECARD_LIB.TIMECARD(SCH_1):PAGE9_I29@LSI.BNO080_LGA_28(CHIPS)':
 'ENV_SCL': CDS_PINID='ENV_SCL';
NODE_NAME     R363 1
 '@TIMECARD_LIB.TIMECARD(SCH_1):PAGE9_I67@PASSIVE.RESISTOR(CHIPS)':
 '1': CDS_PINID='\1\';
NET_NAME
'R_BNO080_EVN_SDA'
 '@TIMECARD_LIB.TIMECARD(SCH_1):R_BNO080_EVN_SDA':
 C_SIGNAL='@timecard_lib.timecard(sch_1):r_bno080_evn_sda';
NODE_NAME     U29 16
 '@TIMECARD_LIB.TIMECARD(SCH_1):PAGE9_I29@LSI.BNO080_LGA_28(CHIPS)':
 'ENV_SDA': CDS_PINID='ENV_SDA';
NODE_NAME     R330 1
 '@TIMECARD_LIB.TIMECARD(SCH_1):PAGE9_I64@PASSIVE.RESISTOR(CHIPS)':
 '1': CDS_PINID='\1\';
NET_NAME
'R_BNO080_I2C_SCL'
 '@TIMECARD_LIB.TIMECARD(SCH_1):R_BNO080_I2C_SCL':
 C_SIGNAL='@timecard_lib.timecard(sch_1):r_bno080_i2c_scl';
NODE_NAME     R77 2
 '@TIMECARD_LIB.TIMECARD(SCH_1):PAGE9_I11@PASSIVE.RESISTOR(CHIPS)':
 '2': CDS_PINID='\2\';
NODE_NAME     U29 19
 '@TIMECARD_LIB.TIMECARD(SCH_1):PAGE9_I29@LSI.BNO080_LGA_28(CHIPS)':
 'H_SCL/SCK/RX': CDS_PINID='\h_scl/sck/rx\';
NET_NAME
'R_BNO080_I2C_SDA'
 '@TIMECARD_LIB.TIMECARD(SCH_1):R_BNO080_I2C_SDA':
 C_SIGNAL='@timecard_lib.timecard(sch_1):r_bno080_i2c_sda';
NODE_NAME     R76 2
 '@TIMECARD_LIB.TIMECARD(SCH_1):PAGE9_I12@PASSIVE.RESISTOR(CHIPS)':
 '2': CDS_PINID='\2\';
NODE_NAME     U29 20
 '@TIMECARD_LIB.TIMECARD(SCH_1):PAGE9_I29@LSI.BNO080_LGA_28(CHIPS)':
 'H_SDA/H_MISO/TX': CDS_PINID='\h_sda/h_miso/tx\';
NET_NAME
'R_BNO080_INT_N'
 '@TIMECARD_LIB.TIMECARD(SCH_1):R_BNO080_INT_N':
 C_SIGNAL='@timecard_lib.timecard(sch_1):r_bno080_int_n';
NODE_NAME     U29 14
 '@TIMECARD_LIB.TIMECARD(SCH_1):PAGE9_I29@LSI.BNO080_LGA_28(CHIPS)':
 'H_INTN': CDS_PINID='H_INTN';
NODE_NAME     R79 2
 '@TIMECARD_LIB.TIMECARD(SCH_1):PAGE9_I31@PASSIVE.RESISTOR(CHIPS)':
 '2': CDS_PINID='\2\';
NODE_NAME     TP17 1
 '@TIMECARD_LIB.TIMECARD(SCH_1):PAGE16_I1632@CLS.TP_PIONT(CHIPS)':
 '1': CDS_PINID='\1\';
NET_NAME
'R_BNO080_RST_N'
 '@TIMECARD_LIB.TIMECARD(SCH_1):R_BNO080_RST_N':
 C_SIGNAL='@timecard_lib.timecard(sch_1):r_bno080_rst_n';
NODE_NAME     U29 11
 '@TIMECARD_LIB.TIMECARD(SCH_1):PAGE9_I29@LSI.BNO080_LGA_28(CHIPS)':
 'RST*': CDS_PINID='\rst*\';
NODE_NAME     R78 1
 '@TIMECARD_LIB.TIMECARD(SCH_1):PAGE9_I41@PASSIVE.RESISTOR(CHIPS)':
 '1': CDS_PINID='\1\';
NODE_NAME     R301 1
 '@TIMECARD_LIB.TIMECARD(SCH_1):PAGE9_I43@PASSIVE.RESISTOR(CHIPS)':
 '1': CDS_PINID='\1\';
NODE_NAME     R291 2
 '@TIMECARD_LIB.TIMECARD(SCH_1):PAGE9_I44@PASSIVE.RESISTOR(CHIPS)':
 '2': CDS_PINID='\2\';
NODE_NAME     TP16 1
 '@TIMECARD_LIB.TIMECARD(SCH_1):PAGE16_I1631@CLS.TP_PIONT(CHIPS)':
 '1': CDS_PINID='\1\';
NET_NAME
'R_FPGA_TDO'
 '@TIMECARD_LIB.TIMECARD(SCH_1):R_FPGA_TDO':
 C_SIGNAL='@timecard_lib.timecard(sch_1):r_fpga_tdo';
NODE_NAME     U24 U13
 '@TIMECARD_LIB.TIMECARD(SCH_1):PAGE127_I232@PLD.XC7A200T_2FBG484C_FBG484(CHIPS)':
 'TDO_0': CDS_PINID='TDO_0';
NODE_NAME     R195 2
 '@TIMECARD_LIB.TIMECARD(SCH_1):PAGE127_I331@PASSIVE.RESISTOR(CHIPS)':
 '2': CDS_PINID='\2\';
NET_NAME
'R_FT4232_CHC_RX'
 '@TIMECARD_LIB.TIMECARD(SCH_1):R_FT4232_CHC_RX':
 C_SIGNAL='@timecard_lib.timecard(sch_1):r_ft4232_chc_rx';
NODE_NAME     U18 39
 '@TIMECARD_LIB.TIMECARD(SCH_1):PAGE524_I64@INTERFACE.FT4232HL_REEL_QFP64(CHIPS)':
 'CDBUS1': CDS_PINID='CDBUS1';
NODE_NAME     R481 1
 '@TIMECARD_LIB.TIMECARD(SCH_1):PAGE524_I150@PASSIVE.RESISTOR(CHIPS)':
 '1': CDS_PINID='\1\';
NODE_NAME     R352 1
 '@TIMECARD_LIB.TIMECARD(SCH_1):PAGE524_I154@PASSIVE.RESISTOR(CHIPS)':
 '1': CDS_PINID='\1\';
NET_NAME
'R_FT4232_CHC_TX'
 '@TIMECARD_LIB.TIMECARD(SCH_1):R_FT4232_CHC_TX':
 C_SIGNAL='@timecard_lib.timecard(sch_1):r_ft4232_chc_tx';
NODE_NAME     U18 38
 '@TIMECARD_LIB.TIMECARD(SCH_1):PAGE524_I64@INTERFACE.FT4232HL_REEL_QFP64(CHIPS)':
 'CDBUS0': CDS_PINID='CDBUS0';
NODE_NAME     R353 1
 '@TIMECARD_LIB.TIMECARD(SCH_1):PAGE524_I153@PASSIVE.RESISTOR(CHIPS)':
 '1': CDS_PINID='\1\';
NET_NAME
'R_FT4232_CHD_RX'
 '@TIMECARD_LIB.TIMECARD(SCH_1):R_FT4232_CHD_RX':
 C_SIGNAL='@timecard_lib.timecard(sch_1):r_ft4232_chd_rx';
NODE_NAME     U18 52
 '@TIMECARD_LIB.TIMECARD(SCH_1):PAGE524_I64@INTERFACE.FT4232HL_REEL_QFP64(CHIPS)':
 'DDBUS1': CDS_PINID='DDBUS1';
NODE_NAME     R349 1
 '@TIMECARD_LIB.TIMECARD(SCH_1):PAGE524_I184@PASSIVE.RESISTOR(CHIPS)':
 '1': CDS_PINID='\1\';
NODE_NAME     R132 1
 '@TIMECARD_LIB.TIMECARD(SCH_1):PAGE524_I188@PASSIVE.RESISTOR(CHIPS)':
 '1': CDS_PINID='\1\';
NET_NAME
'R_FT4232_CHD_TX'
 '@TIMECARD_LIB.TIMECARD(SCH_1):R_FT4232_CHD_TX':
 C_SIGNAL='@timecard_lib.timecard(sch_1):r_ft4232_chd_tx';
NODE_NAME     U18 48
 '@TIMECARD_LIB.TIMECARD(SCH_1):PAGE524_I64@INTERFACE.FT4232HL_REEL_QFP64(CHIPS)':
 'DDBUS0': CDS_PINID='DDBUS0';
NODE_NAME     R131 1
 '@TIMECARD_LIB.TIMECARD(SCH_1):PAGE524_I187@PASSIVE.RESISTOR(CHIPS)':
 '1': CDS_PINID='\1\';
NET_NAME
'R_FT4232_I2C_SCL'
 '@TIMECARD_LIB.TIMECARD(SCH_1):R_FT4232_I2C_SCL':
 C_SIGNAL='@timecard_lib.timecard(sch_1):r_ft4232_i2c_scl';
NODE_NAME     U18 26
 '@TIMECARD_LIB.TIMECARD(SCH_1):PAGE524_I64@INTERFACE.FT4232HL_REEL_QFP64(CHIPS)':
 'BDBUS0': CDS_PINID='BDBUS0';
NODE_NAME     R471 1
 '@TIMECARD_LIB.TIMECARD(SCH_1):PAGE524_I169@PASSIVE.RESISTOR(CHIPS)':
 '1': CDS_PINID='\1\';
NET_NAME
'R_FT4232_I2C_SDA_IN'
 '@TIMECARD_LIB.TIMECARD(SCH_1):R_FT4232_I2C_SDA_IN':
 C_SIGNAL='@timecard_lib.timecard(sch_1):r_ft4232_i2c_sda_in';
NODE_NAME     U18 28
 '@TIMECARD_LIB.TIMECARD(SCH_1):PAGE524_I64@INTERFACE.FT4232HL_REEL_QFP64(CHIPS)':
 'BDBUS2': CDS_PINID='BDBUS2';
NODE_NAME     R473 1
 '@TIMECARD_LIB.TIMECARD(SCH_1):PAGE524_I170@PASSIVE.RESISTOR(CHIPS)':
 '1': CDS_PINID='\1\';
NET_NAME
'R_FT4232_I2C_SDA_OUT'
 '@TIMECARD_LIB.TIMECARD(SCH_1):R_FT4232_I2C_SDA_OUT':
 C_SIGNAL='@timecard_lib.timecard(sch_1):r_ft4232_i2c_sda_out';
NODE_NAME     U18 27
 '@TIMECARD_LIB.TIMECARD(SCH_1):PAGE524_I64@INTERFACE.FT4232HL_REEL_QFP64(CHIPS)':
 'BDBUS1': CDS_PINID='BDBUS1';
NODE_NAME     R472 1
 '@TIMECARD_LIB.TIMECARD(SCH_1):PAGE524_I166@PASSIVE.RESISTOR(CHIPS)':
 '1': CDS_PINID='\1\';
NET_NAME
'R_FT4232_TCK'
 '@TIMECARD_LIB.TIMECARD(SCH_1):R_FT4232_TCK':
 C_SIGNAL='@timecard_lib.timecard(sch_1):r_ft4232_tck';
NODE_NAME     U18 16
 '@TIMECARD_LIB.TIMECARD(SCH_1):PAGE524_I64@INTERFACE.FT4232HL_REEL_QFP64(CHIPS)':
 'ADBUS0': CDS_PINID='ADBUS0';
NODE_NAME     R467 1
 '@TIMECARD_LIB.TIMECARD(SCH_1):PAGE524_I141@PASSIVE.RESISTOR(CHIPS)':
 '1': CDS_PINID='\1\';
NET_NAME
'R_FT4232_TDI'
 '@TIMECARD_LIB.TIMECARD(SCH_1):R_FT4232_TDI':
 C_SIGNAL='@timecard_lib.timecard(sch_1):r_ft4232_tdi';
NODE_NAME     U18 17
 '@TIMECARD_LIB.TIMECARD(SCH_1):PAGE524_I64@INTERFACE.FT4232HL_REEL_QFP64(CHIPS)':
 'ADBUS1': CDS_PINID='ADBUS1';
NODE_NAME     R468 1
 '@TIMECARD_LIB.TIMECARD(SCH_1):PAGE524_I140@PASSIVE.RESISTOR(CHIPS)':
 '1': CDS_PINID='\1\';
NET_NAME
'R_FT4232_TDO'
 '@TIMECARD_LIB.TIMECARD(SCH_1):R_FT4232_TDO':
 C_SIGNAL='@timecard_lib.timecard(sch_1):r_ft4232_tdo';
NODE_NAME     U18 18
 '@TIMECARD_LIB.TIMECARD(SCH_1):PAGE524_I64@INTERFACE.FT4232HL_REEL_QFP64(CHIPS)':
 'ADBUS2': CDS_PINID='ADBUS2';
NODE_NAME     R469 1
 '@TIMECARD_LIB.TIMECARD(SCH_1):PAGE524_I142@PASSIVE.RESISTOR(CHIPS)':
 '1': CDS_PINID='\1\';
NODE_NAME     R466 1
 '@TIMECARD_LIB.TIMECARD(SCH_1):PAGE524_I198@PASSIVE.RESISTOR(CHIPS)':
 '1': CDS_PINID='\1\';
NET_NAME
'R_FT4232_TMS'
 '@TIMECARD_LIB.TIMECARD(SCH_1):R_FT4232_TMS':
 C_SIGNAL='@timecard_lib.timecard(sch_1):r_ft4232_tms';
NODE_NAME     U18 19
 '@TIMECARD_LIB.TIMECARD(SCH_1):PAGE524_I64@INTERFACE.FT4232HL_REEL_QFP64(CHIPS)':
 'ADBUS3': CDS_PINID='ADBUS3';
NODE_NAME     R470 1
 '@TIMECARD_LIB.TIMECARD(SCH_1):PAGE524_I139@PASSIVE.RESISTOR(CHIPS)':
 '1': CDS_PINID='\1\';
NET_NAME
'R_FT_USB_DM'
 '@TIMECARD_LIB.TIMECARD(SCH_1):R_FT_USB_DM':
 C_SIGNAL='@timecard_lib.timecard(sch_1):r_ft_usb_dm';
NODE_NAME     R128 2
 '@TIMECARD_LIB.TIMECARD(SCH_1):PAGE524_I28@PASSIVE.RESISTOR(CHIPS)':
 '2': CDS_PINID='\2\';
NODE_NAME     U18 7
 '@TIMECARD_LIB.TIMECARD(SCH_1):PAGE524_I64@INTERFACE.FT4232HL_REEL_QFP64(CHIPS)':
 'DM': CDS_PINID='DM';
NET_NAME
'R_FT_USB_DP'
 '@TIMECARD_LIB.TIMECARD(SCH_1):R_FT_USB_DP':
 C_SIGNAL='@timecard_lib.timecard(sch_1):r_ft_usb_dp';
NODE_NAME     R129 2
 '@TIMECARD_LIB.TIMECARD(SCH_1):PAGE524_I26@PASSIVE.RESISTOR(CHIPS)':
 '2': CDS_PINID='\2\';
NODE_NAME     U18 8
 '@TIMECARD_LIB.TIMECARD(SCH_1):PAGE524_I64@INTERFACE.FT4232HL_REEL_QFP64(CHIPS)':
 'DP': CDS_PINID='DP';
NET_NAME
'R_ICP10100_I2C_SCL'
 '@TIMECARD_LIB.TIMECARD(SCH_1):R_ICP10100_I2C_SCL':
 C_SIGNAL='@timecard_lib.timecard(sch_1):r_icp10100_i2c_scl';
NODE_NAME     R73 2
 '@TIMECARD_LIB.TIMECARD(SCH_1):PAGE8_I6@PASSIVE.RESISTOR(CHIPS)':
 '2': CDS_PINID='\2\';
NODE_NAME     U28 2
 '@TIMECARD_LIB.TIMECARD(SCH_1):PAGE8_I24@ANALOG.ICP_10100_LGA10(CHIPS)':
 'SCL': CDS_PINID='SCL';
NET_NAME
'R_ICP10100_I2C_SDA'
 '@TIMECARD_LIB.TIMECARD(SCH_1):R_ICP10100_I2C_SDA':
 C_SIGNAL='@timecard_lib.timecard(sch_1):r_icp10100_i2c_sda';
NODE_NAME     R72 2
 '@TIMECARD_LIB.TIMECARD(SCH_1):PAGE8_I7@PASSIVE.RESISTOR(CHIPS)':
 '2': CDS_PINID='\2\';
NODE_NAME     U28 4
 '@TIMECARD_LIB.TIMECARD(SCH_1):PAGE8_I24@ANALOG.ICP_10100_LGA10(CHIPS)':
 'SDA': CDS_PINID='SDA';
NET_NAME
'R_LM75B_1_I2C_SDA'
 '@TIMECARD_LIB.TIMECARD(SCH_1):R_LM75B_1_I2C_SDA':
 C_SIGNAL='@timecard_lib.timecard(sch_1):r_lm75b_1_i2c_sda';
NODE_NAME     R332 2
 '@TIMECARD_LIB.TIMECARD(SCH_1):PAGE6_I15@PASSIVE.RESISTOR(CHIPS)':
 '2': CDS_PINID='\2\';
NODE_NAME     U8 1
 '@TIMECARD_LIB.TIMECARD(SCH_1):PAGE6_I34@INTERFACE.LM75BDP_TSSOP8(CHIPS)':
 'SDA': CDS_PINID='SDA';
NET_NAME
'R_LM75B_2_I2C_SDA'
 '@TIMECARD_LIB.TIMECARD(SCH_1):R_LM75B_2_I2C_SDA':
 C_SIGNAL='@timecard_lib.timecard(sch_1):r_lm75b_2_i2c_sda';
NODE_NAME     U35 1
 '@TIMECARD_LIB.TIMECARD(SCH_1):PAGE6_I59@INTERFACE.LM75BDP_TSSOP8(CHIPS)':
 'SDA': CDS_PINID='SDA';
NODE_NAME     R406 2
 '@TIMECARD_LIB.TIMECARD(SCH_1):PAGE6_I76@PASSIVE.RESISTOR(CHIPS)':
 '2': CDS_PINID='\2\';
NET_NAME
'R_LM75B_3_I2C_SDA'
 '@TIMECARD_LIB.TIMECARD(SCH_1):R_LM75B_3_I2C_SDA':
 C_SIGNAL='@timecard_lib.timecard(sch_1):r_lm75b_3_i2c_sda';
NODE_NAME     U36 1
 '@TIMECARD_LIB.TIMECARD(SCH_1):PAGE6_I81@INTERFACE.LM75BDP_TSSOP8(CHIPS)':
 'SDA': CDS_PINID='SDA';
NODE_NAME     R407 2
 '@TIMECARD_LIB.TIMECARD(SCH_1):PAGE6_I100@PASSIVE.RESISTOR(CHIPS)':
 '2': CDS_PINID='\2\';
NET_NAME
'R_MAC_10MHZ_RF_OUT'
 '@TIMECARD_LIB.TIMECARD(SCH_1):R_MAC_10MHZ_RF_OUT':
 C_SIGNAL='@timecard_lib.timecard(sch_1):r_mac_10mhz_rf_out';
NODE_NAME     R92 1
 '@TIMECARD_LIB.TIMECARD(SCH_1):PAGE527_I55@PASSIVE.RESISTOR(CHIPS)':
 '1': CDS_PINID='\1\';
NODE_NAME     MAC_PIN3 1
 '@TIMECARD_LIB.TIMECARD(SCH_1):PAGE527_I226@MECH.NUT(CHIPS)':
 '1': CDS_PINID='\1\';
NET_NAME
'R_MAC_BITEOUT'
 '@TIMECARD_LIB.TIMECARD(SCH_1):R_MAC_BITE OUT':
 C_SIGNAL='@timecard_lib.timecard(sch_1):\r_mac_bite out\';
NODE_NAME     R93 1
 '@TIMECARD_LIB.TIMECARD(SCH_1):PAGE527_I53@PASSIVE.RESISTOR(CHIPS)':
 '1': CDS_PINID='\1\';
NODE_NAME     MAC_PIN6 1
 '@TIMECARD_LIB.TIMECARD(SCH_1):PAGE527_I225@MECH.NUT(CHIPS)':
 '1': CDS_PINID='\1\';
NODE_NAME     TP62 1
 '@TIMECARD_LIB.TIMECARD(SCH_1):PAGE16_I1705@CLS.TP_PIONT(CHIPS)':
 '1': CDS_PINID='\1\';
NET_NAME
'R_MAC_PPS_IN0N'
 '@TIMECARD_LIB.TIMECARD(SCH_1):R_MAC_PPS_IN0N':
 C_SIGNAL='@timecard_lib.timecard(sch_1):r_mac_pps_in0n';
NODE_NAME     R86 2
 '@TIMECARD_LIB.TIMECARD(SCH_1):PAGE527_I29@PASSIVE.RESISTOR(CHIPS)':
 '2': CDS_PINID='\2\';
NODE_NAME     R90 1
 '@TIMECARD_LIB.TIMECARD(SCH_1):PAGE527_I33@PASSIVE.RESISTOR(CHIPS)':
 '1': CDS_PINID='\1\';
NODE_NAME     P1 7
 '@TIMECARD_LIB.TIMECARD(SCH_1):PAGE527_I193@CONNECTOR.CONN_HDR_2X10_M_S_SMT(CHIPS)':
 '7': CDS_PINID='\7\';
NET_NAME
'R_MAC_PPS_IN0P'
 '@TIMECARD_LIB.TIMECARD(SCH_1):R_MAC_PPS_IN0P':
 C_SIGNAL='@timecard_lib.timecard(sch_1):r_mac_pps_in0p';
NODE_NAME     R85 2
 '@TIMECARD_LIB.TIMECARD(SCH_1):PAGE527_I30@PASSIVE.RESISTOR(CHIPS)':
 '2': CDS_PINID='\2\';
NODE_NAME     R90 2
 '@TIMECARD_LIB.TIMECARD(SCH_1):PAGE527_I33@PASSIVE.RESISTOR(CHIPS)':
 '2': CDS_PINID='\2\';
NODE_NAME     P1 5
 '@TIMECARD_LIB.TIMECARD(SCH_1):PAGE527_I193@CONNECTOR.CONN_HDR_2X10_M_S_SMT(CHIPS)':
 '5': CDS_PINID='\5\';
NET_NAME
'R_MAC_PPS_IN1N'
 '@TIMECARD_LIB.TIMECARD(SCH_1):R_MAC_PPS_IN1N':
 C_SIGNAL='@timecard_lib.timecard(sch_1):r_mac_pps_in1n';
NODE_NAME     R84 2
 '@TIMECARD_LIB.TIMECARD(SCH_1):PAGE527_I31@PASSIVE.RESISTOR(CHIPS)':
 '2': CDS_PINID='\2\';
NODE_NAME     R89 2
 '@TIMECARD_LIB.TIMECARD(SCH_1):PAGE527_I34@PASSIVE.RESISTOR(CHIPS)':
 '2': CDS_PINID='\2\';
NODE_NAME     P1 3
 '@TIMECARD_LIB.TIMECARD(SCH_1):PAGE527_I193@CONNECTOR.CONN_HDR_2X10_M_S_SMT(CHIPS)':
 '3': CDS_PINID='\3\';
NET_NAME
'R_MAC_PPS_IN1P'
 '@TIMECARD_LIB.TIMECARD(SCH_1):R_MAC_PPS_IN1P':
 C_SIGNAL='@timecard_lib.timecard(sch_1):r_mac_pps_in1p';
NODE_NAME     R83 2
 '@TIMECARD_LIB.TIMECARD(SCH_1):PAGE527_I32@PASSIVE.RESISTOR(CHIPS)':
 '2': CDS_PINID='\2\';
NODE_NAME     R89 1
 '@TIMECARD_LIB.TIMECARD(SCH_1):PAGE527_I34@PASSIVE.RESISTOR(CHIPS)':
 '1': CDS_PINID='\1\';
NODE_NAME     P1 1
 '@TIMECARD_LIB.TIMECARD(SCH_1):PAGE527_I193@CONNECTOR.CONN_HDR_2X10_M_S_SMT(CHIPS)':
 '1': CDS_PINID='\1\';
NET_NAME
'R_MAC_PPS_OUTN'
 '@TIMECARD_LIB.TIMECARD(SCH_1):R_MAC_PPS_OUTN':
 C_SIGNAL='@timecard_lib.timecard(sch_1):r_mac_pps_outn';
NODE_NAME     R88 2
 '@TIMECARD_LIB.TIMECARD(SCH_1):PAGE527_I13@PASSIVE.RESISTOR(CHIPS)':
 '2': CDS_PINID='\2\';
NODE_NAME     P1 19
 '@TIMECARD_LIB.TIMECARD(SCH_1):PAGE527_I193@CONNECTOR.CONN_HDR_2X10_M_S_SMT(CHIPS)':
 '19': CDS_PINID='\19\';
NET_NAME
'R_MAC_PPS_OUTP'
 '@TIMECARD_LIB.TIMECARD(SCH_1):R_MAC_PPS_OUTP':
 C_SIGNAL='@timecard_lib.timecard(sch_1):r_mac_pps_outp';
NODE_NAME     R87 2
 '@TIMECARD_LIB.TIMECARD(SCH_1):PAGE527_I14@PASSIVE.RESISTOR(CHIPS)':
 '2': CDS_PINID='\2\';
NODE_NAME     P1 17
 '@TIMECARD_LIB.TIMECARD(SCH_1):PAGE527_I193@CONNECTOR.CONN_HDR_2X10_M_S_SMT(CHIPS)':
 '17': CDS_PINID='\17\';
NET_NAME
'R_MAC_UART_RX_FPGA_TX'
 '@TIMECARD_LIB.TIMECARD(SCH_1):R_MAC_UART_RX_FPGA_TX':
 C_SIGNAL='@timecard_lib.timecard(sch_1):r_mac_uart_rx_fpga_tx';
NODE_NAME     R95 1
 '@TIMECARD_LIB.TIMECARD(SCH_1):PAGE527_I52@PASSIVE.RESISTOR(CHIPS)':
 '1': CDS_PINID='\1\';
NODE_NAME     MAC_PIN8 1
 '@TIMECARD_LIB.TIMECARD(SCH_1):PAGE527_I220@MECH.NUT(CHIPS)':
 '1': CDS_PINID='\1\';
NODE_NAME     R264 2
 '@TIMECARD_LIB.TIMECARD(SCH_1):PAGE527_I222@PASSIVE.RESISTOR(CHIPS)':
 '2': CDS_PINID='\2\';
NODE_NAME     R81 1
 '@TIMECARD_LIB.TIMECARD(SCH_1):PAGE527_I240@PASSIVE.RESISTOR(CHIPS)':
 '1': CDS_PINID='\1\';
NET_NAME
'R_MAC_UART_TX_FPGA_RX'
 '@TIMECARD_LIB.TIMECARD(SCH_1):R_MAC_UART_TX_FPGA_RX':
 C_SIGNAL='@timecard_lib.timecard(sch_1):r_mac_uart_tx_fpga_rx';
NODE_NAME     R94 1
 '@TIMECARD_LIB.TIMECARD(SCH_1):PAGE527_I54@PASSIVE.RESISTOR(CHIPS)':
 '1': CDS_PINID='\1\';
NODE_NAME     MAC_PIN7 1
 '@TIMECARD_LIB.TIMECARD(SCH_1):PAGE527_I224@MECH.NUT(CHIPS)':
 '1': CDS_PINID='\1\';
NODE_NAME     R82 1
 '@TIMECARD_LIB.TIMECARD(SCH_1):PAGE527_I241@PASSIVE.RESISTOR(CHIPS)':
 '1': CDS_PINID='\1\';
NET_NAME
'R_MAC_USB_DM'
 '@TIMECARD_LIB.TIMECARD(SCH_1):R_MAC_USB_DM':
 C_SIGNAL='@timecard_lib.timecard(sch_1):r_mac_usb_dm';
NODE_NAME     R98 1
 '@TIMECARD_LIB.TIMECARD(SCH_1):PAGE527_I175@PASSIVE.RESISTOR(CHIPS)':
 '1': CDS_PINID='\1\';
NODE_NAME     P1 4
 '@TIMECARD_LIB.TIMECARD(SCH_1):PAGE527_I193@CONNECTOR.CONN_HDR_2X10_M_S_SMT(CHIPS)':
 '4': CDS_PINID='\4\';
NET_NAME
'R_MAC_USB_DP'
 '@TIMECARD_LIB.TIMECARD(SCH_1):R_MAC_USB_DP':
 C_SIGNAL='@timecard_lib.timecard(sch_1):r_mac_usb_dp';
NODE_NAME     R97 1
 '@TIMECARD_LIB.TIMECARD(SCH_1):PAGE527_I176@PASSIVE.RESISTOR(CHIPS)':
 '1': CDS_PINID='\1\';
NODE_NAME     P1 2
 '@TIMECARD_LIB.TIMECARD(SCH_1):PAGE527_I193@CONNECTOR.CONN_HDR_2X10_M_S_SMT(CHIPS)':
 '2': CDS_PINID='\2\';
NET_NAME
'R_PCA9546_I2C_SCL'
 '@TIMECARD_LIB.TIMECARD(SCH_1):R_PCA9546_I2C_SCL':
 C_SIGNAL='@timecard_lib.timecard(sch_1):r_pca9546_i2c_scl';
NODE_NAME     R59 2
 '@TIMECARD_LIB.TIMECARD(SCH_1):PAGE5_I4@PASSIVE.RESISTOR(CHIPS)':
 '2': CDS_PINID='\2\';
NODE_NAME     U4 14
 '@TIMECARD_LIB.TIMECARD(SCH_1):PAGE5_I33@INTERFACE.PCA9546APW_TSSOP16(CHIPS)':
 'SCL': CDS_PINID='SCL';
NODE_NAME     R145 2
 '@TIMECARD_LIB.TIMECARD(SCH_1):PAGE5_I67@PASSIVE.RESISTOR(CHIPS)':
 '2': CDS_PINID='\2\';
NODE_NAME     R27 2
 '@TIMECARD_LIB.TIMECARD(SCH_1):PAGE5_I72@PASSIVE.RESISTOR(CHIPS)':
 '2': CDS_PINID='\2\';
NODE_NAME     R148 2
 '@TIMECARD_LIB.TIMECARD(SCH_1):PAGE5_I81@PASSIVE.RESISTOR(CHIPS)':
 '2': CDS_PINID='\2\';
NODE_NAME     R311 2
 '@TIMECARD_LIB.TIMECARD(SCH_1):PAGE5_I115@PASSIVE.RESISTOR(CHIPS)':
 '2': CDS_PINID='\2\';
NET_NAME
'R_PCA9546_I2C_SDA'
 '@TIMECARD_LIB.TIMECARD(SCH_1):R_PCA9546_I2C_SDA':
 C_SIGNAL='@timecard_lib.timecard(sch_1):r_pca9546_i2c_sda';
NODE_NAME     U4 15
 '@TIMECARD_LIB.TIMECARD(SCH_1):PAGE5_I33@INTERFACE.PCA9546APW_TSSOP16(CHIPS)':
 'SDA': CDS_PINID='SDA';
NODE_NAME     R144 2
 '@TIMECARD_LIB.TIMECARD(SCH_1):PAGE5_I68@PASSIVE.RESISTOR(CHIPS)':
 '2': CDS_PINID='\2\';
NODE_NAME     R26 2
 '@TIMECARD_LIB.TIMECARD(SCH_1):PAGE5_I69@PASSIVE.RESISTOR(CHIPS)':
 '2': CDS_PINID='\2\';
NODE_NAME     R147 2
 '@TIMECARD_LIB.TIMECARD(SCH_1):PAGE5_I80@PASSIVE.RESISTOR(CHIPS)':
 '2': CDS_PINID='\2\';
NODE_NAME     R58 2
 '@TIMECARD_LIB.TIMECARD(SCH_1):PAGE5_I88@PASSIVE.RESISTOR(CHIPS)':
 '2': CDS_PINID='\2\';
NODE_NAME     R310 2
 '@TIMECARD_LIB.TIMECARD(SCH_1):PAGE5_I116@PASSIVE.RESISTOR(CHIPS)':
 '2': CDS_PINID='\2\';
NET_NAME
'R_RGB_LED_I2C_SCL'
 '@TIMECARD_LIB.TIMECARD(SCH_1):R_RGB_LED_I2C_SCL':
 C_SIGNAL='@timecard_lib.timecard(sch_1):r_rgb_led_i2c_scl';
NODE_NAME     U33 7
 '@TIMECARD_LIB.TIMECARD(SCH_1):PAGE14_I219@INTERFACE.IS32FL3207_QWLA3_TR_QFN29(CHIPS)':
 'SCL': CDS_PINID='SCL';
NODE_NAME     R322 2
 '@TIMECARD_LIB.TIMECARD(SCH_1):PAGE14_I257@PASSIVE.RESISTOR(CHIPS)':
 '2': CDS_PINID='\2\';
NODE_NAME     R318 2
 '@TIMECARD_LIB.TIMECARD(SCH_1):PAGE14_I261@PASSIVE.RESISTOR(CHIPS)':
 '2': CDS_PINID='\2\';
NODE_NAME     R366 2
 '@TIMECARD_LIB.TIMECARD(SCH_1):PAGE14_I299@PASSIVE.RESISTOR(CHIPS)':
 '2': CDS_PINID='\2\';
NET_NAME
'R_RGB_LED_I2C_SDA'
 '@TIMECARD_LIB.TIMECARD(SCH_1):R_RGB_LED_I2C_SDA':
 C_SIGNAL='@timecard_lib.timecard(sch_1):r_rgb_led_i2c_sda';
NODE_NAME     U33 6
 '@TIMECARD_LIB.TIMECARD(SCH_1):PAGE14_I219@INTERFACE.IS32FL3207_QWLA3_TR_QFN29(CHIPS)':
 'SDA': CDS_PINID='SDA';
NODE_NAME     R321 2
 '@TIMECARD_LIB.TIMECARD(SCH_1):PAGE14_I258@PASSIVE.RESISTOR(CHIPS)':
 '2': CDS_PINID='\2\';
NODE_NAME     R317 2
 '@TIMECARD_LIB.TIMECARD(SCH_1):PAGE14_I259@PASSIVE.RESISTOR(CHIPS)':
 '2': CDS_PINID='\2\';
NODE_NAME     R364 2
 '@TIMECARD_LIB.TIMECARD(SCH_1):PAGE14_I298@PASSIVE.RESISTOR(CHIPS)':
 '2': CDS_PINID='\2\';
NET_NAME
'R_SHT3X_ALERT_N'
 '@TIMECARD_LIB.TIMECARD(SCH_1):R_SHT3X_ALERT_N':
 C_SIGNAL='@timecard_lib.timecard(sch_1):r_sht3x_alert_n';
NODE_NAME     R299 1
 '@TIMECARD_LIB.TIMECARD(SCH_1):PAGE7_I40@PASSIVE.RESISTOR(CHIPS)':
 '1': CDS_PINID='\1\';
NODE_NAME     U27 3
 '@TIMECARD_LIB.TIMECARD(SCH_1):PAGE7_I44@ANALOG.SHT31A_DIS_B10KS_DFN8(CHIPS)':
 'ALERT': CDS_PINID='ALERT';
NODE_NAME     TP27 1
 '@TIMECARD_LIB.TIMECARD(SCH_1):PAGE16_I1661@CLS.TP_PIONT(CHIPS)':
 '1': CDS_PINID='\1\';
NET_NAME
'R_SHT3X_I2C_SCL'
 '@TIMECARD_LIB.TIMECARD(SCH_1):R_SHT3X_I2C_SCL':
 C_SIGNAL='@timecard_lib.timecard(sch_1):r_sht3x_i2c_scl';
NODE_NAME     R67 2
 '@TIMECARD_LIB.TIMECARD(SCH_1):PAGE7_I13@PASSIVE.RESISTOR(CHIPS)':
 '2': CDS_PINID='\2\';
NODE_NAME     U27 4
 '@TIMECARD_LIB.TIMECARD(SCH_1):PAGE7_I44@ANALOG.SHT31A_DIS_B10KS_DFN8(CHIPS)':
 'SCL': CDS_PINID='SCL';
NET_NAME
'R_SHT3X_I2C_SDA'
 '@TIMECARD_LIB.TIMECARD(SCH_1):R_SHT3X_I2C_SDA':
 C_SIGNAL='@timecard_lib.timecard(sch_1):r_sht3x_i2c_sda';
NODE_NAME     R66 2
 '@TIMECARD_LIB.TIMECARD(SCH_1):PAGE7_I14@PASSIVE.RESISTOR(CHIPS)':
 '2': CDS_PINID='\2\';
NODE_NAME     U27 1
 '@TIMECARD_LIB.TIMECARD(SCH_1):PAGE7_I44@ANALOG.SHT31A_DIS_B10KS_DFN8(CHIPS)':
 'SDA': CDS_PINID='SDA';
NET_NAME
'R_SHT3X_RST_N'
 '@TIMECARD_LIB.TIMECARD(SCH_1):R_SHT3X_RST_N':
 C_SIGNAL='@timecard_lib.timecard(sch_1):r_sht3x_rst_n';
NODE_NAME     R298 1
 '@TIMECARD_LIB.TIMECARD(SCH_1):PAGE7_I33@PASSIVE.RESISTOR(CHIPS)':
 '1': CDS_PINID='\1\';
NODE_NAME     R296 2
 '@TIMECARD_LIB.TIMECARD(SCH_1):PAGE7_I38@PASSIVE.RESISTOR(CHIPS)':
 '2': CDS_PINID='\2\';
NODE_NAME     R297 1
 '@TIMECARD_LIB.TIMECARD(SCH_1):PAGE7_I39@PASSIVE.RESISTOR(CHIPS)':
 '1': CDS_PINID='\1\';
NODE_NAME     U27 6
 '@TIMECARD_LIB.TIMECARD(SCH_1):PAGE7_I44@ANALOG.SHT31A_DIS_B10KS_DFN8(CHIPS)':
 'RESET*': CDS_PINID='\reset*\';
NODE_NAME     TP26 1
 '@TIMECARD_LIB.TIMECARD(SCH_1):PAGE16_I1660@CLS.TP_PIONT(CHIPS)':
 '1': CDS_PINID='\1\';
NET_NAME
'R_XP3R3V_PG'
 '@TIMECARD_LIB.TIMECARD(SCH_1):R_XP3R3V_PG':
 C_SIGNAL='@timecard_lib.timecard(sch_1):r_xp3r3v_pg';
NODE_NAME     C77 2
 '@TIMECARD_LIB.TIMECARD(SCH_1):PAGE517_I2@PASSIVE.CAPACITOR(CHIPS)':
 '2': CDS_PINID='\2\';
NODE_NAME     R51 2
 '@TIMECARD_LIB.TIMECARD(SCH_1):PAGE517_I3@PASSIVE.RESISTOR(CHIPS)':
 '2': CDS_PINID='\2\';
NODE_NAME     U6 18
 '@TIMECARD_LIB.TIMECARD(SCH_1):PAGE517_I42@STDLOGIC.TPS54824RNVR_VQFN18(CHIPS)':
 'PGOOD': CDS_PINID='PGOOD';
NODE_NAME     R263 1
 '@TIMECARD_LIB.TIMECARD(SCH_1):PAGE517_I47@PASSIVE.RESISTOR(CHIPS)':
 '1': CDS_PINID='\1\';
NET_NAME
'R_XP5R0V_EN'
 '@TIMECARD_LIB.TIMECARD(SCH_1):R_XP5R0V_EN':
 C_SIGNAL='@timecard_lib.timecard(sch_1):r_xp5r0v_en';
NODE_NAME     R48 1
 '@TIMECARD_LIB.TIMECARD(SCH_1):PAGE516_I9@PASSIVE.RESISTOR(CHIPS)':
 '1': CDS_PINID='\1\';
NODE_NAME     C29 1
 '@TIMECARD_LIB.TIMECARD(SCH_1):PAGE516_I10@PASSIVE.CAPACITOR(CHIPS)':
 '1': CDS_PINID='\1\';
NODE_NAME     R49 2
 '@TIMECARD_LIB.TIMECARD(SCH_1):PAGE516_I16@PASSIVE.RESISTOR(CHIPS)':
 '2': CDS_PINID='\2\';
NODE_NAME     U5 17
 '@TIMECARD_LIB.TIMECARD(SCH_1):PAGE516_I42@STDLOGIC.TPS54824RNVR_VQFN18(CHIPS)':
 'EN': CDS_PINID='EN';
NODE_NAME     R142 2
 '@TIMECARD_LIB.TIMECARD(SCH_1):PAGE516_I44@PASSIVE.RESISTOR(CHIPS)':
 '2': CDS_PINID='\2\';
NET_NAME
'SEC_EEPROM_SDA'
 '@TIMECARD_LIB.TIMECARD(SCH_1):SEC_EEPROM_SDA':
 C_SIGNAL='@timecard_lib.timecard(sch_1):sec_eeprom_sda';
NODE_NAME     U19 5
 '@TIMECARD_LIB.TIMECARD(SCH_1):PAGE5_I151@MEMORY.24LC16BT_I_ST_TSSOP8(CHIPS)':
 'SDA': CDS_PINID='SDA';
NODE_NAME     R45 2
 '@TIMECARD_LIB.TIMECARD(SCH_1):PAGE5_I162@PASSIVE.RESISTOR(CHIPS)':
 '2': CDS_PINID='\2\';
NET_NAME
'SEC_EEPROM_WP'
 '@TIMECARD_LIB.TIMECARD(SCH_1):SEC_EEPROM_WP':
 C_SIGNAL='@timecard_lib.timecard(sch_1):sec_eeprom_wp';
NODE_NAME     J17 3
 '@TIMECARD_LIB.TIMECARD(SCH_1):PAGE5_I127@CONNECTOR.CONN_HDR_2X2_M_S_SMT(CHIPS)':
 '3': CDS_PINID='\3\';
NODE_NAME     U19 7
 '@TIMECARD_LIB.TIMECARD(SCH_1):PAGE5_I151@MEMORY.24LC16BT_I_ST_TSSOP8(CHIPS)':
 'WP': CDS_PINID='WP';
NODE_NAME     R24 1
 '@TIMECARD_LIB.TIMECARD(SCH_1):PAGE5_I167@PASSIVE.RESISTOR(CHIPS)':
 '1': CDS_PINID='\1\';
NODE_NAME     R3 2
 '@TIMECARD_LIB.TIMECARD(SCH_1):PAGE5_I169@PASSIVE.RESISTOR(CHIPS)':
 '2': CDS_PINID='\2\';
NODE_NAME     R2 2
 '@TIMECARD_LIB.TIMECARD(SCH_1):PAGE5_I173@PASSIVE.RESISTOR(CHIPS)':
 '2': CDS_PINID='\2\';
NODE_NAME     TP20 1
 '@TIMECARD_LIB.TIMECARD(SCH_1):PAGE16_I1615@CLS.TP_PIONT(CHIPS)':
 '1': CDS_PINID='\1\';
NET_NAME
'SG'
 '@TIMECARD_LIB.TIMECARD(SCH_1):SG':
 C_SIGNAL='@timecard_lib.timecard(sch_1):sg',
 CDS_GLOBAL_NET='TRUE';
NODE_NAME     C37 2
 '@TIMECARD_LIB.TIMECARD(SCH_1):PAGE3_I4@PASSIVE.CAPACITOR(CHIPS)':
 '2': CDS_PINID='\2\';
NODE_NAME     GF1 B4
 '@TIMECARD_LIB.TIMECARD(SCH_1):PAGE3_I61@CONNECTOR.CONN_64P_GF(CHIPS)':
 'GND1': CDS_PINID='GND1';
NODE_NAME     GF1 A4
 '@TIMECARD_LIB.TIMECARD(SCH_1):PAGE3_I61@CONNECTOR.CONN_64P_GF(CHIPS)':
 'GND2': CDS_PINID='GND2';
NODE_NAME     GF1 B7
 '@TIMECARD_LIB.TIMECARD(SCH_1):PAGE3_I61@CONNECTOR.CONN_64P_GF(CHIPS)':
 'GND3': CDS_PINID='GND3';
NODE_NAME     GF1 A12
 '@TIMECARD_LIB.TIMECARD(SCH_1):PAGE3_I61@CONNECTOR.CONN_64P_GF(CHIPS)':
 'GND4': CDS_PINID='GND4';
NODE_NAME     GF1 B13
 '@TIMECARD_LIB.TIMECARD(SCH_1):PAGE3_I61@CONNECTOR.CONN_64P_GF(CHIPS)':
 'GND5': CDS_PINID='GND5';
NODE_NAME     GF1 A15
 '@TIMECARD_LIB.TIMECARD(SCH_1):PAGE3_I61@CONNECTOR.CONN_64P_GF(CHIPS)':
 'GND6': CDS_PINID='GND6';
NODE_NAME     GF1 B16
 '@TIMECARD_LIB.TIMECARD(SCH_1):PAGE3_I61@CONNECTOR.CONN_64P_GF(CHIPS)':
 'GND7': CDS_PINID='GND7';
NODE_NAME     GF1 A18
 '@TIMECARD_LIB.TIMECARD(SCH_1):PAGE3_I61@CONNECTOR.CONN_64P_GF(CHIPS)':
 'GND8': CDS_PINID='GND8';
NODE_NAME     GF1 B18
 '@TIMECARD_LIB.TIMECARD(SCH_1):PAGE3_I61@CONNECTOR.CONN_64P_GF(CHIPS)':
 'GND9': CDS_PINID='GND9';
NODE_NAME     GF1 A20
 '@TIMECARD_LIB.TIMECARD(SCH_1):PAGE3_I61@CONNECTOR.CONN_64P_GF(CHIPS)':
 'GND10': CDS_PINID='GND10';
NODE_NAME     GF1 B21
 '@TIMECARD_LIB.TIMECARD(SCH_1):PAGE3_I61@CONNECTOR.CONN_64P_GF(CHIPS)':
 'GND11': CDS_PINID='GND11';
NODE_NAME     GF1 B22
 '@TIMECARD_LIB.TIMECARD(SCH_1):PAGE3_I61@CONNECTOR.CONN_64P_GF(CHIPS)':
 'GND12': CDS_PINID='GND12';
NODE_NAME     GF1 A23
 '@TIMECARD_LIB.TIMECARD(SCH_1):PAGE3_I61@CONNECTOR.CONN_64P_GF(CHIPS)':
 'GND13': CDS_PINID='GND13';
NODE_NAME     GF1 A24
 '@TIMECARD_LIB.TIMECARD(SCH_1):PAGE3_I61@CONNECTOR.CONN_64P_GF(CHIPS)':
 'GND14': CDS_PINID='GND14';
NODE_NAME     GF1 B25
 '@TIMECARD_LIB.TIMECARD(SCH_1):PAGE3_I61@CONNECTOR.CONN_64P_GF(CHIPS)':
 'GND15': CDS_PINID='GND15';
NODE_NAME     GF1 B26
 '@TIMECARD_LIB.TIMECARD(SCH_1):PAGE3_I61@CONNECTOR.CONN_64P_GF(CHIPS)':
 'GND17': CDS_PINID='GND17';
NODE_NAME     GF1 A27
 '@TIMECARD_LIB.TIMECARD(SCH_1):PAGE3_I61@CONNECTOR.CONN_64P_GF(CHIPS)':
 'GND18': CDS_PINID='GND18';
NODE_NAME     GF1 A28
 '@TIMECARD_LIB.TIMECARD(SCH_1):PAGE3_I61@CONNECTOR.CONN_64P_GF(CHIPS)':
 'GND19': CDS_PINID='GND19';
NODE_NAME     GF1 B29
 '@TIMECARD_LIB.TIMECARD(SCH_1):PAGE3_I61@CONNECTOR.CONN_64P_GF(CHIPS)':
 'GND20': CDS_PINID='GND20';
NODE_NAME     GF1 A31
 '@TIMECARD_LIB.TIMECARD(SCH_1):PAGE3_I61@CONNECTOR.CONN_64P_GF(CHIPS)':
 'GND21': CDS_PINID='GND21';
NODE_NAME     GF1 B32
 '@TIMECARD_LIB.TIMECARD(SCH_1):PAGE3_I61@CONNECTOR.CONN_64P_GF(CHIPS)':
 'GND22': CDS_PINID='GND22';
NODE_NAME     R334 2
 '@TIMECARD_LIB.TIMECARD(SCH_1):PAGE6_I30@PASSIVE.RESISTOR(CHIPS)':
 '2': CDS_PINID='\2\';
NODE_NAME     R336 2
 '@TIMECARD_LIB.TIMECARD(SCH_1):PAGE6_I32@PASSIVE.RESISTOR(CHIPS)':
 '2': CDS_PINID='\2\';
NODE_NAME     R338 2
 '@TIMECARD_LIB.TIMECARD(SCH_1):PAGE6_I33@PASSIVE.RESISTOR(CHIPS)':
 '2': CDS_PINID='\2\';
NODE_NAME     C39 1
 '@TIMECARD_LIB.TIMECARD(SCH_1):PAGE6_I37@PASSIVE.CAPACITOR(CHIPS)':
 '1': CDS_PINID='\1\';
NODE_NAME     U8 4
 '@TIMECARD_LIB.TIMECARD(SCH_1):PAGE6_I38@INTERFACE.LM75BDP_TSSOP8(CHIPS)':
 'GND': CDS_PINID='GND';
NODE_NAME     R69 2
 '@TIMECARD_LIB.TIMECARD(SCH_1):PAGE7_I7@PASSIVE.RESISTOR(CHIPS)':
 '2': CDS_PINID='\2\';
NODE_NAME     C51 2
 '@TIMECARD_LIB.TIMECARD(SCH_1):PAGE9_I17@PASSIVE.CAPACITOR(CHIPS)':
 '2': CDS_PINID='\2\';
NODE_NAME     C72 2
 '@TIMECARD_LIB.TIMECARD(SCH_1):PAGE11_I12@PASSIVE.CAPACITOR(CHIPS)':
 '2': CDS_PINID='\2\';
NODE_NAME     C73 2
 '@TIMECARD_LIB.TIMECARD(SCH_1):PAGE11_I13@PASSIVE.CAPACITOR(CHIPS)':
 '2': CDS_PINID='\2\';
NODE_NAME     C78 2
 '@TIMECARD_LIB.TIMECARD(SCH_1):PAGE11_I15@PASSIVE.CAPACITOR(CHIPS)':
 '2': CDS_PINID='\2\';
NODE_NAME     R114 2
 '@TIMECARD_LIB.TIMECARD(SCH_1):PAGE11_I18@PASSIVE.RESISTOR(CHIPS)':
 '2': CDS_PINID='\2\';
NODE_NAME     C79 2
 '@TIMECARD_LIB.TIMECARD(SCH_1):PAGE11_I24@PASSIVE.CAPACITOR(CHIPS)':
 '2': CDS_PINID='\2\';
NODE_NAME     C80 2
 '@TIMECARD_LIB.TIMECARD(SCH_1):PAGE11_I26@PASSIVE.CAPACITOR(CHIPS)':
 '2': CDS_PINID='\2\';
NODE_NAME     CR5 1
 '@TIMECARD_LIB.TIMECARD(SCH_1):PAGE12_I42@DISCRETE.DIODE_4_V1(CHIPS)':
 'GND': CDS_PINID='GND';
NODE_NAME     R55 2
 '@TIMECARD_LIB.TIMECARD(SCH_1):PAGE3_I62@PASSIVE.RESISTOR(CHIPS)':
 '2': CDS_PINID='\2\';
NODE_NAME     C77 1
 '@TIMECARD_LIB.TIMECARD(SCH_1):PAGE517_I2@PASSIVE.CAPACITOR(CHIPS)':
 '1': CDS_PINID='\1\';
NODE_NAME     C76 2
 '@TIMECARD_LIB.TIMECARD(SCH_1):PAGE517_I6@PASSIVE.CAPACITOR(CHIPS)':
 '2': CDS_PINID='\2\';
NODE_NAME     R52 2
 '@TIMECARD_LIB.TIMECARD(SCH_1):PAGE517_I11@PASSIVE.RESISTOR(CHIPS)':
 '2': CDS_PINID='\2\';
NODE_NAME     C46 2
 '@TIMECARD_LIB.TIMECARD(SCH_1):PAGE517_I12@PASSIVE.CAPACITOR(CHIPS)':
 '2': CDS_PINID='\2\';
NODE_NAME     C48 2
 '@TIMECARD_LIB.TIMECARD(SCH_1):PAGE517_I14@PASSIVE.CAPACITOR(CHIPS)':
 '2': CDS_PINID='\2\';
NODE_NAME     C50 2
 '@TIMECARD_LIB.TIMECARD(SCH_1):PAGE517_I15@PASSIVE.CAPACITOR(CHIPS)':
 '2': CDS_PINID='\2\';
NODE_NAME     C52 2
 '@TIMECARD_LIB.TIMECARD(SCH_1):PAGE517_I16@PASSIVE.CAPACITOR(CHIPS)':
 '2': CDS_PINID='\2\';
NODE_NAME     C53 2
 '@TIMECARD_LIB.TIMECARD(SCH_1):PAGE517_I21@PASSIVE.CAPACITOR(CHIPS)':
 '2': CDS_PINID='\2\';
NODE_NAME     SP2 1
 '@TIMECARD_LIB.TIMECARD(SCH_1):PAGE517_I24@MECH.SOLDER_PREFORM(CHIPS)':
 '1': CDS_PINID='\1\';
NODE_NAME     R39 2
 '@TIMECARD_LIB.TIMECARD(SCH_1):PAGE517_I32@PASSIVE.RESISTOR(CHIPS)':
 '2': CDS_PINID='\2\';
NODE_NAME     C18 2
 '@TIMECARD_LIB.TIMECARD(SCH_1):PAGE517_I36@PASSIVE.CAPACITOR(CHIPS)':
 '2': CDS_PINID='\2\';
NODE_NAME     C20 2
 '@TIMECARD_LIB.TIMECARD(SCH_1):PAGE517_I37@PASSIVE.CAPACITOR(CHIPS)':
 '2': CDS_PINID='\2\';
NODE_NAME     C21 2
 '@TIMECARD_LIB.TIMECARD(SCH_1):PAGE517_I38@PASSIVE.CAPACITOR(CHIPS)':
 '2': CDS_PINID='\2\';
NODE_NAME     C22 2
 '@TIMECARD_LIB.TIMECARD(SCH_1):PAGE517_I40@PASSIVE.CAPACITOR(CHIPS)':
 '2': CDS_PINID='\2\';
NODE_NAME     U6 3
 '@TIMECARD_LIB.TIMECARD(SCH_1):PAGE517_I42@STDLOGIC.TPS54824RNVR_VQFN18(CHIPS)':
 'PGND_1': CDS_PINID='PGND_1';
NODE_NAME     U6 4
 '@TIMECARD_LIB.TIMECARD(SCH_1):PAGE517_I42@STDLOGIC.TPS54824RNVR_VQFN18(CHIPS)':
 'PGND_2': CDS_PINID='PGND_2';
NODE_NAME     U6 5
 '@TIMECARD_LIB.TIMECARD(SCH_1):PAGE517_I42@STDLOGIC.TPS54824RNVR_VQFN18(CHIPS)':
 'PGND_3': CDS_PINID='PGND_3';
NODE_NAME     U6 8
 '@TIMECARD_LIB.TIMECARD(SCH_1):PAGE517_I42@STDLOGIC.TPS54824RNVR_VQFN18(CHIPS)':
 'PGND_4': CDS_PINID='PGND_4';
NODE_NAME     U6 9
 '@TIMECARD_LIB.TIMECARD(SCH_1):PAGE517_I42@STDLOGIC.TPS54824RNVR_VQFN18(CHIPS)':
 'PGND_5': CDS_PINID='PGND_5';
NODE_NAME     U6 10
 '@TIMECARD_LIB.TIMECARD(SCH_1):PAGE517_I42@STDLOGIC.TPS54824RNVR_VQFN18(CHIPS)':
 'PGND_6': CDS_PINID='PGND_6';
NODE_NAME     C74 2
 '@TIMECARD_LIB.TIMECARD(SCH_1):PAGE516_I4@PASSIVE.CAPACITOR(CHIPS)':
 '2': CDS_PINID='\2\';
NODE_NAME     C75 1
 '@TIMECARD_LIB.TIMECARD(SCH_1):PAGE516_I7@PASSIVE.CAPACITOR(CHIPS)':
 '1': CDS_PINID='\1\';
NODE_NAME     R48 2
 '@TIMECARD_LIB.TIMECARD(SCH_1):PAGE516_I9@PASSIVE.RESISTOR(CHIPS)':
 '2': CDS_PINID='\2\';
NODE_NAME     C29 2
 '@TIMECARD_LIB.TIMECARD(SCH_1):PAGE516_I10@PASSIVE.CAPACITOR(CHIPS)':
 '2': CDS_PINID='\2\';
NODE_NAME     C30 2
 '@TIMECARD_LIB.TIMECARD(SCH_1):PAGE516_I18@PASSIVE.CAPACITOR(CHIPS)':
 '2': CDS_PINID='\2\';
NODE_NAME     C32 2
 '@TIMECARD_LIB.TIMECARD(SCH_1):PAGE516_I19@PASSIVE.CAPACITOR(CHIPS)':
 '2': CDS_PINID='\2\';
NODE_NAME     C33 2
 '@TIMECARD_LIB.TIMECARD(SCH_1):PAGE516_I20@PASSIVE.CAPACITOR(CHIPS)':
 '2': CDS_PINID='\2\';
NODE_NAME     C41 2
 '@TIMECARD_LIB.TIMECARD(SCH_1):PAGE516_I22@PASSIVE.CAPACITOR(CHIPS)':
 '2': CDS_PINID='\2\';
NODE_NAME     SP1 1
 '@TIMECARD_LIB.TIMECARD(SCH_1):PAGE516_I24@MECH.SOLDER_PREFORM(CHIPS)':
 '1': CDS_PINID='\1\';
NODE_NAME     C12 2
 '@TIMECARD_LIB.TIMECARD(SCH_1):PAGE516_I32@PASSIVE.CAPACITOR(CHIPS)':
 '2': CDS_PINID='\2\';
NODE_NAME     C13 2
 '@TIMECARD_LIB.TIMECARD(SCH_1):PAGE516_I33@PASSIVE.CAPACITOR(CHIPS)':
 '2': CDS_PINID='\2\';
NODE_NAME     C14 2
 '@TIMECARD_LIB.TIMECARD(SCH_1):PAGE516_I35@PASSIVE.CAPACITOR(CHIPS)':
 '2': CDS_PINID='\2\';
NODE_NAME     R33 2
 '@TIMECARD_LIB.TIMECARD(SCH_1):PAGE516_I38@PASSIVE.RESISTOR(CHIPS)':
 '2': CDS_PINID='\2\';
NODE_NAME     C15 2
 '@TIMECARD_LIB.TIMECARD(SCH_1):PAGE516_I40@PASSIVE.CAPACITOR(CHIPS)':
 '2': CDS_PINID='\2\';
NODE_NAME     U5 3
 '@TIMECARD_LIB.TIMECARD(SCH_1):PAGE516_I42@STDLOGIC.TPS54824RNVR_VQFN18(CHIPS)':
 'PGND_1': CDS_PINID='PGND_1';
NODE_NAME     U5 4
 '@TIMECARD_LIB.TIMECARD(SCH_1):PAGE516_I42@STDLOGIC.TPS54824RNVR_VQFN18(CHIPS)':
 'PGND_2': CDS_PINID='PGND_2';
NODE_NAME     U5 5
 '@TIMECARD_LIB.TIMECARD(SCH_1):PAGE516_I42@STDLOGIC.TPS54824RNVR_VQFN18(CHIPS)':
 'PGND_3': CDS_PINID='PGND_3';
NODE_NAME     U5 8
 '@TIMECARD_LIB.TIMECARD(SCH_1):PAGE516_I42@STDLOGIC.TPS54824RNVR_VQFN18(CHIPS)':
 'PGND_4': CDS_PINID='PGND_4';
NODE_NAME     U5 9
 '@TIMECARD_LIB.TIMECARD(SCH_1):PAGE516_I42@STDLOGIC.TPS54824RNVR_VQFN18(CHIPS)':
 'PGND_5': CDS_PINID='PGND_5';
NODE_NAME     U5 10
 '@TIMECARD_LIB.TIMECARD(SCH_1):PAGE516_I42@STDLOGIC.TPS54824RNVR_VQFN18(CHIPS)':
 'PGND_6': CDS_PINID='PGND_6';
NODE_NAME     C17 2
 '@TIMECARD_LIB.TIMECARD(SCH_1):PAGE3_I92@PASSIVE.CAPACITOR(CHIPS)':
 '2': CDS_PINID='\2\';
NODE_NAME     U2 4
 '@TIMECARD_LIB.TIMECARD(SCH_1):PAGE3_I100@STDLOGIC.G220_10198_01(CHIPS)':
 'GND': CDS_PINID='GND';
NODE_NAME     C38 2
 '@TIMECARD_LIB.TIMECARD(SCH_1):PAGE5_I45@PASSIVE.CAPACITOR(CHIPS)':
 '2': CDS_PINID='\2\';
NODE_NAME     U4 8
 '@TIMECARD_LIB.TIMECARD(SCH_1):PAGE5_I54@INTERFACE.PCA9546APW_TSSOP16(CHIPS)':
 'VSS': CDS_PINID='VSS';
NODE_NAME     R155 1
 '@TIMECARD_LIB.TIMECARD(SCH_1):PAGE5_I66@PASSIVE.RESISTOR(CHIPS)':
 '1': CDS_PINID='\1\';
NODE_NAME     C3 2
 '@TIMECARD_LIB.TIMECARD(SCH_1):PAGE15_I156@PASSIVE.CAPACITOR(CHIPS)':
 '2': CDS_PINID='\2\';
NODE_NAME     CR10 A
 '@TIMECARD_LIB.TIMECARD(SCH_1):PAGE15_I159@DISCRETE.DIODE_2E(CHIPS)':
 'A': CDS_PINID='A';
NODE_NAME     C2 2
 '@TIMECARD_LIB.TIMECARD(SCH_1):PAGE15_I160@PASSIVE.CAPACITOR(CHIPS)':
 '2': CDS_PINID='\2\';
NODE_NAME     R5 2
 '@TIMECARD_LIB.TIMECARD(SCH_1):PAGE15_I169@PASSIVE.RESISTOR(CHIPS)':
 '2': CDS_PINID='\2\';
NODE_NAME     R46 1
 '@TIMECARD_LIB.TIMECARD(SCH_1):PAGE15_I171@PASSIVE.RESISTOR(CHIPS)':
 '1': CDS_PINID='\1\';
NODE_NAME     C4 1
 '@TIMECARD_LIB.TIMECARD(SCH_1):PAGE15_I172@PASSIVE.CAPACITOR(CHIPS)':
 '1': CDS_PINID='\1\';
NODE_NAME     R8 1
 '@TIMECARD_LIB.TIMECARD(SCH_1):PAGE15_I173@PASSIVE.RESISTOR(CHIPS)':
 '1': CDS_PINID='\1\';
NODE_NAME     R7 1
 '@TIMECARD_LIB.TIMECARD(SCH_1):PAGE15_I174@PASSIVE.RESISTOR(CHIPS)':
 '1': CDS_PINID='\1\';
NODE_NAME     R10 2
 '@TIMECARD_LIB.TIMECARD(SCH_1):PAGE15_I183@PASSIVE.RESISTOR(CHIPS)':
 '2': CDS_PINID='\2\';
NODE_NAME     C7 2
 '@TIMECARD_LIB.TIMECARD(SCH_1):PAGE15_I185@PASSIVE.CAPACITOR(CHIPS)':
 '2': CDS_PINID='\2\';
NODE_NAME     R14 2
 '@TIMECARD_LIB.TIMECARD(SCH_1):PAGE15_I186@PASSIVE.RESISTOR(CHIPS)':
 '2': CDS_PINID='\2\';
NODE_NAME     R16 2
 '@TIMECARD_LIB.TIMECARD(SCH_1):PAGE15_I188@PASSIVE.RESISTOR(CHIPS)':
 '2': CDS_PINID='\2\';
NODE_NAME     C6 2
 '@TIMECARD_LIB.TIMECARD(SCH_1):PAGE15_I196@PASSIVE.CAPACITOR(CHIPS)':
 '2': CDS_PINID='\2\';
NODE_NAME     R12 2
 '@TIMECARD_LIB.TIMECARD(SCH_1):PAGE15_I197@PASSIVE.RESISTOR(CHIPS)':
 '2': CDS_PINID='\2\';
NODE_NAME     C8 2
 '@TIMECARD_LIB.TIMECARD(SCH_1):PAGE15_I201@PASSIVE.CAPACITOR(CHIPS)':
 '2': CDS_PINID='\2\';
NODE_NAME     CR3 A
 '@TIMECARD_LIB.TIMECARD(SCH_1):PAGE15_I204@DISCRETE.DIODE_2(CHIPS)':
 'A': CDS_PINID='A';
NODE_NAME     C9 2
 '@TIMECARD_LIB.TIMECARD(SCH_1):PAGE15_I206@PASSIVE.CAPACITOR(CHIPS)':
 '2': CDS_PINID='\2\';
NODE_NAME     C10 2
 '@TIMECARD_LIB.TIMECARD(SCH_1):PAGE15_I207@PASSIVE.CAPACITOR(CHIPS)':
 '2': CDS_PINID='\2\';
NODE_NAME     C5 2
 '@TIMECARD_LIB.TIMECARD(SCH_1):PAGE15_I211@PASSIVE.CAPACITOR(CHIPS)':
 '2': CDS_PINID='\2\';
NODE_NAME     U1 7
 '@TIMECARD_LIB.TIMECARD(SCH_1):PAGE15_I212@STDLOGIC.MP5022CGQV_Z_QFN22(CHIPS)':
 'GND': CDS_PINID='GND';
NODE_NAME     R165 2
 '@TIMECARD_LIB.TIMECARD(SCH_1):PAGE68_I2@PASSIVE.RESISTOR(CHIPS)':
 '2': CDS_PINID='\2\';
NODE_NAME     C184 2
 '@TIMECARD_LIB.TIMECARD(SCH_1):PAGE68_I3@PASSIVE.CAPACITOR(CHIPS)':
 '2': CDS_PINID='\2\';
NODE_NAME     C190 2
 '@TIMECARD_LIB.TIMECARD(SCH_1):PAGE68_I5@PASSIVE.CAPACITOR(CHIPS)':
 '2': CDS_PINID='\2\';
NODE_NAME     U20 5
 '@TIMECARD_LIB.TIMECARD(SCH_1):PAGE68_I6@ANALOG.ISL80101IRAJZ_DFN10(CHIPS)':
 'GND': CDS_PINID='GND';
NODE_NAME     U20 11
 '@TIMECARD_LIB.TIMECARD(SCH_1):PAGE68_I6@ANALOG.ISL80101IRAJZ_DFN10(CHIPS)':
 'THRM_PAD': CDS_PINID='THRM_PAD';
NODE_NAME     C192 2
 '@TIMECARD_LIB.TIMECARD(SCH_1):PAGE68_I9@PASSIVE.CAPACITOR(CHIPS)':
 '2': CDS_PINID='\2\';
NODE_NAME     R186 1
 '@TIMECARD_LIB.TIMECARD(SCH_1):PAGE68_I14@PASSIVE.RESISTOR(CHIPS)':
 '1': CDS_PINID='\1\';
NODE_NAME     R189 1
 '@TIMECARD_LIB.TIMECARD(SCH_1):PAGE68_I16@PASSIVE.RESISTOR(CHIPS)':
 '1': CDS_PINID='\1\';
NODE_NAME     C185 2
 '@TIMECARD_LIB.TIMECARD(SCH_1):PAGE68_I27@PASSIVE.CAPACITOR(CHIPS)':
 '2': CDS_PINID='\2\';
NODE_NAME     C188 2
 '@TIMECARD_LIB.TIMECARD(SCH_1):PAGE68_I35@PASSIVE.CAPACITOR(CHIPS)':
 '2': CDS_PINID='\2\';
NODE_NAME     R174 2
 '@TIMECARD_LIB.TIMECARD(SCH_1):PAGE68_I44@PASSIVE.RESISTOR(CHIPS)':
 '2': CDS_PINID='\2\';
NODE_NAME     C187 2
 '@TIMECARD_LIB.TIMECARD(SCH_1):PAGE68_I46@PASSIVE.CAPACITOR(CHIPS)':
 '2': CDS_PINID='\2\';
NODE_NAME     C186 2
 '@TIMECARD_LIB.TIMECARD(SCH_1):PAGE68_I47@PASSIVE.CAPACITOR(CHIPS)':
 '2': CDS_PINID='\2\';
NODE_NAME     C191 2
 '@TIMECARD_LIB.TIMECARD(SCH_1):PAGE68_I49@PASSIVE.CAPACITOR(CHIPS)':
 '2': CDS_PINID='\2\';
NODE_NAME     C189 2
 '@TIMECARD_LIB.TIMECARD(SCH_1):PAGE68_I51@PASSIVE.CAPACITOR(CHIPS)':
 '2': CDS_PINID='\2\';
NODE_NAME     U21 5
 '@TIMECARD_LIB.TIMECARD(SCH_1):PAGE68_I52@ANALOG.ISL80101IRAJZ_DFN10(CHIPS)':
 'GND': CDS_PINID='GND';
NODE_NAME     U21 11
 '@TIMECARD_LIB.TIMECARD(SCH_1):PAGE68_I52@ANALOG.ISL80101IRAJZ_DFN10(CHIPS)':
 'THRM_PAD': CDS_PINID='THRM_PAD';
NODE_NAME     C194 2
 '@TIMECARD_LIB.TIMECARD(SCH_1):PAGE68_I60@PASSIVE.CAPACITOR(CHIPS)':
 '2': CDS_PINID='\2\';
NODE_NAME     C196 2
 '@TIMECARD_LIB.TIMECARD(SCH_1):PAGE68_I61@PASSIVE.CAPACITOR(CHIPS)':
 '2': CDS_PINID='\2\';
NODE_NAME     C193 2
 '@TIMECARD_LIB.TIMECARD(SCH_1):PAGE68_I71@PASSIVE.CAPACITOR(CHIPS)':
 '2': CDS_PINID='\2\';
NODE_NAME     R188 1
 '@TIMECARD_LIB.TIMECARD(SCH_1):PAGE68_I79@PASSIVE.RESISTOR(CHIPS)':
 '1': CDS_PINID='\1\';
NODE_NAME     R190 1
 '@TIMECARD_LIB.TIMECARD(SCH_1):PAGE68_I80@PASSIVE.RESISTOR(CHIPS)':
 '1': CDS_PINID='\1\';
NODE_NAME     C195 2
 '@TIMECARD_LIB.TIMECARD(SCH_1):PAGE68_I81@PASSIVE.CAPACITOR(CHIPS)':
 '2': CDS_PINID='\2\';
NODE_NAME     C197 2
 '@TIMECARD_LIB.TIMECARD(SCH_1):PAGE68_I83@PASSIVE.CAPACITOR(CHIPS)':
 '2': CDS_PINID='\2\';
NODE_NAME     C180 2
 '@TIMECARD_LIB.TIMECARD(SCH_1):PAGE68_I93@PASSIVE.CAPACITOR(CHIPS)':
 '2': CDS_PINID='\2\';
NODE_NAME     C182 2
 '@TIMECARD_LIB.TIMECARD(SCH_1):PAGE68_I94@PASSIVE.CAPACITOR(CHIPS)':
 '2': CDS_PINID='\2\';
NODE_NAME     C181 2
 '@TIMECARD_LIB.TIMECARD(SCH_1):PAGE68_I97@PASSIVE.CAPACITOR(CHIPS)':
 '2': CDS_PINID='\2\';
NODE_NAME     C183 2
 '@TIMECARD_LIB.TIMECARD(SCH_1):PAGE68_I98@PASSIVE.CAPACITOR(CHIPS)':
 '2': CDS_PINID='\2\';
NODE_NAME     U24 N9
 '@TIMECARD_LIB.TIMECARD(SCH_1):PAGE127_I232@PLD.XC7A200T_2FBG484C_FBG484(CHIPS)':
 'DXN_0': CDS_PINID='DXN_0';
NODE_NAME     U24 N10
 '@TIMECARD_LIB.TIMECARD(SCH_1):PAGE127_I232@PLD.XC7A200T_2FBG484C_FBG484(CHIPS)':
 'DXP_0': CDS_PINID='DXP_0';
NODE_NAME     U24 M9
 '@TIMECARD_LIB.TIMECARD(SCH_1):PAGE127_I232@PLD.XC7A200T_2FBG484C_FBG484(CHIPS)':
 'VN_0': CDS_PINID='VN_0';
NODE_NAME     U24 L10
 '@TIMECARD_LIB.TIMECARD(SCH_1):PAGE127_I232@PLD.XC7A200T_2FBG484C_FBG484(CHIPS)':
 'VP_0': CDS_PINID='VP_0';
NODE_NAME     U24 L9
 '@TIMECARD_LIB.TIMECARD(SCH_1):PAGE127_I232@PLD.XC7A200T_2FBG484C_FBG484(CHIPS)':
 'VREFN_0': CDS_PINID='VREFN_0';
NODE_NAME     U24 M10
 '@TIMECARD_LIB.TIMECARD(SCH_1):PAGE127_I232@PLD.XC7A200T_2FBG484C_FBG484(CHIPS)':
 'VREFP_0': CDS_PINID='VREFP_0';
NODE_NAME     R216 2
 '@TIMECARD_LIB.TIMECARD(SCH_1):PAGE127_I391@PASSIVE.RESISTOR(CHIPS)':
 '2': CDS_PINID='\2\';
NODE_NAME     R220 2
 '@TIMECARD_LIB.TIMECARD(SCH_1):PAGE127_I393@PASSIVE.RESISTOR(CHIPS)':
 '2': CDS_PINID='\2\';
NODE_NAME     R214 2
 '@TIMECARD_LIB.TIMECARD(SCH_1):PAGE127_I397@PASSIVE.RESISTOR(CHIPS)':
 '2': CDS_PINID='\2\';
NODE_NAME     R222 2
 '@TIMECARD_LIB.TIMECARD(SCH_1):PAGE127_I405@PASSIVE.RESISTOR(CHIPS)':
 '2': CDS_PINID='\2\';
NODE_NAME     R218 2
 '@TIMECARD_LIB.TIMECARD(SCH_1):PAGE127_I406@PASSIVE.RESISTOR(CHIPS)':
 '2': CDS_PINID='\2\';
NODE_NAME     R212 2
 '@TIMECARD_LIB.TIMECARD(SCH_1):PAGE127_I407@PASSIVE.RESISTOR(CHIPS)':
 '2': CDS_PINID='\2\';
NODE_NAME     U24 A11
 '@TIMECARD_LIB.TIMECARD(SCH_1):PAGE164_I138@PLD.XC7A200T_2FBG484C_FBG484(CHIPS)':
 'GND_1': CDS_PINID='GND_1';
NODE_NAME     U24 A12
 '@TIMECARD_LIB.TIMECARD(SCH_1):PAGE164_I138@PLD.XC7A200T_2FBG484C_FBG484(CHIPS)':
 'GND_2': CDS_PINID='GND_2';
NODE_NAME     U24 A2
 '@TIMECARD_LIB.TIMECARD(SCH_1):PAGE164_I138@PLD.XC7A200T_2FBG484C_FBG484(CHIPS)':
 'GND_3': CDS_PINID='GND_3';
NODE_NAME     U24 A22
 '@TIMECARD_LIB.TIMECARD(SCH_1):PAGE164_I138@PLD.XC7A200T_2FBG484C_FBG484(CHIPS)':
 'GND_4': CDS_PINID='GND_4';
NODE_NAME     U24 A3
 '@TIMECARD_LIB.TIMECARD(SCH_1):PAGE164_I138@PLD.XC7A200T_2FBG484C_FBG484(CHIPS)':
 'GND_5': CDS_PINID='GND_5';
NODE_NAME     U24 A5
 '@TIMECARD_LIB.TIMECARD(SCH_1):PAGE164_I138@PLD.XC7A200T_2FBG484C_FBG484(CHIPS)':
 'GND_6': CDS_PINID='GND_6';
NODE_NAME     U24 A7
 '@TIMECARD_LIB.TIMECARD(SCH_1):PAGE164_I138@PLD.XC7A200T_2FBG484C_FBG484(CHIPS)':
 'GND_7': CDS_PINID='GND_7';
NODE_NAME     U24 A9
 '@TIMECARD_LIB.TIMECARD(SCH_1):PAGE164_I138@PLD.XC7A200T_2FBG484C_FBG484(CHIPS)':
 'GND_8': CDS_PINID='GND_8';
NODE_NAME     U24 AA12
 '@TIMECARD_LIB.TIMECARD(SCH_1):PAGE164_I138@PLD.XC7A200T_2FBG484C_FBG484(CHIPS)':
 'GND_9': CDS_PINID='GND_9';
NODE_NAME     U24 AA2
 '@TIMECARD_LIB.TIMECARD(SCH_1):PAGE164_I138@PLD.XC7A200T_2FBG484C_FBG484(CHIPS)':
 'GND_10': CDS_PINID='GND_10';
NODE_NAME     U24 AA22
 '@TIMECARD_LIB.TIMECARD(SCH_1):PAGE164_I138@PLD.XC7A200T_2FBG484C_FBG484(CHIPS)':
 'GND_11': CDS_PINID='GND_11';
NODE_NAME     U24 AB19
 '@TIMECARD_LIB.TIMECARD(SCH_1):PAGE164_I138@PLD.XC7A200T_2FBG484C_FBG484(CHIPS)':
 'GND_12': CDS_PINID='GND_12';
NODE_NAME     U24 AB9
 '@TIMECARD_LIB.TIMECARD(SCH_1):PAGE164_I138@PLD.XC7A200T_2FBG484C_FBG484(CHIPS)':
 'GND_13': CDS_PINID='GND_13';
NODE_NAME     U24 B12
 '@TIMECARD_LIB.TIMECARD(SCH_1):PAGE164_I138@PLD.XC7A200T_2FBG484C_FBG484(CHIPS)':
 'GND_14': CDS_PINID='GND_14';
NODE_NAME     U24 B19
 '@TIMECARD_LIB.TIMECARD(SCH_1):PAGE164_I138@PLD.XC7A200T_2FBG484C_FBG484(CHIPS)':
 'GND_15': CDS_PINID='GND_15';
NODE_NAME     U24 B3
 '@TIMECARD_LIB.TIMECARD(SCH_1):PAGE164_I138@PLD.XC7A200T_2FBG484C_FBG484(CHIPS)':
 'GND_16': CDS_PINID='GND_16';
NODE_NAME     U24 C10
 '@TIMECARD_LIB.TIMECARD(SCH_1):PAGE164_I138@PLD.XC7A200T_2FBG484C_FBG484(CHIPS)':
 'GND_17': CDS_PINID='GND_17';
NODE_NAME     U24 C12
 '@TIMECARD_LIB.TIMECARD(SCH_1):PAGE164_I138@PLD.XC7A200T_2FBG484C_FBG484(CHIPS)':
 'GND_18': CDS_PINID='GND_18';
NODE_NAME     U24 C16
 '@TIMECARD_LIB.TIMECARD(SCH_1):PAGE164_I138@PLD.XC7A200T_2FBG484C_FBG484(CHIPS)':
 'GND_19': CDS_PINID='GND_19';
NODE_NAME     U24 C3
 '@TIMECARD_LIB.TIMECARD(SCH_1):PAGE164_I138@PLD.XC7A200T_2FBG484C_FBG484(CHIPS)':
 'GND_20': CDS_PINID='GND_20';
NODE_NAME     U24 C6
 '@TIMECARD_LIB.TIMECARD(SCH_1):PAGE164_I138@PLD.XC7A200T_2FBG484C_FBG484(CHIPS)':
 'GND_21': CDS_PINID='GND_21';
NODE_NAME     U24 D12
 '@TIMECARD_LIB.TIMECARD(SCH_1):PAGE164_I138@PLD.XC7A200T_2FBG484C_FBG484(CHIPS)':
 'GND_22': CDS_PINID='GND_22';
NODE_NAME     U24 D13
 '@TIMECARD_LIB.TIMECARD(SCH_1):PAGE164_I138@PLD.XC7A200T_2FBG484C_FBG484(CHIPS)':
 'GND_23': CDS_PINID='GND_23';
NODE_NAME     U24 D3
 '@TIMECARD_LIB.TIMECARD(SCH_1):PAGE164_I138@PLD.XC7A200T_2FBG484C_FBG484(CHIPS)':
 'GND_24': CDS_PINID='GND_24';
NODE_NAME     U24 D4
 '@TIMECARD_LIB.TIMECARD(SCH_1):PAGE164_I138@PLD.XC7A200T_2FBG484C_FBG484(CHIPS)':
 'GND_25': CDS_PINID='GND_25';
NODE_NAME     U24 D8
 '@TIMECARD_LIB.TIMECARD(SCH_1):PAGE164_I138@PLD.XC7A200T_2FBG484C_FBG484(CHIPS)':
 'GND_26': CDS_PINID='GND_26';
NODE_NAME     U24 E11
 '@TIMECARD_LIB.TIMECARD(SCH_1):PAGE164_I138@PLD.XC7A200T_2FBG484C_FBG484(CHIPS)':
 'GND_27': CDS_PINID='GND_27';
NODE_NAME     U24 E20
 '@TIMECARD_LIB.TIMECARD(SCH_1):PAGE164_I138@PLD.XC7A200T_2FBG484C_FBG484(CHIPS)':
 'GND_28': CDS_PINID='GND_28';
NODE_NAME     U24 E4
 '@TIMECARD_LIB.TIMECARD(SCH_1):PAGE164_I138@PLD.XC7A200T_2FBG484C_FBG484(CHIPS)':
 'GND_29': CDS_PINID='GND_29';
NODE_NAME     U24 E5
 '@TIMECARD_LIB.TIMECARD(SCH_1):PAGE164_I138@PLD.XC7A200T_2FBG484C_FBG484(CHIPS)':
 'GND_30': CDS_PINID='GND_30';
NODE_NAME     U24 E7
 '@TIMECARD_LIB.TIMECARD(SCH_1):PAGE164_I138@PLD.XC7A200T_2FBG484C_FBG484(CHIPS)':
 'GND_31': CDS_PINID='GND_31';
NODE_NAME     U24 E9
 '@TIMECARD_LIB.TIMECARD(SCH_1):PAGE164_I138@PLD.XC7A200T_2FBG484C_FBG484(CHIPS)':
 'GND_32': CDS_PINID='GND_32';
NODE_NAME     U24 F11
 '@TIMECARD_LIB.TIMECARD(SCH_1):PAGE164_I138@PLD.XC7A200T_2FBG484C_FBG484(CHIPS)':
 'GND_33': CDS_PINID='GND_33';
NODE_NAME     U24 F17
 '@TIMECARD_LIB.TIMECARD(SCH_1):PAGE164_I138@PLD.XC7A200T_2FBG484C_FBG484(CHIPS)':
 'GND_34': CDS_PINID='GND_34';
NODE_NAME     U24 F5
 '@TIMECARD_LIB.TIMECARD(SCH_1):PAGE164_I138@PLD.XC7A200T_2FBG484C_FBG484(CHIPS)':
 'GND_35': CDS_PINID='GND_35';
NODE_NAME     U24 G10
 '@TIMECARD_LIB.TIMECARD(SCH_1):PAGE164_I138@PLD.XC7A200T_2FBG484C_FBG484(CHIPS)':
 'GND_36': CDS_PINID='GND_36';
NODE_NAME     U24 G12
 '@TIMECARD_LIB.TIMECARD(SCH_1):PAGE164_I138@PLD.XC7A200T_2FBG484C_FBG484(CHIPS)':
 'GND_37': CDS_PINID='GND_37';
NODE_NAME     U24 G14
 '@TIMECARD_LIB.TIMECARD(SCH_1):PAGE164_I138@PLD.XC7A200T_2FBG484C_FBG484(CHIPS)':
 'GND_38': CDS_PINID='GND_38';
NODE_NAME     U24 G5
 '@TIMECARD_LIB.TIMECARD(SCH_1):PAGE164_I138@PLD.XC7A200T_2FBG484C_FBG484(CHIPS)':
 'GND_39': CDS_PINID='GND_39';
NODE_NAME     U24 G6
 '@TIMECARD_LIB.TIMECARD(SCH_1):PAGE164_I138@PLD.XC7A200T_2FBG484C_FBG484(CHIPS)':
 'GND_40': CDS_PINID='GND_40';
NODE_NAME     U24 G7
 '@TIMECARD_LIB.TIMECARD(SCH_1):PAGE164_I138@PLD.XC7A200T_2FBG484C_FBG484(CHIPS)':
 'GND_41': CDS_PINID='GND_41';
NODE_NAME     U24 G8
 '@TIMECARD_LIB.TIMECARD(SCH_1):PAGE164_I138@PLD.XC7A200T_2FBG484C_FBG484(CHIPS)':
 'GND_42': CDS_PINID='GND_42';
NODE_NAME     U24 G9
 '@TIMECARD_LIB.TIMECARD(SCH_1):PAGE164_I138@PLD.XC7A200T_2FBG484C_FBG484(CHIPS)':
 'GND_43': CDS_PINID='GND_43';
NODE_NAME     U24 H1
 '@TIMECARD_LIB.TIMECARD(SCH_1):PAGE164_I138@PLD.XC7A200T_2FBG484C_FBG484(CHIPS)':
 'GND_44': CDS_PINID='GND_44';
NODE_NAME     U24 H11
 '@TIMECARD_LIB.TIMECARD(SCH_1):PAGE164_I138@PLD.XC7A200T_2FBG484C_FBG484(CHIPS)':
 'GND_45': CDS_PINID='GND_45';
NODE_NAME     U24 H21
 '@TIMECARD_LIB.TIMECARD(SCH_1):PAGE164_I138@PLD.XC7A200T_2FBG484C_FBG484(CHIPS)':
 'GND_46': CDS_PINID='GND_46';
NODE_NAME     U24 H7
 '@TIMECARD_LIB.TIMECARD(SCH_1):PAGE164_I138@PLD.XC7A200T_2FBG484C_FBG484(CHIPS)':
 'GND_47': CDS_PINID='GND_47';
NODE_NAME     U24 H9
 '@TIMECARD_LIB.TIMECARD(SCH_1):PAGE164_I138@PLD.XC7A200T_2FBG484C_FBG484(CHIPS)':
 'GND_48': CDS_PINID='GND_48';
NODE_NAME     U24 J10
 '@TIMECARD_LIB.TIMECARD(SCH_1):PAGE164_I138@PLD.XC7A200T_2FBG484C_FBG484(CHIPS)':
 'GND_49': CDS_PINID='GND_49';
NODE_NAME     U24 J12
 '@TIMECARD_LIB.TIMECARD(SCH_1):PAGE164_I138@PLD.XC7A200T_2FBG484C_FBG484(CHIPS)':
 'GND_50': CDS_PINID='GND_50';
NODE_NAME     U24 J18
 '@TIMECARD_LIB.TIMECARD(SCH_1):PAGE164_I138@PLD.XC7A200T_2FBG484C_FBG484(CHIPS)':
 'GND_51': CDS_PINID='GND_51';
NODE_NAME     U24 J8
 '@TIMECARD_LIB.TIMECARD(SCH_1):PAGE164_I138@PLD.XC7A200T_2FBG484C_FBG484(CHIPS)':
 'GND_52': CDS_PINID='GND_52';
NODE_NAME     U24 K11
 '@TIMECARD_LIB.TIMECARD(SCH_1):PAGE164_I138@PLD.XC7A200T_2FBG484C_FBG484(CHIPS)':
 'GND_53': CDS_PINID='GND_53';
NODE_NAME     U24 K15
 '@TIMECARD_LIB.TIMECARD(SCH_1):PAGE164_I138@PLD.XC7A200T_2FBG484C_FBG484(CHIPS)':
 'GND_54': CDS_PINID='GND_54';
NODE_NAME     U24 K5
 '@TIMECARD_LIB.TIMECARD(SCH_1):PAGE164_I138@PLD.XC7A200T_2FBG484C_FBG484(CHIPS)':
 'GND_55': CDS_PINID='GND_55';
NODE_NAME     U24 K7
 '@TIMECARD_LIB.TIMECARD(SCH_1):PAGE164_I138@PLD.XC7A200T_2FBG484C_FBG484(CHIPS)':
 'GND_56': CDS_PINID='GND_56';
NODE_NAME     U24 L2
 '@TIMECARD_LIB.TIMECARD(SCH_1):PAGE164_I138@PLD.XC7A200T_2FBG484C_FBG484(CHIPS)':
 'GND_57': CDS_PINID='GND_57';
NODE_NAME     U24 L22
 '@TIMECARD_LIB.TIMECARD(SCH_1):PAGE164_I138@PLD.XC7A200T_2FBG484C_FBG484(CHIPS)':
 'GND_58': CDS_PINID='GND_58';
NODE_NAME     U24 L8
 '@TIMECARD_LIB.TIMECARD(SCH_1):PAGE164_I138@PLD.XC7A200T_2FBG484C_FBG484(CHIPS)':
 'GND_59': CDS_PINID='GND_59';
NODE_NAME     U24 M11
 '@TIMECARD_LIB.TIMECARD(SCH_1):PAGE164_I138@PLD.XC7A200T_2FBG484C_FBG484(CHIPS)':
 'GND_60': CDS_PINID='GND_60';
NODE_NAME     U24 M19
 '@TIMECARD_LIB.TIMECARD(SCH_1):PAGE164_I138@PLD.XC7A200T_2FBG484C_FBG484(CHIPS)':
 'GND_61': CDS_PINID='GND_61';
NODE_NAME     U24 M7
 '@TIMECARD_LIB.TIMECARD(SCH_1):PAGE164_I138@PLD.XC7A200T_2FBG484C_FBG484(CHIPS)':
 'GND_62': CDS_PINID='GND_62';
NODE_NAME     U24 N16
 '@TIMECARD_LIB.TIMECARD(SCH_1):PAGE164_I138@PLD.XC7A200T_2FBG484C_FBG484(CHIPS)':
 'GND_63': CDS_PINID='GND_63';
NODE_NAME     U24 N6
 '@TIMECARD_LIB.TIMECARD(SCH_1):PAGE164_I138@PLD.XC7A200T_2FBG484C_FBG484(CHIPS)':
 'GND_64': CDS_PINID='GND_64';
NODE_NAME     U24 N8
 '@TIMECARD_LIB.TIMECARD(SCH_1):PAGE164_I138@PLD.XC7A200T_2FBG484C_FBG484(CHIPS)':
 'GND_65': CDS_PINID='GND_65';
NODE_NAME     U24 P11
 '@TIMECARD_LIB.TIMECARD(SCH_1):PAGE164_I138@PLD.XC7A200T_2FBG484C_FBG484(CHIPS)':
 'GND_66': CDS_PINID='GND_66';
NODE_NAME     U24 P13
 '@TIMECARD_LIB.TIMECARD(SCH_1):PAGE164_I138@PLD.XC7A200T_2FBG484C_FBG484(CHIPS)':
 'GND_67': CDS_PINID='GND_67';
NODE_NAME     U24 P3
 '@TIMECARD_LIB.TIMECARD(SCH_1):PAGE164_I138@PLD.XC7A200T_2FBG484C_FBG484(CHIPS)':
 'GND_68': CDS_PINID='GND_68';
NODE_NAME     U24 P7
 '@TIMECARD_LIB.TIMECARD(SCH_1):PAGE164_I138@PLD.XC7A200T_2FBG484C_FBG484(CHIPS)':
 'GND_69': CDS_PINID='GND_69';
NODE_NAME     U24 P9
 '@TIMECARD_LIB.TIMECARD(SCH_1):PAGE164_I138@PLD.XC7A200T_2FBG484C_FBG484(CHIPS)':
 'GND_70': CDS_PINID='GND_70';
NODE_NAME     U24 R10
 '@TIMECARD_LIB.TIMECARD(SCH_1):PAGE164_I138@PLD.XC7A200T_2FBG484C_FBG484(CHIPS)':
 'GND_71': CDS_PINID='GND_71';
NODE_NAME     U24 R12
 '@TIMECARD_LIB.TIMECARD(SCH_1):PAGE164_I138@PLD.XC7A200T_2FBG484C_FBG484(CHIPS)':
 'GND_72': CDS_PINID='GND_72';
NODE_NAME     U24 R20
 '@TIMECARD_LIB.TIMECARD(SCH_1):PAGE164_I138@PLD.XC7A200T_2FBG484C_FBG484(CHIPS)':
 'GND_73': CDS_PINID='GND_73';
NODE_NAME     U24 R8
 '@TIMECARD_LIB.TIMECARD(SCH_1):PAGE164_I138@PLD.XC7A200T_2FBG484C_FBG484(CHIPS)':
 'GND_74': CDS_PINID='GND_74';
NODE_NAME     U24 T11
 '@TIMECARD_LIB.TIMECARD(SCH_1):PAGE164_I138@PLD.XC7A200T_2FBG484C_FBG484(CHIPS)':
 'GND_75': CDS_PINID='GND_75';
NODE_NAME     U24 T17
 '@TIMECARD_LIB.TIMECARD(SCH_1):PAGE164_I138@PLD.XC7A200T_2FBG484C_FBG484(CHIPS)':
 'GND_76': CDS_PINID='GND_76';
NODE_NAME     U24 T7
 '@TIMECARD_LIB.TIMECARD(SCH_1):PAGE164_I138@PLD.XC7A200T_2FBG484C_FBG484(CHIPS)':
 'GND_77': CDS_PINID='GND_77';
NODE_NAME     U24 T9
 '@TIMECARD_LIB.TIMECARD(SCH_1):PAGE164_I138@PLD.XC7A200T_2FBG484C_FBG484(CHIPS)':
 'GND_78': CDS_PINID='GND_78';
NODE_NAME     U24 U14
 '@TIMECARD_LIB.TIMECARD(SCH_1):PAGE164_I138@PLD.XC7A200T_2FBG484C_FBG484(CHIPS)':
 'GND_79': CDS_PINID='GND_79';
NODE_NAME     U24 U4
 '@TIMECARD_LIB.TIMECARD(SCH_1):PAGE164_I138@PLD.XC7A200T_2FBG484C_FBG484(CHIPS)':
 'GND_80': CDS_PINID='GND_80';
NODE_NAME     U24 V1
 '@TIMECARD_LIB.TIMECARD(SCH_1):PAGE164_I138@PLD.XC7A200T_2FBG484C_FBG484(CHIPS)':
 'GND_81': CDS_PINID='GND_81';
NODE_NAME     U24 V11
 '@TIMECARD_LIB.TIMECARD(SCH_1):PAGE164_I138@PLD.XC7A200T_2FBG484C_FBG484(CHIPS)':
 'GND_82': CDS_PINID='GND_82';
NODE_NAME     U24 V21
 '@TIMECARD_LIB.TIMECARD(SCH_1):PAGE164_I138@PLD.XC7A200T_2FBG484C_FBG484(CHIPS)':
 'GND_83': CDS_PINID='GND_83';
NODE_NAME     U24 W18
 '@TIMECARD_LIB.TIMECARD(SCH_1):PAGE164_I138@PLD.XC7A200T_2FBG484C_FBG484(CHIPS)':
 'GND_84': CDS_PINID='GND_84';
NODE_NAME     U24 W8
 '@TIMECARD_LIB.TIMECARD(SCH_1):PAGE164_I138@PLD.XC7A200T_2FBG484C_FBG484(CHIPS)':
 'GND_85': CDS_PINID='GND_85';
NODE_NAME     U24 Y15
 '@TIMECARD_LIB.TIMECARD(SCH_1):PAGE164_I138@PLD.XC7A200T_2FBG484C_FBG484(CHIPS)':
 'GND_86': CDS_PINID='GND_86';
NODE_NAME     U24 Y5
 '@TIMECARD_LIB.TIMECARD(SCH_1):PAGE164_I138@PLD.XC7A200T_2FBG484C_FBG484(CHIPS)':
 'GND_87': CDS_PINID='GND_87';
NODE_NAME     U24 K9
 '@TIMECARD_LIB.TIMECARD(SCH_1):PAGE164_I138@PLD.XC7A200T_2FBG484C_FBG484(CHIPS)':
 'GNDADC_0': CDS_PINID='GNDADC_0';
NODE_NAME     C176 2
 '@TIMECARD_LIB.TIMECARD(SCH_1):PAGE164_I172@PASSIVE.CAPACITOR(CHIPS)':
 '2': CDS_PINID='\2\';
NODE_NAME     C175 2
 '@TIMECARD_LIB.TIMECARD(SCH_1):PAGE164_I173@PASSIVE.CAPACITOR(CHIPS)':
 '2': CDS_PINID='\2\';
NODE_NAME     C172 2
 '@TIMECARD_LIB.TIMECARD(SCH_1):PAGE164_I174@PASSIVE.CAPACITOR(CHIPS)':
 '2': CDS_PINID='\2\';
NODE_NAME     C158 2
 '@TIMECARD_LIB.TIMECARD(SCH_1):PAGE164_I176@PASSIVE.CAPACITOR(CHIPS)':
 '2': CDS_PINID='\2\';
NODE_NAME     C120 2
 '@TIMECARD_LIB.TIMECARD(SCH_1):PAGE164_I177@PASSIVE.CAPACITOR(CHIPS)':
 '2': CDS_PINID='\2\';
NODE_NAME     C174 2
 '@TIMECARD_LIB.TIMECARD(SCH_1):PAGE164_I178@PASSIVE.CAPACITOR(CHIPS)':
 '2': CDS_PINID='\2\';
NODE_NAME     C201 2
 '@TIMECARD_LIB.TIMECARD(SCH_1):PAGE164_I182@PASSIVE.CAPACITOR(CHIPS)':
 '2': CDS_PINID='\2\';
NODE_NAME     C207 2
 '@TIMECARD_LIB.TIMECARD(SCH_1):PAGE164_I183@PASSIVE.CAPACITOR(CHIPS)':
 '2': CDS_PINID='\2\';
NODE_NAME     C214 2
 '@TIMECARD_LIB.TIMECARD(SCH_1):PAGE164_I184@PASSIVE.CAPACITOR(CHIPS)':
 '2': CDS_PINID='\2\';
NODE_NAME     C222 2
 '@TIMECARD_LIB.TIMECARD(SCH_1):PAGE164_I185@PASSIVE.CAPACITOR(CHIPS)':
 '2': CDS_PINID='\2\';
NODE_NAME     C109 2
 '@TIMECARD_LIB.TIMECARD(SCH_1):PAGE164_I186@PASSIVE.CAPACITOR(CHIPS)':
 '2': CDS_PINID='\2\';
NODE_NAME     C114 2
 '@TIMECARD_LIB.TIMECARD(SCH_1):PAGE164_I187@PASSIVE.CAPACITOR(CHIPS)':
 '2': CDS_PINID='\2\';
NODE_NAME     C121 2
 '@TIMECARD_LIB.TIMECARD(SCH_1):PAGE164_I188@PASSIVE.CAPACITOR(CHIPS)':
 '2': CDS_PINID='\2\';
NODE_NAME     C129 2
 '@TIMECARD_LIB.TIMECARD(SCH_1):PAGE164_I189@PASSIVE.CAPACITOR(CHIPS)':
 '2': CDS_PINID='\2\';
NODE_NAME     C133 2
 '@TIMECARD_LIB.TIMECARD(SCH_1):PAGE164_I190@PASSIVE.CAPACITOR(CHIPS)':
 '2': CDS_PINID='\2\';
NODE_NAME     C141 2
 '@TIMECARD_LIB.TIMECARD(SCH_1):PAGE164_I191@PASSIVE.CAPACITOR(CHIPS)':
 '2': CDS_PINID='\2\';
NODE_NAME     C147 2
 '@TIMECARD_LIB.TIMECARD(SCH_1):PAGE164_I192@PASSIVE.CAPACITOR(CHIPS)':
 '2': CDS_PINID='\2\';
NODE_NAME     C152 2
 '@TIMECARD_LIB.TIMECARD(SCH_1):PAGE164_I193@PASSIVE.CAPACITOR(CHIPS)':
 '2': CDS_PINID='\2\';
NODE_NAME     C156 2
 '@TIMECARD_LIB.TIMECARD(SCH_1):PAGE164_I194@PASSIVE.CAPACITOR(CHIPS)':
 '2': CDS_PINID='\2\';
NODE_NAME     C161 2
 '@TIMECARD_LIB.TIMECARD(SCH_1):PAGE164_I195@PASSIVE.CAPACITOR(CHIPS)':
 '2': CDS_PINID='\2\';
NODE_NAME     C166 2
 '@TIMECARD_LIB.TIMECARD(SCH_1):PAGE164_I196@PASSIVE.CAPACITOR(CHIPS)':
 '2': CDS_PINID='\2\';
NODE_NAME     C169 2
 '@TIMECARD_LIB.TIMECARD(SCH_1):PAGE164_I197@PASSIVE.CAPACITOR(CHIPS)':
 '2': CDS_PINID='\2\';
NODE_NAME     C171 2
 '@TIMECARD_LIB.TIMECARD(SCH_1):PAGE164_I198@PASSIVE.CAPACITOR(CHIPS)':
 '2': CDS_PINID='\2\';
NODE_NAME     C200 2
 '@TIMECARD_LIB.TIMECARD(SCH_1):PAGE164_I199@PASSIVE.CAPACITOR(CHIPS)':
 '2': CDS_PINID='\2\';
NODE_NAME     C206 2
 '@TIMECARD_LIB.TIMECARD(SCH_1):PAGE164_I200@PASSIVE.CAPACITOR(CHIPS)':
 '2': CDS_PINID='\2\';
NODE_NAME     C212 2
 '@TIMECARD_LIB.TIMECARD(SCH_1):PAGE164_I201@PASSIVE.CAPACITOR(CHIPS)':
 '2': CDS_PINID='\2\';
NODE_NAME     C219 2
 '@TIMECARD_LIB.TIMECARD(SCH_1):PAGE164_I202@PASSIVE.CAPACITOR(CHIPS)':
 '2': CDS_PINID='\2\';
NODE_NAME     C106 2
 '@TIMECARD_LIB.TIMECARD(SCH_1):PAGE164_I203@PASSIVE.CAPACITOR(CHIPS)':
 '2': CDS_PINID='\2\';
NODE_NAME     C113 2
 '@TIMECARD_LIB.TIMECARD(SCH_1):PAGE164_I204@PASSIVE.CAPACITOR(CHIPS)':
 '2': CDS_PINID='\2\';
NODE_NAME     C202 2
 '@TIMECARD_LIB.TIMECARD(SCH_1):PAGE164_I205@PASSIVE.CAPACITOR(CHIPS)':
 '2': CDS_PINID='\2\';
NODE_NAME     C210 2
 '@TIMECARD_LIB.TIMECARD(SCH_1):PAGE164_I206@PASSIVE.CAPACITOR(CHIPS)':
 '2': CDS_PINID='\2\';
NODE_NAME     C215 2
 '@TIMECARD_LIB.TIMECARD(SCH_1):PAGE164_I207@PASSIVE.CAPACITOR(CHIPS)':
 '2': CDS_PINID='\2\';
NODE_NAME     C103 2
 '@TIMECARD_LIB.TIMECARD(SCH_1):PAGE164_I208@PASSIVE.CAPACITOR(CHIPS)':
 '2': CDS_PINID='\2\';
NODE_NAME     C112 2
 '@TIMECARD_LIB.TIMECARD(SCH_1):PAGE164_I209@PASSIVE.CAPACITOR(CHIPS)':
 '2': CDS_PINID='\2\';
NODE_NAME     C119 2
 '@TIMECARD_LIB.TIMECARD(SCH_1):PAGE164_I210@PASSIVE.CAPACITOR(CHIPS)':
 '2': CDS_PINID='\2\';
NODE_NAME     C126 2
 '@TIMECARD_LIB.TIMECARD(SCH_1):PAGE164_I211@PASSIVE.CAPACITOR(CHIPS)':
 '2': CDS_PINID='\2\';
NODE_NAME     C132 2
 '@TIMECARD_LIB.TIMECARD(SCH_1):PAGE164_I212@PASSIVE.CAPACITOR(CHIPS)':
 '2': CDS_PINID='\2\';
NODE_NAME     C139 2
 '@TIMECARD_LIB.TIMECARD(SCH_1):PAGE164_I213@PASSIVE.CAPACITOR(CHIPS)':
 '2': CDS_PINID='\2\';
NODE_NAME     C144 2
 '@TIMECARD_LIB.TIMECARD(SCH_1):PAGE164_I214@PASSIVE.CAPACITOR(CHIPS)':
 '2': CDS_PINID='\2\';
NODE_NAME     C149 2
 '@TIMECARD_LIB.TIMECARD(SCH_1):PAGE164_I215@PASSIVE.CAPACITOR(CHIPS)':
 '2': CDS_PINID='\2\';
NODE_NAME     C203 2
 '@TIMECARD_LIB.TIMECARD(SCH_1):PAGE164_I216@PASSIVE.CAPACITOR(CHIPS)':
 '2': CDS_PINID='\2\';
NODE_NAME     C211 2
 '@TIMECARD_LIB.TIMECARD(SCH_1):PAGE164_I217@PASSIVE.CAPACITOR(CHIPS)':
 '2': CDS_PINID='\2\';
NODE_NAME     C216 2
 '@TIMECARD_LIB.TIMECARD(SCH_1):PAGE164_I218@PASSIVE.CAPACITOR(CHIPS)':
 '2': CDS_PINID='\2\';
NODE_NAME     C221 2
 '@TIMECARD_LIB.TIMECARD(SCH_1):PAGE164_I219@PASSIVE.CAPACITOR(CHIPS)':
 '2': CDS_PINID='\2\';
NODE_NAME     C107 2
 '@TIMECARD_LIB.TIMECARD(SCH_1):PAGE164_I220@PASSIVE.CAPACITOR(CHIPS)':
 '2': CDS_PINID='\2\';
NODE_NAME     C115 2
 '@TIMECARD_LIB.TIMECARD(SCH_1):PAGE164_I221@PASSIVE.CAPACITOR(CHIPS)':
 '2': CDS_PINID='\2\';
NODE_NAME     C223 2
 '@TIMECARD_LIB.TIMECARD(SCH_1):PAGE164_I222@PASSIVE.CAPACITOR(CHIPS)':
 '2': CDS_PINID='\2\';
NODE_NAME     C130 2
 '@TIMECARD_LIB.TIMECARD(SCH_1):PAGE164_I223@PASSIVE.CAPACITOR(CHIPS)':
 '2': CDS_PINID='\2\';
NODE_NAME     C134 2
 '@TIMECARD_LIB.TIMECARD(SCH_1):PAGE164_I224@PASSIVE.CAPACITOR(CHIPS)':
 '2': CDS_PINID='\2\';
NODE_NAME     C140 2
 '@TIMECARD_LIB.TIMECARD(SCH_1):PAGE164_I225@PASSIVE.CAPACITOR(CHIPS)':
 '2': CDS_PINID='\2\';
NODE_NAME     C145 2
 '@TIMECARD_LIB.TIMECARD(SCH_1):PAGE164_I226@PASSIVE.CAPACITOR(CHIPS)':
 '2': CDS_PINID='\2\';
NODE_NAME     C153 2
 '@TIMECARD_LIB.TIMECARD(SCH_1):PAGE164_I227@PASSIVE.CAPACITOR(CHIPS)':
 '2': CDS_PINID='\2\';
NODE_NAME     C157 2
 '@TIMECARD_LIB.TIMECARD(SCH_1):PAGE164_I228@PASSIVE.CAPACITOR(CHIPS)':
 '2': CDS_PINID='\2\';
NODE_NAME     C162 2
 '@TIMECARD_LIB.TIMECARD(SCH_1):PAGE164_I229@PASSIVE.CAPACITOR(CHIPS)':
 '2': CDS_PINID='\2\';
NODE_NAME     C165 2
 '@TIMECARD_LIB.TIMECARD(SCH_1):PAGE164_I230@PASSIVE.CAPACITOR(CHIPS)':
 '2': CDS_PINID='\2\';
NODE_NAME     C204 2
 '@TIMECARD_LIB.TIMECARD(SCH_1):PAGE164_I231@PASSIVE.CAPACITOR(CHIPS)':
 '2': CDS_PINID='\2\';
NODE_NAME     C208 2
 '@TIMECARD_LIB.TIMECARD(SCH_1):PAGE164_I232@PASSIVE.CAPACITOR(CHIPS)':
 '2': CDS_PINID='\2\';
NODE_NAME     C213 2
 '@TIMECARD_LIB.TIMECARD(SCH_1):PAGE164_I233@PASSIVE.CAPACITOR(CHIPS)':
 '2': CDS_PINID='\2\';
NODE_NAME     C220 2
 '@TIMECARD_LIB.TIMECARD(SCH_1):PAGE164_I234@PASSIVE.CAPACITOR(CHIPS)':
 '2': CDS_PINID='\2\';
NODE_NAME     C108 2
 '@TIMECARD_LIB.TIMECARD(SCH_1):PAGE164_I235@PASSIVE.CAPACITOR(CHIPS)':
 '2': CDS_PINID='\2\';
NODE_NAME     C116 2
 '@TIMECARD_LIB.TIMECARD(SCH_1):PAGE164_I236@PASSIVE.CAPACITOR(CHIPS)':
 '2': CDS_PINID='\2\';
NODE_NAME     C122 2
 '@TIMECARD_LIB.TIMECARD(SCH_1):PAGE164_I237@PASSIVE.CAPACITOR(CHIPS)':
 '2': CDS_PINID='\2\';
NODE_NAME     C127 2
 '@TIMECARD_LIB.TIMECARD(SCH_1):PAGE164_I238@PASSIVE.CAPACITOR(CHIPS)':
 '2': CDS_PINID='\2\';
NODE_NAME     C135 2
 '@TIMECARD_LIB.TIMECARD(SCH_1):PAGE164_I239@PASSIVE.CAPACITOR(CHIPS)':
 '2': CDS_PINID='\2\';
NODE_NAME     C142 2
 '@TIMECARD_LIB.TIMECARD(SCH_1):PAGE164_I240@PASSIVE.CAPACITOR(CHIPS)':
 '2': CDS_PINID='\2\';
NODE_NAME     C146 2
 '@TIMECARD_LIB.TIMECARD(SCH_1):PAGE164_I241@PASSIVE.CAPACITOR(CHIPS)':
 '2': CDS_PINID='\2\';
NODE_NAME     C151 2
 '@TIMECARD_LIB.TIMECARD(SCH_1):PAGE164_I242@PASSIVE.CAPACITOR(CHIPS)':
 '2': CDS_PINID='\2\';
NODE_NAME     C128 2
 '@TIMECARD_LIB.TIMECARD(SCH_1):PAGE164_I243@PASSIVE.CAPACITOR(CHIPS)':
 '2': CDS_PINID='\2\';
NODE_NAME     C160 2
 '@TIMECARD_LIB.TIMECARD(SCH_1):PAGE164_I245@PASSIVE.CAPACITOR(CHIPS)':
 '2': CDS_PINID='\2\';
NODE_NAME     C117 2
 '@TIMECARD_LIB.TIMECARD(SCH_1):PAGE164_I246@PASSIVE.CAPACITOR(CHIPS)':
 '2': CDS_PINID='\2\';
NODE_NAME     C131 2
 '@TIMECARD_LIB.TIMECARD(SCH_1):PAGE164_I248@PASSIVE.CAPACITOR(CHIPS)':
 '2': CDS_PINID='\2\';
NODE_NAME     C136 2
 '@TIMECARD_LIB.TIMECARD(SCH_1):PAGE164_I249@PASSIVE.CAPACITOR(CHIPS)':
 '2': CDS_PINID='\2\';
NODE_NAME     C148 2
 '@TIMECARD_LIB.TIMECARD(SCH_1):PAGE164_I250@PASSIVE.CAPACITOR(CHIPS)':
 '2': CDS_PINID='\2\';
NODE_NAME     C218 2
 '@TIMECARD_LIB.TIMECARD(SCH_1):PAGE164_I251@PASSIVE.CAPACITOR(CHIPS)':
 '2': CDS_PINID='\2\';
NODE_NAME     C105 2
 '@TIMECARD_LIB.TIMECARD(SCH_1):PAGE164_I252@PASSIVE.CAPACITOR(CHIPS)':
 '2': CDS_PINID='\2\';
NODE_NAME     C111 2
 '@TIMECARD_LIB.TIMECARD(SCH_1):PAGE164_I253@PASSIVE.CAPACITOR(CHIPS)':
 '2': CDS_PINID='\2\';
NODE_NAME     C118 2
 '@TIMECARD_LIB.TIMECARD(SCH_1):PAGE164_I254@PASSIVE.CAPACITOR(CHIPS)':
 '2': CDS_PINID='\2\';
NODE_NAME     C124 2
 '@TIMECARD_LIB.TIMECARD(SCH_1):PAGE164_I255@PASSIVE.CAPACITOR(CHIPS)':
 '2': CDS_PINID='\2\';
NODE_NAME     C110 2
 '@TIMECARD_LIB.TIMECARD(SCH_1):PAGE164_I256@PASSIVE.CAPACITOR(CHIPS)':
 '2': CDS_PINID='\2\';
NODE_NAME     C104 2
 '@TIMECARD_LIB.TIMECARD(SCH_1):PAGE164_I257@PASSIVE.CAPACITOR(CHIPS)':
 '2': CDS_PINID='\2\';
NODE_NAME     C217 2
 '@TIMECARD_LIB.TIMECARD(SCH_1):PAGE164_I258@PASSIVE.CAPACITOR(CHIPS)':
 '2': CDS_PINID='\2\';
NODE_NAME     C209 2
 '@TIMECARD_LIB.TIMECARD(SCH_1):PAGE164_I259@PASSIVE.CAPACITOR(CHIPS)':
 '2': CDS_PINID='\2\';
NODE_NAME     C205 2
 '@TIMECARD_LIB.TIMECARD(SCH_1):PAGE164_I260@PASSIVE.CAPACITOR(CHIPS)':
 '2': CDS_PINID='\2\';
NODE_NAME     C125 2
 '@TIMECARD_LIB.TIMECARD(SCH_1):PAGE164_I264@PASSIVE.CAPACITOR(CHIPS)':
 '2': CDS_PINID='\2\';
NODE_NAME     C143 2
 '@TIMECARD_LIB.TIMECARD(SCH_1):PAGE164_I265@PASSIVE.CAPACITOR(CHIPS)':
 '2': CDS_PINID='\2\';
NODE_NAME     C155 2
 '@TIMECARD_LIB.TIMECARD(SCH_1):PAGE164_I266@PASSIVE.CAPACITOR(CHIPS)':
 '2': CDS_PINID='\2\';
NODE_NAME     C168 2
 '@TIMECARD_LIB.TIMECARD(SCH_1):PAGE164_I267@PASSIVE.CAPACITOR(CHIPS)':
 '2': CDS_PINID='\2\';
NODE_NAME     C164 2
 '@TIMECARD_LIB.TIMECARD(SCH_1):PAGE164_I268@PASSIVE.CAPACITOR(CHIPS)':
 '2': CDS_PINID='\2\';
NODE_NAME     C154 2
 '@TIMECARD_LIB.TIMECARD(SCH_1):PAGE164_I270@PASSIVE.CAPACITOR(CHIPS)':
 '2': CDS_PINID='\2\';
NODE_NAME     C159 2
 '@TIMECARD_LIB.TIMECARD(SCH_1):PAGE164_I271@PASSIVE.CAPACITOR(CHIPS)':
 '2': CDS_PINID='\2\';
NODE_NAME     C163 2
 '@TIMECARD_LIB.TIMECARD(SCH_1):PAGE164_I272@PASSIVE.CAPACITOR(CHIPS)':
 '2': CDS_PINID='\2\';
NODE_NAME     C167 2
 '@TIMECARD_LIB.TIMECARD(SCH_1):PAGE164_I273@PASSIVE.CAPACITOR(CHIPS)':
 '2': CDS_PINID='\2\';
NODE_NAME     C179 2
 '@TIMECARD_LIB.TIMECARD(SCH_1):PAGE164_I274@PASSIVE.CAPACITOR(CHIPS)':
 '2': CDS_PINID='\2\';
NODE_NAME     C138 2
 '@TIMECARD_LIB.TIMECARD(SCH_1):PAGE164_I275@PASSIVE.CAPACITOR(CHIPS)':
 '2': CDS_PINID='\2\';
NODE_NAME     C150 2
 '@TIMECARD_LIB.TIMECARD(SCH_1):PAGE164_I276@PASSIVE.CAPACITOR(CHIPS)':
 '2': CDS_PINID='\2\';
NODE_NAME     C177 2
 '@TIMECARD_LIB.TIMECARD(SCH_1):PAGE164_I277@PASSIVE.CAPACITOR(CHIPS)':
 '2': CDS_PINID='\2\';
NODE_NAME     C173 2
 '@TIMECARD_LIB.TIMECARD(SCH_1):PAGE164_I280@PASSIVE.CAPACITOR(CHIPS)':
 '2': CDS_PINID='\2\';
NODE_NAME     C137 2
 '@TIMECARD_LIB.TIMECARD(SCH_1):PAGE164_I281@PASSIVE.CAPACITOR(CHIPS)':
 '2': CDS_PINID='\2\';
NODE_NAME     C170 2
 '@TIMECARD_LIB.TIMECARD(SCH_1):PAGE164_I282@PASSIVE.CAPACITOR(CHIPS)':
 '2': CDS_PINID='\2\';
NODE_NAME     C178 2
 '@TIMECARD_LIB.TIMECARD(SCH_1):PAGE164_I283@PASSIVE.CAPACITOR(CHIPS)':
 '2': CDS_PINID='\2\';
NODE_NAME     R237 2
 '@TIMECARD_LIB.TIMECARD(SCH_1):PAGE515_I56@PASSIVE.RESISTOR(CHIPS)':
 '2': CDS_PINID='\2\';
NODE_NAME     C232 2
 '@TIMECARD_LIB.TIMECARD(SCH_1):PAGE515_I61@PASSIVE.CAPACITOR(CHIPS)':
 '2': CDS_PINID='\2\';
NODE_NAME     C233 2
 '@TIMECARD_LIB.TIMECARD(SCH_1):PAGE515_I63@PASSIVE.CAPACITOR(CHIPS)':
 '2': CDS_PINID='\2\';
NODE_NAME     C237 2
 '@TIMECARD_LIB.TIMECARD(SCH_1):PAGE515_I64@PASSIVE.CAPACITOR(CHIPS)':
 '2': CDS_PINID='\2\';
NODE_NAME     C236 2
 '@TIMECARD_LIB.TIMECARD(SCH_1):PAGE515_I66@PASSIVE.CAPACITOR(CHIPS)':
 '2': CDS_PINID='\2\';
NODE_NAME     C240 2
 '@TIMECARD_LIB.TIMECARD(SCH_1):PAGE515_I71@PASSIVE.CAPACITOR(CHIPS)':
 '2': CDS_PINID='\2\';
NODE_NAME     C241 2
 '@TIMECARD_LIB.TIMECARD(SCH_1):PAGE515_I72@PASSIVE.CAPACITOR(CHIPS)':
 '2': CDS_PINID='\2\';
NODE_NAME     C243 2
 '@TIMECARD_LIB.TIMECARD(SCH_1):PAGE515_I74@PASSIVE.CAPACITOR(CHIPS)':
 '2': CDS_PINID='\2\';
NODE_NAME     U22 4
 '@TIMECARD_LIB.TIMECARD(SCH_1):PAGE515_I76@ANALOG.NCP45560IMNTWG_H_DFN12(CHIPS)':
 'GND': CDS_PINID='GND';
NODE_NAME     C235 2
 '@TIMECARD_LIB.TIMECARD(SCH_1):PAGE515_I80@PASSIVE.CAPACITOR(CHIPS)':
 '2': CDS_PINID='\2\';
NODE_NAME     C238 2
 '@TIMECARD_LIB.TIMECARD(SCH_1):PAGE515_I81@PASSIVE.CAPACITOR(CHIPS)':
 '2': CDS_PINID='\2\';
NODE_NAME     C229 2
 '@TIMECARD_LIB.TIMECARD(SCH_1):PAGE515_I87@PASSIVE.CAPACITOR(CHIPS)':
 '2': CDS_PINID='\2\';
NODE_NAME     R227 2
 '@TIMECARD_LIB.TIMECARD(SCH_1):PAGE515_I127@PASSIVE.RESISTOR(CHIPS)':
 '2': CDS_PINID='\2\';
NODE_NAME     C227 2
 '@TIMECARD_LIB.TIMECARD(SCH_1):PAGE515_I128@PASSIVE.CAPACITOR(CHIPS)':
 '2': CDS_PINID='\2\';
NODE_NAME     C228 2
 '@TIMECARD_LIB.TIMECARD(SCH_1):PAGE515_I130@PASSIVE.CAPACITOR(CHIPS)':
 '2': CDS_PINID='\2\';
NODE_NAME     C231 2
 '@TIMECARD_LIB.TIMECARD(SCH_1):PAGE515_I132@PASSIVE.CAPACITOR(CHIPS)':
 '2': CDS_PINID='\2\';
NODE_NAME     C230 2
 '@TIMECARD_LIB.TIMECARD(SCH_1):PAGE515_I134@PASSIVE.CAPACITOR(CHIPS)':
 '2': CDS_PINID='\2\';
NODE_NAME     C234 2
 '@TIMECARD_LIB.TIMECARD(SCH_1):PAGE515_I138@PASSIVE.CAPACITOR(CHIPS)':
 '2': CDS_PINID='\2\';
NODE_NAME     R232 1
 '@TIMECARD_LIB.TIMECARD(SCH_1):PAGE515_I143@PASSIVE.RESISTOR(CHIPS)':
 '1': CDS_PINID='\1\';
NODE_NAME     R233 1
 '@TIMECARD_LIB.TIMECARD(SCH_1):PAGE515_I145@PASSIVE.RESISTOR(CHIPS)':
 '1': CDS_PINID='\1\';
NODE_NAME     C239 2
 '@TIMECARD_LIB.TIMECARD(SCH_1):PAGE515_I147@PASSIVE.CAPACITOR(CHIPS)':
 '2': CDS_PINID='\2\';
NODE_NAME     C242 2
 '@TIMECARD_LIB.TIMECARD(SCH_1):PAGE515_I149@PASSIVE.CAPACITOR(CHIPS)':
 '2': CDS_PINID='\2\';
NODE_NAME     U25 5
 '@TIMECARD_LIB.TIMECARD(SCH_1):PAGE515_I151@ANALOG.ISL80101IRAJZ_DFN10(CHIPS)':
 'GND': CDS_PINID='GND';
NODE_NAME     U25 11
 '@TIMECARD_LIB.TIMECARD(SCH_1):PAGE515_I151@ANALOG.ISL80101IRAJZ_DFN10(CHIPS)':
 'THRM_PAD': CDS_PINID='THRM_PAD';
NODE_NAME     C224 2
 '@TIMECARD_LIB.TIMECARD(SCH_1):PAGE515_I154@PASSIVE.CAPACITOR(CHIPS)':
 '2': CDS_PINID='\2\';
NODE_NAME     C226 2
 '@TIMECARD_LIB.TIMECARD(SCH_1):PAGE515_I155@PASSIVE.CAPACITOR(CHIPS)':
 '2': CDS_PINID='\2\';
NODE_NAME     Y3 3
 '@TIMECARD_LIB.TIMECARD(SCH_1):PAGE522_I144@CLOCK.OSC6P_V2(CHIPS)':
 'GND': CDS_PINID='GND';
NODE_NAME     Y4 3
 '@TIMECARD_LIB.TIMECARD(SCH_1):PAGE522_I145@CLOCK.OSC6P_V2(CHIPS)':
 'GND': CDS_PINID='GND';
NODE_NAME     C248 2
 '@TIMECARD_LIB.TIMECARD(SCH_1):PAGE522_I147@PASSIVE.CAPACITOR(CHIPS)':
 '2': CDS_PINID='\2\';
NODE_NAME     C246 2
 '@TIMECARD_LIB.TIMECARD(SCH_1):PAGE522_I151@PASSIVE.CAPACITOR(CHIPS)':
 '2': CDS_PINID='\2\';
NODE_NAME     C244 2
 '@TIMECARD_LIB.TIMECARD(SCH_1):PAGE522_I152@PASSIVE.CAPACITOR(CHIPS)':
 '2': CDS_PINID='\2\';
NODE_NAME     C245 2
 '@TIMECARD_LIB.TIMECARD(SCH_1):PAGE522_I153@PASSIVE.CAPACITOR(CHIPS)':
 '2': CDS_PINID='\2\';
NODE_NAME     C247 2
 '@TIMECARD_LIB.TIMECARD(SCH_1):PAGE522_I154@PASSIVE.CAPACITOR(CHIPS)':
 '2': CDS_PINID='\2\';
NODE_NAME     C249 2
 '@TIMECARD_LIB.TIMECARD(SCH_1):PAGE522_I158@PASSIVE.CAPACITOR(CHIPS)':
 '2': CDS_PINID='\2\';
NODE_NAME     R239 2
 '@TIMECARD_LIB.TIMECARD(SCH_1):PAGE522_I169@PASSIVE.RESISTOR(CHIPS)':
 '2': CDS_PINID='\2\';
NODE_NAME     R241 2
 '@TIMECARD_LIB.TIMECARD(SCH_1):PAGE522_I170@PASSIVE.RESISTOR(CHIPS)':
 '2': CDS_PINID='\2\';
NODE_NAME     R240 2
 '@TIMECARD_LIB.TIMECARD(SCH_1):PAGE522_I172@PASSIVE.RESISTOR(CHIPS)':
 '2': CDS_PINID='\2\';
NODE_NAME     R242 2
 '@TIMECARD_LIB.TIMECARD(SCH_1):PAGE522_I174@PASSIVE.RESISTOR(CHIPS)':
 '2': CDS_PINID='\2\';
NODE_NAME     C256 2
 '@TIMECARD_LIB.TIMECARD(SCH_1):PAGE523_I7@PASSIVE.CAPACITOR(CHIPS)':
 '2': CDS_PINID='\2\';
NODE_NAME     U26 3
 '@TIMECARD_LIB.TIMECARD(SCH_1):PAGE523_I11@STDLOGIC.TPS54824RNVR_VQFN18(CHIPS)':
 'PGND_1': CDS_PINID='PGND_1';
NODE_NAME     U26 4
 '@TIMECARD_LIB.TIMECARD(SCH_1):PAGE523_I11@STDLOGIC.TPS54824RNVR_VQFN18(CHIPS)':
 'PGND_2': CDS_PINID='PGND_2';
NODE_NAME     U26 5
 '@TIMECARD_LIB.TIMECARD(SCH_1):PAGE523_I11@STDLOGIC.TPS54824RNVR_VQFN18(CHIPS)':
 'PGND_3': CDS_PINID='PGND_3';
NODE_NAME     U26 8
 '@TIMECARD_LIB.TIMECARD(SCH_1):PAGE523_I11@STDLOGIC.TPS54824RNVR_VQFN18(CHIPS)':
 'PGND_4': CDS_PINID='PGND_4';
NODE_NAME     U26 9
 '@TIMECARD_LIB.TIMECARD(SCH_1):PAGE523_I11@STDLOGIC.TPS54824RNVR_VQFN18(CHIPS)':
 'PGND_5': CDS_PINID='PGND_5';
NODE_NAME     U26 10
 '@TIMECARD_LIB.TIMECARD(SCH_1):PAGE523_I11@STDLOGIC.TPS54824RNVR_VQFN18(CHIPS)':
 'PGND_6': CDS_PINID='PGND_6';
NODE_NAME     C257 2
 '@TIMECARD_LIB.TIMECARD(SCH_1):PAGE523_I13@PASSIVE.CAPACITOR(CHIPS)':
 '2': CDS_PINID='\2\';
NODE_NAME     C260 2
 '@TIMECARD_LIB.TIMECARD(SCH_1):PAGE523_I14@PASSIVE.CAPACITOR(CHIPS)':
 '2': CDS_PINID='\2\';
NODE_NAME     C261 2
 '@TIMECARD_LIB.TIMECARD(SCH_1):PAGE523_I17@PASSIVE.CAPACITOR(CHIPS)':
 '2': CDS_PINID='\2\';
NODE_NAME     C262 2
 '@TIMECARD_LIB.TIMECARD(SCH_1):PAGE523_I19@PASSIVE.CAPACITOR(CHIPS)':
 '2': CDS_PINID='\2\';
NODE_NAME     R253 2
 '@TIMECARD_LIB.TIMECARD(SCH_1):PAGE523_I26@PASSIVE.RESISTOR(CHIPS)':
 '2': CDS_PINID='\2\';
NODE_NAME     C268 2
 '@TIMECARD_LIB.TIMECARD(SCH_1):PAGE523_I33@PASSIVE.CAPACITOR(CHIPS)':
 '2': CDS_PINID='\2\';
NODE_NAME     C269 2
 '@TIMECARD_LIB.TIMECARD(SCH_1):PAGE523_I34@PASSIVE.CAPACITOR(CHIPS)':
 '2': CDS_PINID='\2\';
NODE_NAME     C270 2
 '@TIMECARD_LIB.TIMECARD(SCH_1):PAGE523_I35@PASSIVE.CAPACITOR(CHIPS)':
 '2': CDS_PINID='\2\';
NODE_NAME     C271 2
 '@TIMECARD_LIB.TIMECARD(SCH_1):PAGE523_I37@PASSIVE.CAPACITOR(CHIPS)':
 '2': CDS_PINID='\2\';
NODE_NAME     SP3 1
 '@TIMECARD_LIB.TIMECARD(SCH_1):PAGE523_I39@MECH.SOLDER_PREFORM(CHIPS)':
 '1': CDS_PINID='\1\';
NODE_NAME     C255 2
 '@TIMECARD_LIB.TIMECARD(SCH_1):PAGE523_I46@PASSIVE.CAPACITOR(CHIPS)':
 '2': CDS_PINID='\2\';
NODE_NAME     C258 1
 '@TIMECARD_LIB.TIMECARD(SCH_1):PAGE523_I50@PASSIVE.CAPACITOR(CHIPS)':
 '1': CDS_PINID='\1\';
NODE_NAME     R246 2
 '@TIMECARD_LIB.TIMECARD(SCH_1):PAGE523_I51@PASSIVE.RESISTOR(CHIPS)':
 '2': CDS_PINID='\2\';
NODE_NAME     P2 8
 '@TIMECARD_LIB.TIMECARD(SCH_1):PAGE11_I36@CONNECTOR.CONN_HDR_2X4_F_S_SMT(CHIPS)':
 '8': CDS_PINID='\8\';
NODE_NAME     C81 2
 '@TIMECARD_LIB.TIMECARD(SCH_1):PAGE11_I43@PASSIVE.CAPACITOR(CHIPS)':
 '2': CDS_PINID='\2\';
NODE_NAME     R270 1
 '@TIMECARD_LIB.TIMECARD(SCH_1):PAGE161_I140@PASSIVE.RESISTOR(CHIPS)':
 '1': CDS_PINID='\1\';
NODE_NAME     C272 2
 '@TIMECARD_LIB.TIMECARD(SCH_1):PAGE11_I44@PASSIVE.CAPACITOR(CHIPS)':
 '2': CDS_PINID='\2\';
NODE_NAME     C273 2
 '@TIMECARD_LIB.TIMECARD(SCH_1):PAGE11_I45@PASSIVE.CAPACITOR(CHIPS)':
 '2': CDS_PINID='\2\';
NODE_NAME     C280 2
 '@TIMECARD_LIB.TIMECARD(SCH_1):PAGE9_I23@PASSIVE.CAPACITOR(CHIPS)':
 '2': CDS_PINID='\2\';
NODE_NAME     C40 2
 '@TIMECARD_LIB.TIMECARD(SCH_1):PAGE7_I18@PASSIVE.CAPACITOR(CHIPS)':
 '2': CDS_PINID='\2\';
NODE_NAME     C276 2
 '@TIMECARD_LIB.TIMECARD(SCH_1):PAGE8_I16@PASSIVE.CAPACITOR(CHIPS)':
 '2': CDS_PINID='\2\';
NODE_NAME     C278 2
 '@TIMECARD_LIB.TIMECARD(SCH_1):PAGE8_I19@PASSIVE.CAPACITOR(CHIPS)':
 '2': CDS_PINID='\2\';
NODE_NAME     C277 2
 '@TIMECARD_LIB.TIMECARD(SCH_1):PAGE8_I21@PASSIVE.CAPACITOR(CHIPS)':
 '2': CDS_PINID='\2\';
NODE_NAME     C279 2
 '@TIMECARD_LIB.TIMECARD(SCH_1):PAGE9_I21@PASSIVE.CAPACITOR(CHIPS)':
 '2': CDS_PINID='\2\';
NODE_NAME     C281 2
 '@TIMECARD_LIB.TIMECARD(SCH_1):PAGE9_I24@PASSIVE.CAPACITOR(CHIPS)':
 '2': CDS_PINID='\2\';
NODE_NAME     C275 2
 '@TIMECARD_LIB.TIMECARD(SCH_1):PAGE7_I19@PASSIVE.CAPACITOR(CHIPS)':
 '2': CDS_PINID='\2\';
NODE_NAME     C274 2
 '@TIMECARD_LIB.TIMECARD(SCH_1):PAGE7_I23@PASSIVE.CAPACITOR(CHIPS)':
 '2': CDS_PINID='\2\';
NODE_NAME     R297 2
 '@TIMECARD_LIB.TIMECARD(SCH_1):PAGE7_I39@PASSIVE.RESISTOR(CHIPS)':
 '2': CDS_PINID='\2\';
NODE_NAME     U27 7
 '@TIMECARD_LIB.TIMECARD(SCH_1):PAGE7_I44@ANALOG.SHT31A_DIS_B10KS_DFN8(CHIPS)':
 'R': CDS_PINID='R';
NODE_NAME     U27 9
 '@TIMECARD_LIB.TIMECARD(SCH_1):PAGE7_I44@ANALOG.SHT31A_DIS_B10KS_DFN8(CHIPS)':
 'THRM_PAD': CDS_PINID='THRM_PAD';
NODE_NAME     U27 8
 '@TIMECARD_LIB.TIMECARD(SCH_1):PAGE7_I44@ANALOG.SHT31A_DIS_B10KS_DFN8(CHIPS)':
 'VSS': CDS_PINID='VSS';
NODE_NAME     U28 8
 '@TIMECARD_LIB.TIMECARD(SCH_1):PAGE8_I24@ANALOG.ICP_10100_LGA10(CHIPS)':
 'GND_1': CDS_PINID='GND_1';
NODE_NAME     U28 9
 '@TIMECARD_LIB.TIMECARD(SCH_1):PAGE8_I24@ANALOG.ICP_10100_LGA10(CHIPS)':
 'GND_2': CDS_PINID='GND_2';
NODE_NAME     U29 2
 '@TIMECARD_LIB.TIMECARD(SCH_1):PAGE9_I29@LSI.BNO080_LGA_28(CHIPS)':
 'GND_1': CDS_PINID='GND_1';
NODE_NAME     U29 25
 '@TIMECARD_LIB.TIMECARD(SCH_1):PAGE9_I29@LSI.BNO080_LGA_28(CHIPS)':
 'GND_2': CDS_PINID='GND_2';
NODE_NAME     R301 2
 '@TIMECARD_LIB.TIMECARD(SCH_1):PAGE9_I43@PASSIVE.RESISTOR(CHIPS)':
 '2': CDS_PINID='\2\';
NODE_NAME     R307 2
 '@TIMECARD_LIB.TIMECARD(SCH_1):PAGE9_I47@PASSIVE.RESISTOR(CHIPS)':
 '2': CDS_PINID='\2\';
NODE_NAME     R305 2
 '@TIMECARD_LIB.TIMECARD(SCH_1):PAGE9_I49@PASSIVE.RESISTOR(CHIPS)':
 '2': CDS_PINID='\2\';
NODE_NAME     R303 2
 '@TIMECARD_LIB.TIMECARD(SCH_1):PAGE9_I50@PASSIVE.RESISTOR(CHIPS)':
 '2': CDS_PINID='\2\';
NODE_NAME     R302 2
 '@TIMECARD_LIB.TIMECARD(SCH_1):PAGE9_I52@PASSIVE.RESISTOR(CHIPS)':
 '2': CDS_PINID='\2\';
NODE_NAME     C285 2
 '@TIMECARD_LIB.TIMECARD(SCH_1):PAGE9_I53@PASSIVE.CAPACITOR(CHIPS)':
 '2': CDS_PINID='\2\';
NODE_NAME     C47 2
 '@TIMECARD_LIB.TIMECARD(SCH_1):PAGE9_I54@PASSIVE.CAPACITOR(CHIPS)':
 '2': CDS_PINID='\2\';
NODE_NAME     R351 2
 '@TIMECARD_LIB.TIMECARD(SCH_1):PAGE8_I30@PASSIVE.RESISTOR(CHIPS)':
 '2': CDS_PINID='\2\';
NODE_NAME     C286 2
 '@TIMECARD_LIB.TIMECARD(SCH_1):PAGE517_I51@PASSIVE.CAPACITOR(CHIPS)':
 '2': CDS_PINID='\2\';
NODE_NAME     CR4 1
 '@TIMECARD_LIB.TIMECARD(SCH_1):PAGE12_I179@DISCRETE.DIODE_4_V1(CHIPS)':
 'GND': CDS_PINID='GND';
NODE_NAME     DS6 C
 '@TIMECARD_LIB.TIMECARD(SCH_1):PAGE14_I140@DISCRETE.OPTICAL(CHIPS)':
 'C': CDS_PINID='C';
NODE_NAME     DS7 C
 '@TIMECARD_LIB.TIMECARD(SCH_1):PAGE14_I141@DISCRETE.OPTICAL(CHIPS)':
 'C': CDS_PINID='C';
NODE_NAME     DS8 C
 '@TIMECARD_LIB.TIMECARD(SCH_1):PAGE14_I142@DISCRETE.OPTICAL(CHIPS)':
 'C': CDS_PINID='C';
NODE_NAME     DS5 C
 '@TIMECARD_LIB.TIMECARD(SCH_1):PAGE14_I143@DISCRETE.OPTICAL(CHIPS)':
 'C': CDS_PINID='C';
NODE_NAME     R271 1
 '@TIMECARD_LIB.TIMECARD(SCH_1):PAGE161_I200@PASSIVE.RESISTOR(CHIPS)':
 '1': CDS_PINID='\1\';
NODE_NAME     R288 1
 '@TIMECARD_LIB.TIMECARD(SCH_1):PAGE161_I201@PASSIVE.RESISTOR(CHIPS)':
 '1': CDS_PINID='\1\';
NODE_NAME     R359 2
 '@TIMECARD_LIB.TIMECARD(SCH_1):PAGE163_I127@PASSIVE.RESISTOR(CHIPS)':
 '2': CDS_PINID='\2\';
NODE_NAME     R360 2
 '@TIMECARD_LIB.TIMECARD(SCH_1):PAGE163_I128@PASSIVE.RESISTOR(CHIPS)':
 '2': CDS_PINID='\2\';
NODE_NAME     R152 1
 '@TIMECARD_LIB.TIMECARD(SCH_1):PAGE5_I85@PASSIVE.RESISTOR(CHIPS)':
 '1': CDS_PINID='\1\';
NODE_NAME     R153 1
 '@TIMECARD_LIB.TIMECARD(SCH_1):PAGE5_I86@PASSIVE.RESISTOR(CHIPS)':
 '1': CDS_PINID='\1\';
NODE_NAME     R154 1
 '@TIMECARD_LIB.TIMECARD(SCH_1):PAGE5_I87@PASSIVE.RESISTOR(CHIPS)':
 '1': CDS_PINID='\1\';
NODE_NAME     R346 2
 '@TIMECARD_LIB.TIMECARD(SCH_1):PAGE8_I33@PASSIVE.RESISTOR(CHIPS)':
 '2': CDS_PINID='\2\';
NODE_NAME     R343 2
 '@TIMECARD_LIB.TIMECARD(SCH_1):PAGE8_I34@PASSIVE.RESISTOR(CHIPS)':
 '2': CDS_PINID='\2\';
NODE_NAME     C291 2
 '@TIMECARD_LIB.TIMECARD(SCH_1):PAGE164_I290@PASSIVE.CAPACITOR(CHIPS)':
 '2': CDS_PINID='\2\';
NODE_NAME     C292 2
 '@TIMECARD_LIB.TIMECARD(SCH_1):PAGE164_I291@PASSIVE.CAPACITOR(CHIPS)':
 '2': CDS_PINID='\2\';
NODE_NAME     C93 2
 '@TIMECARD_LIB.TIMECARD(SCH_1):PAGE164_I292@PASSIVE.CAPACITOR(CHIPS)':
 '2': CDS_PINID='\2\';
NODE_NAME     C293 2
 '@TIMECARD_LIB.TIMECARD(SCH_1):PAGE515_I168@PASSIVE.CAPACITOR(CHIPS)':
 '2': CDS_PINID='\2\';
NODE_NAME     C294 2
 '@TIMECARD_LIB.TIMECARD(SCH_1):PAGE515_I169@PASSIVE.CAPACITOR(CHIPS)':
 '2': CDS_PINID='\2\';
NODE_NAME     C297 2
 '@TIMECARD_LIB.TIMECARD(SCH_1):PAGE15_I229@PASSIVE.CAPACITOR(CHIPS)':
 '2': CDS_PINID='\2\';
NODE_NAME     C299 2
 '@TIMECARD_LIB.TIMECARD(SCH_1):PAGE15_I230@PASSIVE.CAPACITOR(CHIPS)':
 '2': CDS_PINID='\2\';
NODE_NAME     C303 2
 '@TIMECARD_LIB.TIMECARD(SCH_1):PAGE15_I231@PASSIVE.CAPACITOR(CHIPS)':
 '2': CDS_PINID='\2\';
NODE_NAME     C301 2
 '@TIMECARD_LIB.TIMECARD(SCH_1):PAGE15_I232@PASSIVE.CAPACITOR(CHIPS)':
 '2': CDS_PINID='\2\';
NODE_NAME     U7 2
 '@TIMECARD_LIB.TIMECARD(SCH_1):PAGE5_I89@MEMORY.AT24MAC402_SOT23_5(CHIPS)':
 'GND': CDS_PINID='GND';
NODE_NAME     C225 2
 '@TIMECARD_LIB.TIMECARD(SCH_1):PAGE5_I92@PASSIVE.CAPACITOR(CHIPS)':
 '2': CDS_PINID='\2\';
NODE_NAME     R344 2
 '@TIMECARD_LIB.TIMECARD(SCH_1):PAGE5_I97@PASSIVE.RESISTOR(CHIPS)':
 '2': CDS_PINID='\2\';
NODE_NAME     R413 2
 '@TIMECARD_LIB.TIMECARD(SCH_1):PAGE6_I60@PASSIVE.RESISTOR(CHIPS)':
 '2': CDS_PINID='\2\';
NODE_NAME     U36 4
 '@TIMECARD_LIB.TIMECARD(SCH_1):PAGE6_I66@INTERFACE.LM75BDP_TSSOP8(CHIPS)':
 'GND': CDS_PINID='GND';
NODE_NAME     C305 1
 '@TIMECARD_LIB.TIMECARD(SCH_1):PAGE6_I67@PASSIVE.CAPACITOR(CHIPS)':
 '1': CDS_PINID='\1\';
NODE_NAME     R416 2
 '@TIMECARD_LIB.TIMECARD(SCH_1):PAGE6_I72@PASSIVE.RESISTOR(CHIPS)':
 '2': CDS_PINID='\2\';
NODE_NAME     R409 2
 '@TIMECARD_LIB.TIMECARD(SCH_1):PAGE6_I73@PASSIVE.RESISTOR(CHIPS)':
 '2': CDS_PINID='\2\';
NODE_NAME     U35 4
 '@TIMECARD_LIB.TIMECARD(SCH_1):PAGE6_I90@INTERFACE.LM75BDP_TSSOP8(CHIPS)':
 'GND': CDS_PINID='GND';
NODE_NAME     C306 1
 '@TIMECARD_LIB.TIMECARD(SCH_1):PAGE6_I91@PASSIVE.CAPACITOR(CHIPS)':
 '1': CDS_PINID='\1\';
NODE_NAME     R417 2
 '@TIMECARD_LIB.TIMECARD(SCH_1):PAGE6_I93@PASSIVE.RESISTOR(CHIPS)':
 '2': CDS_PINID='\2\';
NODE_NAME     R415 2
 '@TIMECARD_LIB.TIMECARD(SCH_1):PAGE6_I94@PASSIVE.RESISTOR(CHIPS)':
 '2': CDS_PINID='\2\';
NODE_NAME     R411 2
 '@TIMECARD_LIB.TIMECARD(SCH_1):PAGE6_I95@PASSIVE.RESISTOR(CHIPS)':
 '2': CDS_PINID='\2\';
NODE_NAME     J14 2
 '@TIMECARD_LIB.TIMECARD(SCH_1):PAGE127_I427@CONNECTOR.G200_10283_01(CHIPS)':
 '2': CDS_PINID='\2\';
NODE_NAME     J14 10
 '@TIMECARD_LIB.TIMECARD(SCH_1):PAGE127_I427@CONNECTOR.G200_10283_01(CHIPS)':
 '10': CDS_PINID='\10\';
NODE_NAME     R402 2
 '@TIMECARD_LIB.TIMECARD(SCH_1):PAGE127_I440@PASSIVE.RESISTOR(CHIPS)':
 '2': CDS_PINID='\2\';
NODE_NAME     CR7 1
 '@TIMECARD_LIB.TIMECARD(SCH_1):PAGE127_I442@DISCRETE.DIODE_4_V1(CHIPS)':
 'GND': CDS_PINID='GND';
NODE_NAME     CR6 1
 '@TIMECARD_LIB.TIMECARD(SCH_1):PAGE127_I443@DISCRETE.DIODE_4_V1(CHIPS)':
 'GND': CDS_PINID='GND';
NODE_NAME     U13 4
 '@TIMECARD_LIB.TIMECARD(SCH_1):PAGE12_I204@STDLOGIC.74HCT2G125DP_TSSOP8(CHIPS)':
 'GND': CDS_PINID='GND';
NODE_NAME     C83 2
 '@TIMECARD_LIB.TIMECARD(SCH_1):PAGE12_I207@PASSIVE.CAPACITOR(CHIPS)':
 '2': CDS_PINID='\2\';
NODE_NAME     U14 4
 '@TIMECARD_LIB.TIMECARD(SCH_1):PAGE12_I226@STDLOGIC.74HCT2G125DP_TSSOP8(CHIPS)':
 'GND': CDS_PINID='GND';
NODE_NAME     C82 2
 '@TIMECARD_LIB.TIMECARD(SCH_1):PAGE12_I231@PASSIVE.CAPACITOR(CHIPS)':
 '2': CDS_PINID='\2\';
NODE_NAME     U15 4
 '@TIMECARD_LIB.TIMECARD(SCH_1):PAGE12_I255@STDLOGIC.74HCT2G125DP_TSSOP8(CHIPS)':
 'GND': CDS_PINID='GND';
NODE_NAME     C85 2
 '@TIMECARD_LIB.TIMECARD(SCH_1):PAGE12_I272@PASSIVE.CAPACITOR(CHIPS)':
 '2': CDS_PINID='\2\';
NODE_NAME     U16 4
 '@TIMECARD_LIB.TIMECARD(SCH_1):PAGE12_I273@STDLOGIC.74HCT2G125DP_TSSOP8(CHIPS)':
 'GND': CDS_PINID='GND';
NODE_NAME     C84 2
 '@TIMECARD_LIB.TIMECARD(SCH_1):PAGE12_I289@PASSIVE.CAPACITOR(CHIPS)':
 '2': CDS_PINID='\2\';
NODE_NAME     C289 2
 '@TIMECARD_LIB.TIMECARD(SCH_1):PAGE3_I124@PASSIVE.CAPACITOR(CHIPS)':
 '2': CDS_PINID='\2\';
NODE_NAME     C290 2
 '@TIMECARD_LIB.TIMECARD(SCH_1):PAGE3_I126@PASSIVE.CAPACITOR(CHIPS)':
 '2': CDS_PINID='\2\';
NODE_NAME     C288 2
 '@TIMECARD_LIB.TIMECARD(SCH_1):PAGE3_I127@PASSIVE.CAPACITOR(CHIPS)':
 '2': CDS_PINID='\2\';
NODE_NAME     C287 2
 '@TIMECARD_LIB.TIMECARD(SCH_1):PAGE3_I129@PASSIVE.CAPACITOR(CHIPS)':
 '2': CDS_PINID='\2\';
NODE_NAME     DS19 C
 '@TIMECARD_LIB.TIMECARD(SCH_1):PAGE14_I191@DISCRETE.OPTICAL(CHIPS)':
 'C': CDS_PINID='C';
NODE_NAME     DS20 C
 '@TIMECARD_LIB.TIMECARD(SCH_1):PAGE14_I194@DISCRETE.OPTICAL(CHIPS)':
 'C': CDS_PINID='C';
NODE_NAME     U33 4
 '@TIMECARD_LIB.TIMECARD(SCH_1):PAGE14_I219@INTERFACE.IS32FL3207_QWLA3_TR_QFN29(CHIPS)':
 'GND_1': CDS_PINID='GND_1';
NODE_NAME     U33 11
 '@TIMECARD_LIB.TIMECARD(SCH_1):PAGE14_I219@INTERFACE.IS32FL3207_QWLA3_TR_QFN29(CHIPS)':
 'GND_2': CDS_PINID='GND_2';
NODE_NAME     U33 18
 '@TIMECARD_LIB.TIMECARD(SCH_1):PAGE14_I219@INTERFACE.IS32FL3207_QWLA3_TR_QFN29(CHIPS)':
 'GND_3': CDS_PINID='GND_3';
NODE_NAME     U33 25
 '@TIMECARD_LIB.TIMECARD(SCH_1):PAGE14_I219@INTERFACE.IS32FL3207_QWLA3_TR_QFN29(CHIPS)':
 'GND_4': CDS_PINID='GND_4';
NODE_NAME     U33 29
 '@TIMECARD_LIB.TIMECARD(SCH_1):PAGE14_I219@INTERFACE.IS32FL3207_QWLA3_TR_QFN29(CHIPS)':
 'THRM_PAD': CDS_PINID='THRM_PAD';
NODE_NAME     C315 2
 '@TIMECARD_LIB.TIMECARD(SCH_1):PAGE14_I237@PASSIVE.CAPACITOR(CHIPS)':
 '2': CDS_PINID='\2\';
NODE_NAME     C314 2
 '@TIMECARD_LIB.TIMECARD(SCH_1):PAGE14_I238@PASSIVE.CAPACITOR(CHIPS)':
 '2': CDS_PINID='\2\';
NODE_NAME     R323 2
 '@TIMECARD_LIB.TIMECARD(SCH_1):PAGE14_I246@PASSIVE.RESISTOR(CHIPS)':
 '2': CDS_PINID='\2\';
NODE_NAME     R324 1
 '@TIMECARD_LIB.TIMECARD(SCH_1):PAGE14_I247@PASSIVE.RESISTOR(CHIPS)':
 '1': CDS_PINID='\1\';
NODE_NAME     C316 2
 '@TIMECARD_LIB.TIMECARD(SCH_1):PAGE14_I250@PASSIVE.CAPACITOR(CHIPS)':
 '2': CDS_PINID='\2\';
NODE_NAME     C312 2
 '@TIMECARD_LIB.TIMECARD(SCH_1):PAGE8_I39@PASSIVE.CAPACITOR(CHIPS)':
 '2': CDS_PINID='\2\';
NODE_NAME     C313 2
 '@TIMECARD_LIB.TIMECARD(SCH_1):PAGE8_I41@PASSIVE.CAPACITOR(CHIPS)':
 '2': CDS_PINID='\2\';
NODE_NAME     U32 4
 '@TIMECARD_LIB.TIMECARD(SCH_1):PAGE8_I52@STDLOGIC.PCA9508DP_TSSOP8(CHIPS)':
 'GND': CDS_PINID='GND';
NODE_NAME     J1 GH1
 '@TIMECARD_LIB.TIMECARD(SCH_1):PAGE12_I290@CONNECTOR.CONN_JACK_1P_GH4_S_TH(CHIPS)':
 'GH1': CDS_PINID='GH1';
NODE_NAME     J1 GH2
 '@TIMECARD_LIB.TIMECARD(SCH_1):PAGE12_I290@CONNECTOR.CONN_JACK_1P_GH4_S_TH(CHIPS)':
 'GH2': CDS_PINID='GH2';
NODE_NAME     J1 GH3
 '@TIMECARD_LIB.TIMECARD(SCH_1):PAGE12_I290@CONNECTOR.CONN_JACK_1P_GH4_S_TH(CHIPS)':
 'GH3': CDS_PINID='GH3';
NODE_NAME     J1 GH4
 '@TIMECARD_LIB.TIMECARD(SCH_1):PAGE12_I290@CONNECTOR.CONN_JACK_1P_GH4_S_TH(CHIPS)':
 'GH4': CDS_PINID='GH4';
NODE_NAME     J2 GH1
 '@TIMECARD_LIB.TIMECARD(SCH_1):PAGE12_I294@CONNECTOR.CONN_JACK_1P_GH4_S_TH(CHIPS)':
 'GH1': CDS_PINID='GH1';
NODE_NAME     J2 GH2
 '@TIMECARD_LIB.TIMECARD(SCH_1):PAGE12_I294@CONNECTOR.CONN_JACK_1P_GH4_S_TH(CHIPS)':
 'GH2': CDS_PINID='GH2';
NODE_NAME     J2 GH3
 '@TIMECARD_LIB.TIMECARD(SCH_1):PAGE12_I294@CONNECTOR.CONN_JACK_1P_GH4_S_TH(CHIPS)':
 'GH3': CDS_PINID='GH3';
NODE_NAME     J2 GH4
 '@TIMECARD_LIB.TIMECARD(SCH_1):PAGE12_I294@CONNECTOR.CONN_JACK_1P_GH4_S_TH(CHIPS)':
 'GH4': CDS_PINID='GH4';
NODE_NAME     J3 GH1
 '@TIMECARD_LIB.TIMECARD(SCH_1):PAGE12_I297@CONNECTOR.CONN_JACK_1P_GH4_S_TH(CHIPS)':
 'GH1': CDS_PINID='GH1';
NODE_NAME     J3 GH2
 '@TIMECARD_LIB.TIMECARD(SCH_1):PAGE12_I297@CONNECTOR.CONN_JACK_1P_GH4_S_TH(CHIPS)':
 'GH2': CDS_PINID='GH2';
NODE_NAME     J3 GH3
 '@TIMECARD_LIB.TIMECARD(SCH_1):PAGE12_I297@CONNECTOR.CONN_JACK_1P_GH4_S_TH(CHIPS)':
 'GH3': CDS_PINID='GH3';
NODE_NAME     J3 GH4
 '@TIMECARD_LIB.TIMECARD(SCH_1):PAGE12_I297@CONNECTOR.CONN_JACK_1P_GH4_S_TH(CHIPS)':
 'GH4': CDS_PINID='GH4';
NODE_NAME     J4 GH1
 '@TIMECARD_LIB.TIMECARD(SCH_1):PAGE12_I300@CONNECTOR.CONN_JACK_1P_GH4_S_TH(CHIPS)':
 'GH1': CDS_PINID='GH1';
NODE_NAME     J4 GH2
 '@TIMECARD_LIB.TIMECARD(SCH_1):PAGE12_I300@CONNECTOR.CONN_JACK_1P_GH4_S_TH(CHIPS)':
 'GH2': CDS_PINID='GH2';
NODE_NAME     J4 GH3
 '@TIMECARD_LIB.TIMECARD(SCH_1):PAGE12_I300@CONNECTOR.CONN_JACK_1P_GH4_S_TH(CHIPS)':
 'GH3': CDS_PINID='GH3';
NODE_NAME     J4 GH4
 '@TIMECARD_LIB.TIMECARD(SCH_1):PAGE12_I300@CONNECTOR.CONN_JACK_1P_GH4_S_TH(CHIPS)':
 'GH4': CDS_PINID='GH4';
NODE_NAME     U3 3
 '@TIMECARD_LIB.TIMECARD(SCH_1):PAGE3_I135@STDLOGIC.74LVC1G07_SC70_5(CHIPS)':
 'GND': CDS_PINID='GND';
NODE_NAME     P3 4
 '@TIMECARD_LIB.TIMECARD(SCH_1):PAGE15_I238@CONNECTOR.CONN_HDR_2X3_M_RA_TH(CHIPS)':
 '4': CDS_PINID='\4\';
NODE_NAME     P3 5
 '@TIMECARD_LIB.TIMECARD(SCH_1):PAGE15_I238@CONNECTOR.CONN_HDR_2X3_M_RA_TH(CHIPS)':
 '5': CDS_PINID='\5\';
NODE_NAME     P3 6
 '@TIMECARD_LIB.TIMECARD(SCH_1):PAGE15_I238@CONNECTOR.CONN_HDR_2X3_M_RA_TH(CHIPS)':
 '6': CDS_PINID='\6\';
NODE_NAME     U17 2
 '@TIMECARD_LIB.TIMECARD(SCH_1):PAGE524_I3@OTHER.CL1001485A(CHIPS)':
 '2': CDS_PINID='\2\';
NODE_NAME     C86 1
 '@TIMECARD_LIB.TIMECARD(SCH_1):PAGE524_I7@PASSIVE.CAPACITOR(CHIPS)':
 '1': CDS_PINID='\1\';
NODE_NAME     Y2 2
 '@TIMECARD_LIB.TIMECARD(SCH_1):PAGE524_I8@CLOCK.XTAL_4(CHIPS)':
 '2': CDS_PINID='\2\';
NODE_NAME     Y2 4
 '@TIMECARD_LIB.TIMECARD(SCH_1):PAGE524_I8@CLOCK.XTAL_4(CHIPS)':
 '4': CDS_PINID='\4\';
NODE_NAME     C87 1
 '@TIMECARD_LIB.TIMECARD(SCH_1):PAGE524_I10@PASSIVE.CAPACITOR(CHIPS)':
 '1': CDS_PINID='\1\';
NODE_NAME     R130 2
 '@TIMECARD_LIB.TIMECARD(SCH_1):PAGE524_I23@PASSIVE.RESISTOR(CHIPS)':
 '2': CDS_PINID='\2\';
NODE_NAME     U18 10
 '@TIMECARD_LIB.TIMECARD(SCH_1):PAGE524_I64@INTERFACE.FT4232HL_REEL_QFP64(CHIPS)':
 'AGND': CDS_PINID='AGND';
NODE_NAME     U18 51
 '@TIMECARD_LIB.TIMECARD(SCH_1):PAGE524_I64@INTERFACE.FT4232HL_REEL_QFP64(CHIPS)':
 'GND_1': CDS_PINID='GND_1';
NODE_NAME     U18 47
 '@TIMECARD_LIB.TIMECARD(SCH_1):PAGE524_I64@INTERFACE.FT4232HL_REEL_QFP64(CHIPS)':
 'GND_2': CDS_PINID='GND_2';
NODE_NAME     U18 35
 '@TIMECARD_LIB.TIMECARD(SCH_1):PAGE524_I64@INTERFACE.FT4232HL_REEL_QFP64(CHIPS)':
 'GND_3': CDS_PINID='GND_3';
NODE_NAME     U18 25
 '@TIMECARD_LIB.TIMECARD(SCH_1):PAGE524_I64@INTERFACE.FT4232HL_REEL_QFP64(CHIPS)':
 'GND_4': CDS_PINID='GND_4';
NODE_NAME     U18 15
 '@TIMECARD_LIB.TIMECARD(SCH_1):PAGE524_I64@INTERFACE.FT4232HL_REEL_QFP64(CHIPS)':
 'GND_5': CDS_PINID='GND_5';
NODE_NAME     U18 11
 '@TIMECARD_LIB.TIMECARD(SCH_1):PAGE524_I64@INTERFACE.FT4232HL_REEL_QFP64(CHIPS)':
 'GND_6': CDS_PINID='GND_6';
NODE_NAME     U18 5
 '@TIMECARD_LIB.TIMECARD(SCH_1):PAGE524_I64@INTERFACE.FT4232HL_REEL_QFP64(CHIPS)':
 'GND_7': CDS_PINID='GND_7';
NODE_NAME     U18 1
 '@TIMECARD_LIB.TIMECARD(SCH_1):PAGE524_I64@INTERFACE.FT4232HL_REEL_QFP64(CHIPS)':
 'GND_8': CDS_PINID='GND_8';
NODE_NAME     U18 13
 '@TIMECARD_LIB.TIMECARD(SCH_1):PAGE524_I64@INTERFACE.FT4232HL_REEL_QFP64(CHIPS)':
 'TEST': CDS_PINID='TEST';
NODE_NAME     R463 2
 '@TIMECARD_LIB.TIMECARD(SCH_1):PAGE524_I106@PASSIVE.RESISTOR(CHIPS)':
 '2': CDS_PINID='\2\';
NODE_NAME     C90 2
 '@TIMECARD_LIB.TIMECARD(SCH_1):PAGE524_I123@PASSIVE.CAPACITOR(CHIPS)':
 '2': CDS_PINID='\2\';
NODE_NAME     C91 2
 '@TIMECARD_LIB.TIMECARD(SCH_1):PAGE524_I128@PASSIVE.CAPACITOR(CHIPS)':
 '2': CDS_PINID='\2\';
NODE_NAME     J10 9
 '@TIMECARD_LIB.TIMECARD(SCH_1):PAGE524_I173@CONNECTOR.G200_10283_01(CHIPS)':
 '9': CDS_PINID='\9\';
NODE_NAME     U31 5
 '@TIMECARD_LIB.TIMECARD(SCH_1):PAGE524_I201@MEMORY.CAT93C46VI_GT3_SOIC8(CHIPS)':
 'GND': CDS_PINID='GND';
NODE_NAME     R171 1
 '@TIMECARD_LIB.TIMECARD(SCH_1):PAGE16_I1542@PASSIVE.RESISTOR(CHIPS)':
 '1': CDS_PINID='\1\';
NODE_NAME     R173 1
 '@TIMECARD_LIB.TIMECARD(SCH_1):PAGE16_I1544@PASSIVE.RESISTOR(CHIPS)':
 '1': CDS_PINID='\1\';
NODE_NAME     R284 1
 '@TIMECARD_LIB.TIMECARD(SCH_1):PAGE16_I1547@PASSIVE.RESISTOR(CHIPS)':
 '1': CDS_PINID='\1\';
NODE_NAME     R286 1
 '@TIMECARD_LIB.TIMECARD(SCH_1):PAGE16_I1549@PASSIVE.RESISTOR(CHIPS)':
 '1': CDS_PINID='\1\';
NODE_NAME     R328 1
 '@TIMECARD_LIB.TIMECARD(SCH_1):PAGE16_I1550@PASSIVE.RESISTOR(CHIPS)':
 '1': CDS_PINID='\1\';
NODE_NAME     R326 1
 '@TIMECARD_LIB.TIMECARD(SCH_1):PAGE16_I1552@PASSIVE.RESISTOR(CHIPS)':
 '1': CDS_PINID='\1\';
NODE_NAME     R293 1
 '@TIMECARD_LIB.TIMECARD(SCH_1):PAGE16_I1555@PASSIVE.RESISTOR(CHIPS)':
 '1': CDS_PINID='\1\';
NODE_NAME     R309 1
 '@TIMECARD_LIB.TIMECARD(SCH_1):PAGE16_I1557@PASSIVE.RESISTOR(CHIPS)':
 '1': CDS_PINID='\1\';
NODE_NAME     C284 2
 '@TIMECARD_LIB.TIMECARD(SCH_1):PAGE525_I7@PASSIVE.CAPACITOR(CHIPS)':
 '2': CDS_PINID='\2\';
NODE_NAME     C298 2
 '@TIMECARD_LIB.TIMECARD(SCH_1):PAGE525_I8@PASSIVE.CAPACITOR(CHIPS)':
 '2': CDS_PINID='\2\';
NODE_NAME     R488 2
 '@TIMECARD_LIB.TIMECARD(SCH_1):PAGE525_I13@PASSIVE.RESISTOR(CHIPS)':
 '2': CDS_PINID='\2\';
NODE_NAME     C302 2
 '@TIMECARD_LIB.TIMECARD(SCH_1):PAGE525_I14@PASSIVE.CAPACITOR(CHIPS)':
 '2': CDS_PINID='\2\';
NODE_NAME     C300 2
 '@TIMECARD_LIB.TIMECARD(SCH_1):PAGE525_I16@PASSIVE.CAPACITOR(CHIPS)':
 '2': CDS_PINID='\2\';
NODE_NAME     C307 2
 '@TIMECARD_LIB.TIMECARD(SCH_1):PAGE525_I18@PASSIVE.CAPACITOR(CHIPS)':
 '2': CDS_PINID='\2\';
NODE_NAME     C304 2
 '@TIMECARD_LIB.TIMECARD(SCH_1):PAGE525_I20@PASSIVE.CAPACITOR(CHIPS)':
 '2': CDS_PINID='\2\';
NODE_NAME     U41 5
 '@TIMECARD_LIB.TIMECARD(SCH_1):PAGE525_I29@ANALOG.ISL80101IRAJZ_DFN10(CHIPS)':
 'GND': CDS_PINID='GND';
NODE_NAME     U41 11
 '@TIMECARD_LIB.TIMECARD(SCH_1):PAGE525_I29@ANALOG.ISL80101IRAJZ_DFN10(CHIPS)':
 'THRM_PAD': CDS_PINID='THRM_PAD';
NODE_NAME     C309 2
 '@TIMECARD_LIB.TIMECARD(SCH_1):PAGE525_I56@PASSIVE.CAPACITOR(CHIPS)':
 '2': CDS_PINID='\2\';
NODE_NAME     C308 2
 '@TIMECARD_LIB.TIMECARD(SCH_1):PAGE525_I64@PASSIVE.CAPACITOR(CHIPS)':
 '2': CDS_PINID='\2\';
NODE_NAME     R491 2
 '@TIMECARD_LIB.TIMECARD(SCH_1):PAGE525_I67@PASSIVE.RESISTOR(CHIPS)':
 '2': CDS_PINID='\2\';
NODE_NAME     R489 2
 '@TIMECARD_LIB.TIMECARD(SCH_1):PAGE525_I68@PASSIVE.RESISTOR(CHIPS)':
 '2': CDS_PINID='\2\';
NODE_NAME     DS12 C
 '@TIMECARD_LIB.TIMECARD(SCH_1):PAGE14_I289@DISCRETE.OPTICAL(CHIPS)':
 'C': CDS_PINID='C';
NODE_NAME     C101 2
 '@TIMECARD_LIB.TIMECARD(SCH_1):PAGE524_I373@PASSIVE.CAPACITOR(CHIPS)':
 '2': CDS_PINID='\2\';
NODE_NAME     C100 2
 '@TIMECARD_LIB.TIMECARD(SCH_1):PAGE524_I374@PASSIVE.CAPACITOR(CHIPS)':
 '2': CDS_PINID='\2\';
NODE_NAME     C95 2
 '@TIMECARD_LIB.TIMECARD(SCH_1):PAGE524_I375@PASSIVE.CAPACITOR(CHIPS)':
 '2': CDS_PINID='\2\';
NODE_NAME     C96 2
 '@TIMECARD_LIB.TIMECARD(SCH_1):PAGE524_I376@PASSIVE.CAPACITOR(CHIPS)':
 '2': CDS_PINID='\2\';
NODE_NAME     C94 2
 '@TIMECARD_LIB.TIMECARD(SCH_1):PAGE524_I377@PASSIVE.CAPACITOR(CHIPS)':
 '2': CDS_PINID='\2\';
NODE_NAME     C88 2
 '@TIMECARD_LIB.TIMECARD(SCH_1):PAGE524_I378@PASSIVE.CAPACITOR(CHIPS)':
 '2': CDS_PINID='\2\';
NODE_NAME     C98 2
 '@TIMECARD_LIB.TIMECARD(SCH_1):PAGE524_I379@PASSIVE.CAPACITOR(CHIPS)':
 '2': CDS_PINID='\2\';
NODE_NAME     C99 2
 '@TIMECARD_LIB.TIMECARD(SCH_1):PAGE524_I380@PASSIVE.CAPACITOR(CHIPS)':
 '2': CDS_PINID='\2\';
NODE_NAME     R445 2
 '@TIMECARD_LIB.TIMECARD(SCH_1):PAGE524_I395@PASSIVE.RESISTOR(CHIPS)':
 '2': CDS_PINID='\2\';
NODE_NAME     J17 2
 '@TIMECARD_LIB.TIMECARD(SCH_1):PAGE5_I127@CONNECTOR.CONN_HDR_2X2_M_S_SMT(CHIPS)':
 '2': CDS_PINID='\2\';
NODE_NAME     J17 4
 '@TIMECARD_LIB.TIMECARD(SCH_1):PAGE5_I127@CONNECTOR.CONN_HDR_2X2_M_S_SMT(CHIPS)':
 '4': CDS_PINID='\4\';
NODE_NAME     U19 4
 '@TIMECARD_LIB.TIMECARD(SCH_1):PAGE5_I148@MEMORY.24LC16BT_I_ST_TSSOP8(CHIPS)':
 'VSS': CDS_PINID='VSS';
NODE_NAME     R159 2
 '@TIMECARD_LIB.TIMECARD(SCH_1):PAGE5_I156@PASSIVE.RESISTOR(CHIPS)':
 '2': CDS_PINID='\2\';
NODE_NAME     R161 2
 '@TIMECARD_LIB.TIMECARD(SCH_1):PAGE5_I165@PASSIVE.RESISTOR(CHIPS)':
 '2': CDS_PINID='\2\';
NODE_NAME     R163 2
 '@TIMECARD_LIB.TIMECARD(SCH_1):PAGE5_I166@PASSIVE.RESISTOR(CHIPS)':
 '2': CDS_PINID='\2\';
NODE_NAME     R24 2
 '@TIMECARD_LIB.TIMECARD(SCH_1):PAGE5_I167@PASSIVE.RESISTOR(CHIPS)':
 '2': CDS_PINID='\2\';
NODE_NAME     C1 2
 '@TIMECARD_LIB.TIMECARD(SCH_1):PAGE5_I171@PASSIVE.CAPACITOR(CHIPS)':
 '2': CDS_PINID='\2\';
NODE_NAME     R437 1
 '@TIMECARD_LIB.TIMECARD(SCH_1):PAGE161_I239@PASSIVE.RESISTOR(CHIPS)':
 '1': CDS_PINID='\1\';
NODE_NAME     R436 1
 '@TIMECARD_LIB.TIMECARD(SCH_1):PAGE161_I240@PASSIVE.RESISTOR(CHIPS)':
 '1': CDS_PINID='\1\';
NODE_NAME     J11 5
 '@TIMECARD_LIB.TIMECARD(SCH_1):PAGE527_I2@CONNECTOR.CONN_USB_1X5_G2_GH4_F_RA_SMT(CHIPS)':
 '5': CDS_PINID='\5\';
NODE_NAME     J11 G1
 '@TIMECARD_LIB.TIMECARD(SCH_1):PAGE527_I2@CONNECTOR.CONN_USB_1X5_G2_GH4_F_RA_SMT(CHIPS)':
 'G1': CDS_PINID='G1';
NODE_NAME     J11 G2
 '@TIMECARD_LIB.TIMECARD(SCH_1):PAGE527_I2@CONNECTOR.CONN_USB_1X5_G2_GH4_F_RA_SMT(CHIPS)':
 'G2': CDS_PINID='G2';
NODE_NAME     J11 GH1
 '@TIMECARD_LIB.TIMECARD(SCH_1):PAGE527_I2@CONNECTOR.CONN_USB_1X5_G2_GH4_F_RA_SMT(CHIPS)':
 'GH1': CDS_PINID='GH1';
NODE_NAME     J11 GH2
 '@TIMECARD_LIB.TIMECARD(SCH_1):PAGE527_I2@CONNECTOR.CONN_USB_1X5_G2_GH4_F_RA_SMT(CHIPS)':
 'GH2': CDS_PINID='GH2';
NODE_NAME     J11 GH3
 '@TIMECARD_LIB.TIMECARD(SCH_1):PAGE527_I2@CONNECTOR.CONN_USB_1X5_G2_GH4_F_RA_SMT(CHIPS)':
 'GH3': CDS_PINID='GH3';
NODE_NAME     J11 GH4
 '@TIMECARD_LIB.TIMECARD(SCH_1):PAGE527_I2@CONNECTOR.CONN_USB_1X5_G2_GH4_F_RA_SMT(CHIPS)':
 'GH4': CDS_PINID='GH4';
NODE_NAME     U9 2
 '@TIMECARD_LIB.TIMECARD(SCH_1):PAGE527_I4@OTHER.CL1001485A(CHIPS)':
 '2': CDS_PINID='\2\';
NODE_NAME     C63 2
 '@TIMECARD_LIB.TIMECARD(SCH_1):PAGE527_I15@PASSIVE.CAPACITOR(CHIPS)':
 '2': CDS_PINID='\2\';
NODE_NAME     C61 2
 '@TIMECARD_LIB.TIMECARD(SCH_1):PAGE527_I16@PASSIVE.CAPACITOR(CHIPS)':
 '2': CDS_PINID='\2\';
NODE_NAME     C58 2
 '@TIMECARD_LIB.TIMECARD(SCH_1):PAGE527_I47@PASSIVE.CAPACITOR(CHIPS)':
 '2': CDS_PINID='\2\';
NODE_NAME     C59 2
 '@TIMECARD_LIB.TIMECARD(SCH_1):PAGE527_I48@PASSIVE.CAPACITOR(CHIPS)':
 '2': CDS_PINID='\2\';
NODE_NAME     C64 2
 '@TIMECARD_LIB.TIMECARD(SCH_1):PAGE527_I51@PASSIVE.CAPACITOR(CHIPS)':
 '2': CDS_PINID='\2\';
NODE_NAME     C65 2
 '@TIMECARD_LIB.TIMECARD(SCH_1):PAGE527_I56@PASSIVE.CAPACITOR(CHIPS)':
 '2': CDS_PINID='\2\';
NODE_NAME     C66 2
 '@TIMECARD_LIB.TIMECARD(SCH_1):PAGE527_I57@PASSIVE.CAPACITOR(CHIPS)':
 '2': CDS_PINID='\2\';
NODE_NAME     C60 2
 '@TIMECARD_LIB.TIMECARD(SCH_1):PAGE527_I66@PASSIVE.CAPACITOR(CHIPS)':
 '2': CDS_PINID='\2\';
NODE_NAME     C69 2
 '@TIMECARD_LIB.TIMECARD(SCH_1):PAGE527_I74@PASSIVE.CAPACITOR(CHIPS)':
 '2': CDS_PINID='\2\';
NODE_NAME     C70 2
 '@TIMECARD_LIB.TIMECARD(SCH_1):PAGE527_I77@PASSIVE.CAPACITOR(CHIPS)':
 '2': CDS_PINID='\2\';
NODE_NAME     U12 2
 '@TIMECARD_LIB.TIMECARD(SCH_1):PAGE527_I78@STDLOGIC.TPS2051BDBVT_SOT23_5(CHIPS)':
 'GND': CDS_PINID='GND';
NODE_NAME     C71 2
 '@TIMECARD_LIB.TIMECARD(SCH_1):PAGE527_I85@PASSIVE.CAPACITOR(CHIPS)':
 '2': CDS_PINID='\2\';
NODE_NAME     C62 2
 '@TIMECARD_LIB.TIMECARD(SCH_1):PAGE527_I93@PASSIVE.CAPACITOR(CHIPS)':
 '2': CDS_PINID='\2\';
NODE_NAME     C67 2
 '@TIMECARD_LIB.TIMECARD(SCH_1):PAGE527_I103@PASSIVE.CAPACITOR(CHIPS)':
 '2': CDS_PINID='\2\';
NODE_NAME     U11 9
 '@TIMECARD_LIB.TIMECARD(SCH_1):PAGE527_I108@STDLOGIC.TS3USB3031RMGR_WQFN12(CHIPS)':
 'GND': CDS_PINID='GND';
NODE_NAME     R104 2
 '@TIMECARD_LIB.TIMECARD(SCH_1):PAGE527_I126@PASSIVE.RESISTOR(CHIPS)':
 '2': CDS_PINID='\2\';
NODE_NAME     C68 2
 '@TIMECARD_LIB.TIMECARD(SCH_1):PAGE527_I144@PASSIVE.CAPACITOR(CHIPS)':
 '2': CDS_PINID='\2\';
NODE_NAME     U10 3
 '@TIMECARD_LIB.TIMECARD(SCH_1):PAGE527_I146@STDLOGIC.CL5003148A(CHIPS)':
 'GND': CDS_PINID='GND';
NODE_NAME     R99 2
 '@TIMECARD_LIB.TIMECARD(SCH_1):PAGE527_I149@PASSIVE.RESISTOR(CHIPS)':
 '2': CDS_PINID='\2\';
NODE_NAME     P1 8
 '@TIMECARD_LIB.TIMECARD(SCH_1):PAGE527_I193@CONNECTOR.CONN_HDR_2X10_M_S_SMT(CHIPS)':
 '8': CDS_PINID='\8\';
NODE_NAME     P1 9
 '@TIMECARD_LIB.TIMECARD(SCH_1):PAGE527_I193@CONNECTOR.CONN_HDR_2X10_M_S_SMT(CHIPS)':
 '9': CDS_PINID='\9\';
NODE_NAME     P1 15
 '@TIMECARD_LIB.TIMECARD(SCH_1):PAGE527_I193@CONNECTOR.CONN_HDR_2X10_M_S_SMT(CHIPS)':
 '15': CDS_PINID='\15\';
NODE_NAME     J18 1
 '@TIMECARD_LIB.TIMECARD(SCH_1):PAGE527_I198@CONNECTOR.CONN_HDR_1X3_M_S_SMT(CHIPS)':
 '1': CDS_PINID='\1\';
NODE_NAME     J18 3
 '@TIMECARD_LIB.TIMECARD(SCH_1):PAGE527_I198@CONNECTOR.CONN_HDR_1X3_M_S_SMT(CHIPS)':
 '3': CDS_PINID='\3\';
NODE_NAME     R103 2
 '@TIMECARD_LIB.TIMECARD(SCH_1):PAGE527_I202@PASSIVE.RESISTOR(CHIPS)':
 '2': CDS_PINID='\2\';
NODE_NAME     C282 2
 '@TIMECARD_LIB.TIMECARD(SCH_1):PAGE527_I208@PASSIVE.CAPACITOR(CHIPS)':
 '2': CDS_PINID='\2\';
NODE_NAME     C283 2
 '@TIMECARD_LIB.TIMECARD(SCH_1):PAGE527_I209@PASSIVE.CAPACITOR(CHIPS)':
 '2': CDS_PINID='\2\';
NODE_NAME     MAC_PIN4 1
 '@TIMECARD_LIB.TIMECARD(SCH_1):PAGE527_I228@MECH.NUT(CHIPS)':
 '1': CDS_PINID='\1\';
NODE_NAME     MAC_PIN2 1
 '@TIMECARD_LIB.TIMECARD(SCH_1):PAGE527_I229@MECH.NUT(CHIPS)':
 '1': CDS_PINID='\1\';
NODE_NAME     Q2 2
 '@TIMECARD_LIB.TIMECARD(SCH_1):PAGE527_I232@DISCRETE.POWERMOS_3P_NCH_V1(CHIPS)':
 'S': CDS_PINID='S';
NODE_NAME     R441 2
 '@TIMECARD_LIB.TIMECARD(SCH_1):PAGE163_I134@PASSIVE.RESISTOR(CHIPS)':
 '2': CDS_PINID='\2\';
NODE_NAME     R440 2
 '@TIMECARD_LIB.TIMECARD(SCH_1):PAGE163_I135@PASSIVE.RESISTOR(CHIPS)':
 '2': CDS_PINID='\2\';
NODE_NAME     R458 1
 '@TIMECARD_LIB.TIMECARD(SCH_1):PAGE524_I430@PASSIVE.RESISTOR(CHIPS)':
 '1': CDS_PINID='\1\';
NODE_NAME     R459 1
 '@TIMECARD_LIB.TIMECARD(SCH_1):PAGE524_I432@PASSIVE.RESISTOR(CHIPS)':
 '1': CDS_PINID='\1\';
NODE_NAME     R451 2
 '@TIMECARD_LIB.TIMECARD(SCH_1):PAGE524_I441@PASSIVE.RESISTOR(CHIPS)':
 '2': CDS_PINID='\2\';
NODE_NAME     R453 2
 '@TIMECARD_LIB.TIMECARD(SCH_1):PAGE524_I442@PASSIVE.RESISTOR(CHIPS)':
 '2': CDS_PINID='\2\';
NODE_NAME     Q1 2
 '@TIMECARD_LIB.TIMECARD(SCH_1):PAGE524_I445@DISCRETE.POWERMOS_3P_NCH_V1(CHIPS)':
 'S': CDS_PINID='S';
NODE_NAME     R483 1
 '@TIMECARD_LIB.TIMECARD(SCH_1):PAGE524_I462@PASSIVE.RESISTOR(CHIPS)':
 '1': CDS_PINID='\1\';
NODE_NAME     R484 1
 '@TIMECARD_LIB.TIMECARD(SCH_1):PAGE524_I463@PASSIVE.RESISTOR(CHIPS)':
 '1': CDS_PINID='\1\';
NODE_NAME     U30 8
 '@TIMECARD_LIB.TIMECARD(SCH_1):PAGE524_I473@STDLOGIC.TS3A5018PWR_TSSOP16(CHIPS)':
 'GND': CDS_PINID='GND';
NODE_NAME     C89 2
 '@TIMECARD_LIB.TIMECARD(SCH_1):PAGE524_I474@PASSIVE.CAPACITOR(CHIPS)':
 '2': CDS_PINID='\2\';
NODE_NAME     C92 2
 '@TIMECARD_LIB.TIMECARD(SCH_1):PAGE524_I476@PASSIVE.CAPACITOR(CHIPS)':
 '2': CDS_PINID='\2\';
NODE_NAME     U37 8
 '@TIMECARD_LIB.TIMECARD(SCH_1):PAGE524_I478@STDLOGIC.TS3A5018PWR_TSSOP16(CHIPS)':
 'GND': CDS_PINID='GND';
NODE_NAME     U38 8
 '@TIMECARD_LIB.TIMECARD(SCH_1):PAGE524_I481@STDLOGIC.TS3A5018PWR_TSSOP16(CHIPS)':
 'GND': CDS_PINID='GND';
NODE_NAME     C97 2
 '@TIMECARD_LIB.TIMECARD(SCH_1):PAGE524_I482@PASSIVE.CAPACITOR(CHIPS)':
 '2': CDS_PINID='\2\';
NODE_NAME     U39 2
 '@TIMECARD_LIB.TIMECARD(SCH_1):PAGE524_I485@INTERFACE.NLASB3157DFT2G_SC88(CHIPS)':
 'GND': CDS_PINID='GND';
NODE_NAME     C123 2
 '@TIMECARD_LIB.TIMECARD(SCH_1):PAGE524_I486@PASSIVE.CAPACITOR(CHIPS)':
 '2': CDS_PINID='\2\';
NODE_NAME     C102 2
 '@TIMECARD_LIB.TIMECARD(SCH_1):PAGE524_I490@PASSIVE.CAPACITOR(CHIPS)':
 '2': CDS_PINID='\2\';
NODE_NAME     U40 2
 '@TIMECARD_LIB.TIMECARD(SCH_1):PAGE524_I491@INTERFACE.NLASB3157DFT2G_SC88(CHIPS)':
 'GND': CDS_PINID='GND';
NODE_NAME     U23 4
 '@TIMECARD_LIB.TIMECARD(SCH_1):PAGE127_I456@MEMORY.MT25QL128ABA1ESE_SOP8(CHIPS)':
 'VSS': CDS_PINID='VSS';
NODE_NAME     R192 2
 '@TIMECARD_LIB.TIMECARD(SCH_1):PAGE127_I470@PASSIVE.RESISTOR(CHIPS)':
 '2': CDS_PINID='\2\';
NODE_NAME     C199 2
 '@TIMECARD_LIB.TIMECARD(SCH_1):PAGE127_I472@PASSIVE.CAPACITOR(CHIPS)':
 '2': CDS_PINID='\2\';
NODE_NAME     C198 2
 '@TIMECARD_LIB.TIMECARD(SCH_1):PAGE127_I473@PASSIVE.CAPACITOR(CHIPS)':
 '2': CDS_PINID='\2\';
NODE_NAME     J5 9
 '@TIMECARD_LIB.TIMECARD(SCH_1):PAGE16_I1614@CONNECTOR.CONN_HDR_2X6_F_S_SMT(CHIPS)':
 '9': CDS_PINID='\9\';
NODE_NAME     J5 10
 '@TIMECARD_LIB.TIMECARD(SCH_1):PAGE16_I1614@CONNECTOR.CONN_HDR_2X6_F_S_SMT(CHIPS)':
 '10': CDS_PINID='\10\';
NODE_NAME     ME11 1
 '@TIMECARD_LIB.TIMECARD(SCH_1):PAGE33_I1@MECH.MEC_MTH8(CHIPS)':
 '1': CDS_PINID='\1\';
NODE_NAME     ME11 2
 '@TIMECARD_LIB.TIMECARD(SCH_1):PAGE33_I1@MECH.MEC_MTH8(CHIPS)':
 '2': CDS_PINID='\2\';
NODE_NAME     ME11 3
 '@TIMECARD_LIB.TIMECARD(SCH_1):PAGE33_I1@MECH.MEC_MTH8(CHIPS)':
 '3': CDS_PINID='\3\';
NODE_NAME     ME11 4
 '@TIMECARD_LIB.TIMECARD(SCH_1):PAGE33_I1@MECH.MEC_MTH8(CHIPS)':
 '4': CDS_PINID='\4\';
NODE_NAME     ME11 5
 '@TIMECARD_LIB.TIMECARD(SCH_1):PAGE33_I1@MECH.MEC_MTH8(CHIPS)':
 '5': CDS_PINID='\5\';
NODE_NAME     ME11 6
 '@TIMECARD_LIB.TIMECARD(SCH_1):PAGE33_I1@MECH.MEC_MTH8(CHIPS)':
 '6': CDS_PINID='\6\';
NODE_NAME     ME11 7
 '@TIMECARD_LIB.TIMECARD(SCH_1):PAGE33_I1@MECH.MEC_MTH8(CHIPS)':
 '7': CDS_PINID='\7\';
NODE_NAME     ME11 8
 '@TIMECARD_LIB.TIMECARD(SCH_1):PAGE33_I1@MECH.MEC_MTH8(CHIPS)':
 '8': CDS_PINID='\8\';
NODE_NAME     ME12 1
 '@TIMECARD_LIB.TIMECARD(SCH_1):PAGE33_I2@MECH.MEC_MTH8(CHIPS)':
 '1': CDS_PINID='\1\';
NODE_NAME     ME12 2
 '@TIMECARD_LIB.TIMECARD(SCH_1):PAGE33_I2@MECH.MEC_MTH8(CHIPS)':
 '2': CDS_PINID='\2\';
NODE_NAME     ME12 3
 '@TIMECARD_LIB.TIMECARD(SCH_1):PAGE33_I2@MECH.MEC_MTH8(CHIPS)':
 '3': CDS_PINID='\3\';
NODE_NAME     ME12 4
 '@TIMECARD_LIB.TIMECARD(SCH_1):PAGE33_I2@MECH.MEC_MTH8(CHIPS)':
 '4': CDS_PINID='\4\';
NODE_NAME     ME12 5
 '@TIMECARD_LIB.TIMECARD(SCH_1):PAGE33_I2@MECH.MEC_MTH8(CHIPS)':
 '5': CDS_PINID='\5\';
NODE_NAME     ME12 6
 '@TIMECARD_LIB.TIMECARD(SCH_1):PAGE33_I2@MECH.MEC_MTH8(CHIPS)':
 '6': CDS_PINID='\6\';
NODE_NAME     ME12 7
 '@TIMECARD_LIB.TIMECARD(SCH_1):PAGE33_I2@MECH.MEC_MTH8(CHIPS)':
 '7': CDS_PINID='\7\';
NODE_NAME     ME12 8
 '@TIMECARD_LIB.TIMECARD(SCH_1):PAGE33_I2@MECH.MEC_MTH8(CHIPS)':
 '8': CDS_PINID='\8\';
NODE_NAME     ME10 1
 '@TIMECARD_LIB.TIMECARD(SCH_1):PAGE33_I5@MECH.MEC_MTH8(CHIPS)':
 '1': CDS_PINID='\1\';
NODE_NAME     ME10 2
 '@TIMECARD_LIB.TIMECARD(SCH_1):PAGE33_I5@MECH.MEC_MTH8(CHIPS)':
 '2': CDS_PINID='\2\';
NODE_NAME     ME10 3
 '@TIMECARD_LIB.TIMECARD(SCH_1):PAGE33_I5@MECH.MEC_MTH8(CHIPS)':
 '3': CDS_PINID='\3\';
NODE_NAME     ME10 4
 '@TIMECARD_LIB.TIMECARD(SCH_1):PAGE33_I5@MECH.MEC_MTH8(CHIPS)':
 '4': CDS_PINID='\4\';
NODE_NAME     ME10 5
 '@TIMECARD_LIB.TIMECARD(SCH_1):PAGE33_I5@MECH.MEC_MTH8(CHIPS)':
 '5': CDS_PINID='\5\';
NODE_NAME     ME10 6
 '@TIMECARD_LIB.TIMECARD(SCH_1):PAGE33_I5@MECH.MEC_MTH8(CHIPS)':
 '6': CDS_PINID='\6\';
NODE_NAME     ME10 7
 '@TIMECARD_LIB.TIMECARD(SCH_1):PAGE33_I5@MECH.MEC_MTH8(CHIPS)':
 '7': CDS_PINID='\7\';
NODE_NAME     ME10 8
 '@TIMECARD_LIB.TIMECARD(SCH_1):PAGE33_I5@MECH.MEC_MTH8(CHIPS)':
 '8': CDS_PINID='\8\';
NODE_NAME     ME9 1
 '@TIMECARD_LIB.TIMECARD(SCH_1):PAGE33_I7@MECH.MEC_MTH8(CHIPS)':
 '1': CDS_PINID='\1\';
NODE_NAME     ME9 2
 '@TIMECARD_LIB.TIMECARD(SCH_1):PAGE33_I7@MECH.MEC_MTH8(CHIPS)':
 '2': CDS_PINID='\2\';
NODE_NAME     ME9 3
 '@TIMECARD_LIB.TIMECARD(SCH_1):PAGE33_I7@MECH.MEC_MTH8(CHIPS)':
 '3': CDS_PINID='\3\';
NODE_NAME     ME9 4
 '@TIMECARD_LIB.TIMECARD(SCH_1):PAGE33_I7@MECH.MEC_MTH8(CHIPS)':
 '4': CDS_PINID='\4\';
NODE_NAME     ME9 5
 '@TIMECARD_LIB.TIMECARD(SCH_1):PAGE33_I7@MECH.MEC_MTH8(CHIPS)':
 '5': CDS_PINID='\5\';
NODE_NAME     ME9 6
 '@TIMECARD_LIB.TIMECARD(SCH_1):PAGE33_I7@MECH.MEC_MTH8(CHIPS)':
 '6': CDS_PINID='\6\';
NODE_NAME     ME9 7
 '@TIMECARD_LIB.TIMECARD(SCH_1):PAGE33_I7@MECH.MEC_MTH8(CHIPS)':
 '7': CDS_PINID='\7\';
NODE_NAME     ME9 8
 '@TIMECARD_LIB.TIMECARD(SCH_1):PAGE33_I7@MECH.MEC_MTH8(CHIPS)':
 '8': CDS_PINID='\8\';
NODE_NAME     ME3 1
 '@TIMECARD_LIB.TIMECARD(SCH_1):PAGE33_I125@MECH.NUT(CHIPS)':
 '1': CDS_PINID='\1\';
NODE_NAME     ME4 1
 '@TIMECARD_LIB.TIMECARD(SCH_1):PAGE33_I126@MECH.NUT(CHIPS)':
 '1': CDS_PINID='\1\';
NODE_NAME     ME1 1
 '@TIMECARD_LIB.TIMECARD(SCH_1):PAGE33_I127@MECH.NUT(CHIPS)':
 '1': CDS_PINID='\1\';
NODE_NAME     ME2 1
 '@TIMECARD_LIB.TIMECARD(SCH_1):PAGE33_I129@MECH.NUT(CHIPS)':
 '1': CDS_PINID='\1\';
NODE_NAME     C310 1
 '@TIMECARD_LIB.TIMECARD(SCH_1):PAGE12_I318@PASSIVE.CAPACITOR(CHIPS)':
 '1': CDS_PINID='\1\';
NODE_NAME     R496 1
 '@TIMECARD_LIB.TIMECARD(SCH_1):PAGE12_I320@PASSIVE.RESISTOR(CHIPS)':
 '1': CDS_PINID='\1\';
NODE_NAME     R497 1
 '@TIMECARD_LIB.TIMECARD(SCH_1):PAGE12_I322@PASSIVE.RESISTOR(CHIPS)':
 '1': CDS_PINID='\1\';
NODE_NAME     R498 1
 '@TIMECARD_LIB.TIMECARD(SCH_1):PAGE12_I327@PASSIVE.RESISTOR(CHIPS)':
 '1': CDS_PINID='\1\';
NODE_NAME     C317 1
 '@TIMECARD_LIB.TIMECARD(SCH_1):PAGE12_I328@PASSIVE.CAPACITOR(CHIPS)':
 '1': CDS_PINID='\1\';
NODE_NAME     C311 1
 '@TIMECARD_LIB.TIMECARD(SCH_1):PAGE12_I321@PASSIVE.CAPACITOR(CHIPS)':
 '1': CDS_PINID='\1\';
NODE_NAME     R499 1
 '@TIMECARD_LIB.TIMECARD(SCH_1):PAGE12_I331@PASSIVE.RESISTOR(CHIPS)':
 '1': CDS_PINID='\1\';
NODE_NAME     C318 1
 '@TIMECARD_LIB.TIMECARD(SCH_1):PAGE12_I332@PASSIVE.CAPACITOR(CHIPS)':
 '1': CDS_PINID='\1\';
NODE_NAME     R501 1
 '@TIMECARD_LIB.TIMECARD(SCH_1):PAGE161_I241@PASSIVE.RESISTOR(CHIPS)':
 '1': CDS_PINID='\1\';
NODE_NAME     R500 1
 '@TIMECARD_LIB.TIMECARD(SCH_1):PAGE161_I242@PASSIVE.RESISTOR(CHIPS)':
 '1': CDS_PINID='\1\';
NODE_NAME     R504 2
 '@TIMECARD_LIB.TIMECARD(SCH_1):PAGE161_I244@PASSIVE.RESISTOR(CHIPS)':
 '2': CDS_PINID='\2\';
NODE_NAME     R503 2
 '@TIMECARD_LIB.TIMECARD(SCH_1):PAGE161_I246@PASSIVE.RESISTOR(CHIPS)':
 '2': CDS_PINID='\2\';
NODE_NAME     J13 GH1
 '@TIMECARD_LIB.TIMECARD(SCH_1):PAGE524_I495@CONNECTOR.CONN_USB_14P_GH4_F_RA_TH(CHIPS)':
 'GH1': CDS_PINID='GH1';
NODE_NAME     J13 GH2
 '@TIMECARD_LIB.TIMECARD(SCH_1):PAGE524_I495@CONNECTOR.CONN_USB_14P_GH4_F_RA_TH(CHIPS)':
 'GH2': CDS_PINID='GH2';
NODE_NAME     J13 GH3
 '@TIMECARD_LIB.TIMECARD(SCH_1):PAGE524_I495@CONNECTOR.CONN_USB_14P_GH4_F_RA_TH(CHIPS)':
 'GH3': CDS_PINID='GH3';
NODE_NAME     J13 GH4
 '@TIMECARD_LIB.TIMECARD(SCH_1):PAGE524_I495@CONNECTOR.CONN_USB_14P_GH4_F_RA_TH(CHIPS)':
 'GH4': CDS_PINID='GH4';
NODE_NAME     J13 A1
 '@TIMECARD_LIB.TIMECARD(SCH_1):PAGE524_I495@CONNECTOR.CONN_USB_14P_GH4_F_RA_TH(CHIPS)':
 'GND_1': CDS_PINID='GND_1';
NODE_NAME     J13 A12
 '@TIMECARD_LIB.TIMECARD(SCH_1):PAGE524_I495@CONNECTOR.CONN_USB_14P_GH4_F_RA_TH(CHIPS)':
 'GND_2': CDS_PINID='GND_2';
NODE_NAME     J13 B1
 '@TIMECARD_LIB.TIMECARD(SCH_1):PAGE524_I495@CONNECTOR.CONN_USB_14P_GH4_F_RA_TH(CHIPS)':
 'GND_3': CDS_PINID='GND_3';
NODE_NAME     J13 B12
 '@TIMECARD_LIB.TIMECARD(SCH_1):PAGE524_I495@CONNECTOR.CONN_USB_14P_GH4_F_RA_TH(CHIPS)':
 'GND_4': CDS_PINID='GND_4';
NODE_NAME     R442 2
 '@TIMECARD_LIB.TIMECARD(SCH_1):PAGE524_I497@PASSIVE.RESISTOR(CHIPS)':
 '2': CDS_PINID='\2\';
NODE_NAME     U34 2
 '@TIMECARD_LIB.TIMECARD(SCH_1):PAGE3_I139@ANALOG.TPS3808G18DBVR_SOT23_6(CHIPS)':
 'GND': CDS_PINID='GND';
NODE_NAME     DS9 C
 '@TIMECARD_LIB.TIMECARD(SCH_1):PAGE14_I292@DISCRETE.OPTICAL(CHIPS)':
 'C': CDS_PINID='C';
NODE_NAME     C250 2
 '@TIMECARD_LIB.TIMECARD(SCH_1):PAGE3_I152@PASSIVE.CAPACITOR(CHIPS)':
 '2': CDS_PINID='\2\';
NODE_NAME     R224 1
 '@TIMECARD_LIB.TIMECARD(SCH_1):PAGE161_I253@PASSIVE.RESISTOR(CHIPS)':
 '1': CDS_PINID='\1\';
NET_NAME
'SHT3X_ADDR'
 '@TIMECARD_LIB.TIMECARD(SCH_1):SHT3X_ADDR':
 C_SIGNAL='@timecard_lib.timecard(sch_1):sht3x_addr';
NODE_NAME     R69 1
 '@TIMECARD_LIB.TIMECARD(SCH_1):PAGE7_I7@PASSIVE.RESISTOR(CHIPS)':
 '1': CDS_PINID='\1\';
NODE_NAME     R68 2
 '@TIMECARD_LIB.TIMECARD(SCH_1):PAGE7_I8@PASSIVE.RESISTOR(CHIPS)':
 '2': CDS_PINID='\2\';
NODE_NAME     U27 2
 '@TIMECARD_LIB.TIMECARD(SCH_1):PAGE7_I44@ANALOG.SHT31A_DIS_B10KS_DFN8(CHIPS)':
 'ADDR': CDS_PINID='ADDR';
NET_NAME
'SHT3X_I2C_SCL'
 '@TIMECARD_LIB.TIMECARD(SCH_1):SHT3X_I2C_SCL':
 C_SIGNAL='@timecard_lib.timecard(sch_1):sht3x_i2c_scl';
NODE_NAME     U4 7
 '@TIMECARD_LIB.TIMECARD(SCH_1):PAGE5_I33@INTERFACE.PCA9546APW_TSSOP16(CHIPS)':
 'SC1': CDS_PINID='SC1';
NODE_NAME     R65 2
 '@TIMECARD_LIB.TIMECARD(SCH_1):PAGE7_I4@PASSIVE.RESISTOR(CHIPS)':
 '2': CDS_PINID='\2\';
NODE_NAME     R67 1
 '@TIMECARD_LIB.TIMECARD(SCH_1):PAGE7_I13@PASSIVE.RESISTOR(CHIPS)':
 '1': CDS_PINID='\1\';
NET_NAME
'SHT3X_I2C_SDA'
 '@TIMECARD_LIB.TIMECARD(SCH_1):SHT3X_I2C_SDA':
 C_SIGNAL='@timecard_lib.timecard(sch_1):sht3x_i2c_sda';
NODE_NAME     U4 6
 '@TIMECARD_LIB.TIMECARD(SCH_1):PAGE5_I33@INTERFACE.PCA9546APW_TSSOP16(CHIPS)':
 'SD1': CDS_PINID='SD1';
NODE_NAME     R64 2
 '@TIMECARD_LIB.TIMECARD(SCH_1):PAGE7_I3@PASSIVE.RESISTOR(CHIPS)':
 '2': CDS_PINID='\2\';
NODE_NAME     R66 1
 '@TIMECARD_LIB.TIMECARD(SCH_1):PAGE7_I14@PASSIVE.RESISTOR(CHIPS)':
 '1': CDS_PINID='\1\';
NET_NAME
'SMA1_LED_BLUE_N'
 '@TIMECARD_LIB.TIMECARD(SCH_1):SMA1_LED_BLUE_N':
 C_SIGNAL='@timecard_lib.timecard(sch_1):sma1_led_blue_n';
NODE_NAME     R385 1
 '@TIMECARD_LIB.TIMECARD(SCH_1):PAGE14_I107@PASSIVE.RESISTOR(CHIPS)':
 '1': CDS_PINID='\1\';
NODE_NAME     U33 10
 '@TIMECARD_LIB.TIMECARD(SCH_1):PAGE14_I219@INTERFACE.IS32FL3207_QWLA3_TR_QFN29(CHIPS)':
 'OUT3': CDS_PINID='OUT3';
NET_NAME
'SMA1_LED_GREEN_N'
 '@TIMECARD_LIB.TIMECARD(SCH_1):SMA1_LED_GREEN_N':
 C_SIGNAL='@timecard_lib.timecard(sch_1):sma1_led_green_n';
NODE_NAME     R386 1
 '@TIMECARD_LIB.TIMECARD(SCH_1):PAGE14_I108@PASSIVE.RESISTOR(CHIPS)':
 '1': CDS_PINID='\1\';
NODE_NAME     U33 8
 '@TIMECARD_LIB.TIMECARD(SCH_1):PAGE14_I219@INTERFACE.IS32FL3207_QWLA3_TR_QFN29(CHIPS)':
 'OUT1': CDS_PINID='OUT1';
NET_NAME
'SMA1_LED_RED_N'
 '@TIMECARD_LIB.TIMECARD(SCH_1):SMA1_LED_RED_N':
 C_SIGNAL='@timecard_lib.timecard(sch_1):sma1_led_red_n';
NODE_NAME     R387 1
 '@TIMECARD_LIB.TIMECARD(SCH_1):PAGE14_I110@PASSIVE.RESISTOR(CHIPS)':
 '1': CDS_PINID='\1\';
NODE_NAME     U33 9
 '@TIMECARD_LIB.TIMECARD(SCH_1):PAGE14_I219@INTERFACE.IS32FL3207_QWLA3_TR_QFN29(CHIPS)':
 'OUT2': CDS_PINID='OUT2';
NET_NAME
'SMA1_SIG_IN_BF_EN_N'
 '@TIMECARD_LIB.TIMECARD(SCH_1):SMA1_SIG_IN_BF_EN_N':
 C_SIGNAL='@timecard_lib.timecard(sch_1):sma1_sig_in_bf_en_n';
NODE_NAME     U24 K14
 '@TIMECARD_LIB.TIMECARD(SCH_1):PAGE162_I228@PLD.XC7A200T_2FBG484C_FBG484(CHIPS)':
 'IO_L19N_T3_A21_VREF_15': CDS_PINID='IO_L19N_T3_A21_VREF_15';
NODE_NAME     U15 7
 '@TIMECARD_LIB.TIMECARD(SCH_1):PAGE12_I255@STDLOGIC.74HCT2G125DP_TSSOP8(CHIPS)':
 '2OE*': CDS_PINID='\2oe*\';
NODE_NAME     R381 2
 '@TIMECARD_LIB.TIMECARD(SCH_1):PAGE12_I262@PASSIVE.RESISTOR(CHIPS)':
 '2': CDS_PINID='\2\';
NODE_NAME     TP28 1
 '@TIMECARD_LIB.TIMECARD(SCH_1):PAGE16_I1667@CLS.TP_PIONT(CHIPS)':
 '1': CDS_PINID='\1\';
NET_NAME
'SMA1_SIG_IO_CONN'
 '@TIMECARD_LIB.TIMECARD(SCH_1):SMA1_SIG_IO_CONN':
 C_SIGNAL='@timecard_lib.timecard(sch_1):sma1_sig_io_conn';
NODE_NAME     CR4 3
 '@TIMECARD_LIB.TIMECARD(SCH_1):PAGE12_I179@DISCRETE.DIODE_4_V1(CHIPS)':
 'IO2': CDS_PINID='IO2';
NODE_NAME     R127 2
 '@TIMECARD_LIB.TIMECARD(SCH_1):PAGE12_I257@PASSIVE.RESISTOR(CHIPS)':
 '2': CDS_PINID='\2\';
NODE_NAME     J3 1
 '@TIMECARD_LIB.TIMECARD(SCH_1):PAGE12_I297@CONNECTOR.CONN_JACK_1P_GH4_S_TH(CHIPS)':
 '1': CDS_PINID='\1\';
NET_NAME
'SMA1_SIG_OUT_BF_EN_N'
 '@TIMECARD_LIB.TIMECARD(SCH_1):SMA1_SIG_OUT_BF_EN_N':
 C_SIGNAL='@timecard_lib.timecard(sch_1):sma1_sig_out_bf_en_n';
NODE_NAME     U24 K13
 '@TIMECARD_LIB.TIMECARD(SCH_1):PAGE162_I228@PLD.XC7A200T_2FBG484C_FBG484(CHIPS)':
 'IO_L19P_T3_A22_15': CDS_PINID='IO_L19P_T3_A22_15';
NODE_NAME     U15 1
 '@TIMECARD_LIB.TIMECARD(SCH_1):PAGE12_I255@STDLOGIC.74HCT2G125DP_TSSOP8(CHIPS)':
 '1OE*': CDS_PINID='\1oe*\';
NODE_NAME     R361 2
 '@TIMECARD_LIB.TIMECARD(SCH_1):PAGE12_I261@PASSIVE.RESISTOR(CHIPS)':
 '2': CDS_PINID='\2\';
NODE_NAME     TP32 1
 '@TIMECARD_LIB.TIMECARD(SCH_1):PAGE16_I1662@CLS.TP_PIONT(CHIPS)':
 '1': CDS_PINID='\1\';
NET_NAME
'SMA2_LED_BLUE_N'
 '@TIMECARD_LIB.TIMECARD(SCH_1):SMA2_LED_BLUE_N':
 C_SIGNAL='@timecard_lib.timecard(sch_1):sma2_led_blue_n';
NODE_NAME     R388 1
 '@TIMECARD_LIB.TIMECARD(SCH_1):PAGE14_I147@PASSIVE.RESISTOR(CHIPS)':
 '1': CDS_PINID='\1\';
NODE_NAME     U33 14
 '@TIMECARD_LIB.TIMECARD(SCH_1):PAGE14_I219@INTERFACE.IS32FL3207_QWLA3_TR_QFN29(CHIPS)':
 'OUT6': CDS_PINID='OUT6';
NET_NAME
'SMA2_LED_GREEN_N'
 '@TIMECARD_LIB.TIMECARD(SCH_1):SMA2_LED_GREEN_N':
 C_SIGNAL='@timecard_lib.timecard(sch_1):sma2_led_green_n';
NODE_NAME     R389 1
 '@TIMECARD_LIB.TIMECARD(SCH_1):PAGE14_I148@PASSIVE.RESISTOR(CHIPS)':
 '1': CDS_PINID='\1\';
NODE_NAME     U33 12
 '@TIMECARD_LIB.TIMECARD(SCH_1):PAGE14_I219@INTERFACE.IS32FL3207_QWLA3_TR_QFN29(CHIPS)':
 'OUT4': CDS_PINID='OUT4';
NET_NAME
'SMA2_LED_RED_N'
 '@TIMECARD_LIB.TIMECARD(SCH_1):SMA2_LED_RED_N':
 C_SIGNAL='@timecard_lib.timecard(sch_1):sma2_led_red_n';
NODE_NAME     R390 1
 '@TIMECARD_LIB.TIMECARD(SCH_1):PAGE14_I146@PASSIVE.RESISTOR(CHIPS)':
 '1': CDS_PINID='\1\';
NODE_NAME     U33 13
 '@TIMECARD_LIB.TIMECARD(SCH_1):PAGE14_I219@INTERFACE.IS32FL3207_QWLA3_TR_QFN29(CHIPS)':
 'OUT5': CDS_PINID='OUT5';
NET_NAME
'SMA2_SIG_IN_BF_EN_N'
 '@TIMECARD_LIB.TIMECARD(SCH_1):SMA2_SIG_IN_BF_EN_N':
 C_SIGNAL='@timecard_lib.timecard(sch_1):sma2_sig_in_bf_en_n';
NODE_NAME     U24 L13
 '@TIMECARD_LIB.TIMECARD(SCH_1):PAGE162_I228@PLD.XC7A200T_2FBG484C_FBG484(CHIPS)':
 'IO_L20N_T3_A19_15': CDS_PINID='IO_L20N_T3_A19_15';
NODE_NAME     U16 7
 '@TIMECARD_LIB.TIMECARD(SCH_1):PAGE12_I273@STDLOGIC.74HCT2G125DP_TSSOP8(CHIPS)':
 '2OE*': CDS_PINID='\2oe*\';
NODE_NAME     R383 2
 '@TIMECARD_LIB.TIMECARD(SCH_1):PAGE12_I281@PASSIVE.RESISTOR(CHIPS)':
 '2': CDS_PINID='\2\';
NODE_NAME     TP29 1
 '@TIMECARD_LIB.TIMECARD(SCH_1):PAGE16_I1672@CLS.TP_PIONT(CHIPS)':
 '1': CDS_PINID='\1\';
NET_NAME
'SMA2_SIG_IO_CONN'
 '@TIMECARD_LIB.TIMECARD(SCH_1):SMA2_SIG_IO_CONN':
 C_SIGNAL='@timecard_lib.timecard(sch_1):sma2_sig_io_conn';
NODE_NAME     CR4 2
 '@TIMECARD_LIB.TIMECARD(SCH_1):PAGE12_I179@DISCRETE.DIODE_4_V1(CHIPS)':
 'IO1': CDS_PINID='IO1';
NODE_NAME     R126 2
 '@TIMECARD_LIB.TIMECARD(SCH_1):PAGE12_I276@PASSIVE.RESISTOR(CHIPS)':
 '2': CDS_PINID='\2\';
NODE_NAME     J4 1
 '@TIMECARD_LIB.TIMECARD(SCH_1):PAGE12_I300@CONNECTOR.CONN_JACK_1P_GH4_S_TH(CHIPS)':
 '1': CDS_PINID='\1\';
NET_NAME
'SMA2_SIG_OUT_BF_EN_N'
 '@TIMECARD_LIB.TIMECARD(SCH_1):SMA2_SIG_OUT_BF_EN_N':
 C_SIGNAL='@timecard_lib.timecard(sch_1):sma2_sig_out_bf_en_n';
NODE_NAME     U24 M13
 '@TIMECARD_LIB.TIMECARD(SCH_1):PAGE162_I228@PLD.XC7A200T_2FBG484C_FBG484(CHIPS)':
 'IO_L20P_T3_A20_15': CDS_PINID='IO_L20P_T3_A20_15';
NODE_NAME     U16 1
 '@TIMECARD_LIB.TIMECARD(SCH_1):PAGE12_I273@STDLOGIC.74HCT2G125DP_TSSOP8(CHIPS)':
 '1OE*': CDS_PINID='\1oe*\';
NODE_NAME     R331 2
 '@TIMECARD_LIB.TIMECARD(SCH_1):PAGE12_I280@PASSIVE.RESISTOR(CHIPS)':
 '2': CDS_PINID='\2\';
NODE_NAME     TP33 1
 '@TIMECARD_LIB.TIMECARD(SCH_1):PAGE16_I1669@CLS.TP_PIONT(CHIPS)':
 '1': CDS_PINID='\1\';
NET_NAME
'SMA3_LED_BLUE_N'
 '@TIMECARD_LIB.TIMECARD(SCH_1):SMA3_LED_BLUE_N':
 C_SIGNAL='@timecard_lib.timecard(sch_1):sma3_led_blue_n';
NODE_NAME     R391 1
 '@TIMECARD_LIB.TIMECARD(SCH_1):PAGE14_I150@PASSIVE.RESISTOR(CHIPS)':
 '1': CDS_PINID='\1\';
NODE_NAME     U33 17
 '@TIMECARD_LIB.TIMECARD(SCH_1):PAGE14_I219@INTERFACE.IS32FL3207_QWLA3_TR_QFN29(CHIPS)':
 'OUT9': CDS_PINID='OUT9';
NET_NAME
'SMA3_LED_GREEN_N'
 '@TIMECARD_LIB.TIMECARD(SCH_1):SMA3_LED_GREEN_N':
 C_SIGNAL='@timecard_lib.timecard(sch_1):sma3_led_green_n';
NODE_NAME     R392 1
 '@TIMECARD_LIB.TIMECARD(SCH_1):PAGE14_I149@PASSIVE.RESISTOR(CHIPS)':
 '1': CDS_PINID='\1\';
NODE_NAME     U33 15
 '@TIMECARD_LIB.TIMECARD(SCH_1):PAGE14_I219@INTERFACE.IS32FL3207_QWLA3_TR_QFN29(CHIPS)':
 'OUT7': CDS_PINID='OUT7';
NET_NAME
'SMA3_LED_RED_N'
 '@TIMECARD_LIB.TIMECARD(SCH_1):SMA3_LED_RED_N':
 C_SIGNAL='@timecard_lib.timecard(sch_1):sma3_led_red_n';
NODE_NAME     R393 1
 '@TIMECARD_LIB.TIMECARD(SCH_1):PAGE14_I151@PASSIVE.RESISTOR(CHIPS)':
 '1': CDS_PINID='\1\';
NODE_NAME     U33 16
 '@TIMECARD_LIB.TIMECARD(SCH_1):PAGE14_I219@INTERFACE.IS32FL3207_QWLA3_TR_QFN29(CHIPS)':
 'OUT8': CDS_PINID='OUT8';
NET_NAME
'SMA3_SIG_IN_BF_EN_N'
 '@TIMECARD_LIB.TIMECARD(SCH_1):SMA3_SIG_IN_BF_EN_N':
 C_SIGNAL='@timecard_lib.timecard(sch_1):sma3_sig_in_bf_en_n';
NODE_NAME     U24 H15
 '@TIMECARD_LIB.TIMECARD(SCH_1):PAGE162_I228@PLD.XC7A200T_2FBG484C_FBG484(CHIPS)':
 'IO_L5N_T0_AD9N_15': CDS_PINID='IO_L5N_T0_AD9N_15';
NODE_NAME     U13 7
 '@TIMECARD_LIB.TIMECARD(SCH_1):PAGE12_I204@STDLOGIC.74HCT2G125DP_TSSOP8(CHIPS)':
 '2OE*': CDS_PINID='\2oe*\';
NODE_NAME     R377 2
 '@TIMECARD_LIB.TIMECARD(SCH_1):PAGE12_I206@PASSIVE.RESISTOR(CHIPS)':
 '2': CDS_PINID='\2\';
NODE_NAME     TP30 1
 '@TIMECARD_LIB.TIMECARD(SCH_1):PAGE16_I1678@CLS.TP_PIONT(CHIPS)':
 '1': CDS_PINID='\1\';
NET_NAME
'SMA3_SIG_IO_CONN'
 '@TIMECARD_LIB.TIMECARD(SCH_1):SMA3_SIG_IO_CONN':
 C_SIGNAL='@timecard_lib.timecard(sch_1):sma3_sig_io_conn';
NODE_NAME     CR5 3
 '@TIMECARD_LIB.TIMECARD(SCH_1):PAGE12_I42@DISCRETE.DIODE_4_V1(CHIPS)':
 'IO2': CDS_PINID='IO2';
NODE_NAME     R122 2
 '@TIMECARD_LIB.TIMECARD(SCH_1):PAGE12_I197@PASSIVE.RESISTOR(CHIPS)':
 '2': CDS_PINID='\2\';
NODE_NAME     J1 1
 '@TIMECARD_LIB.TIMECARD(SCH_1):PAGE12_I290@CONNECTOR.CONN_JACK_1P_GH4_S_TH(CHIPS)':
 '1': CDS_PINID='\1\';
NET_NAME
'SMA3_SIG_OUT_BF_EN_N'
 '@TIMECARD_LIB.TIMECARD(SCH_1):SMA3_SIG_OUT_BF_EN_N':
 C_SIGNAL='@timecard_lib.timecard(sch_1):sma3_sig_out_bf_en_n';
NODE_NAME     U24 J15
 '@TIMECARD_LIB.TIMECARD(SCH_1):PAGE162_I228@PLD.XC7A200T_2FBG484C_FBG484(CHIPS)':
 'IO_L5P_T0_AD9P_15': CDS_PINID='IO_L5P_T0_AD9P_15';
NODE_NAME     R365 2
 '@TIMECARD_LIB.TIMECARD(SCH_1):PAGE12_I88@PASSIVE.RESISTOR(CHIPS)':
 '2': CDS_PINID='\2\';
NODE_NAME     U13 1
 '@TIMECARD_LIB.TIMECARD(SCH_1):PAGE12_I204@STDLOGIC.74HCT2G125DP_TSSOP8(CHIPS)':
 '1OE*': CDS_PINID='\1oe*\';
NODE_NAME     TP34 1
 '@TIMECARD_LIB.TIMECARD(SCH_1):PAGE16_I1673@CLS.TP_PIONT(CHIPS)':
 '1': CDS_PINID='\1\';
NET_NAME
'SMA4_LED_BLUE_N'
 '@TIMECARD_LIB.TIMECARD(SCH_1):SMA4_LED_BLUE_N':
 C_SIGNAL='@timecard_lib.timecard(sch_1):sma4_led_blue_n';
NODE_NAME     R394 1
 '@TIMECARD_LIB.TIMECARD(SCH_1):PAGE14_I153@PASSIVE.RESISTOR(CHIPS)':
 '1': CDS_PINID='\1\';
NODE_NAME     U33 21
 '@TIMECARD_LIB.TIMECARD(SCH_1):PAGE14_I219@INTERFACE.IS32FL3207_QWLA3_TR_QFN29(CHIPS)':
 'OUT12': CDS_PINID='OUT12';
NET_NAME
'SMA4_LED_GREEN_N'
 '@TIMECARD_LIB.TIMECARD(SCH_1):SMA4_LED_GREEN_N':
 C_SIGNAL='@timecard_lib.timecard(sch_1):sma4_led_green_n';
NODE_NAME     R395 1
 '@TIMECARD_LIB.TIMECARD(SCH_1):PAGE14_I152@PASSIVE.RESISTOR(CHIPS)':
 '1': CDS_PINID='\1\';
NODE_NAME     U33 19
 '@TIMECARD_LIB.TIMECARD(SCH_1):PAGE14_I219@INTERFACE.IS32FL3207_QWLA3_TR_QFN29(CHIPS)':
 'OUT10': CDS_PINID='OUT10';
NET_NAME
'SMA4_LED_RED_N'
 '@TIMECARD_LIB.TIMECARD(SCH_1):SMA4_LED_RED_N':
 C_SIGNAL='@timecard_lib.timecard(sch_1):sma4_led_red_n';
NODE_NAME     R396 1
 '@TIMECARD_LIB.TIMECARD(SCH_1):PAGE14_I154@PASSIVE.RESISTOR(CHIPS)':
 '1': CDS_PINID='\1\';
NODE_NAME     U33 20
 '@TIMECARD_LIB.TIMECARD(SCH_1):PAGE14_I219@INTERFACE.IS32FL3207_QWLA3_TR_QFN29(CHIPS)':
 'OUT11': CDS_PINID='OUT11';
NET_NAME
'SMA4_SIG_IN_BF_EN_N'
 '@TIMECARD_LIB.TIMECARD(SCH_1):SMA4_SIG_IN_BF_EN_N':
 C_SIGNAL='@timecard_lib.timecard(sch_1):sma4_sig_in_bf_en_n';
NODE_NAME     U24 J14
 '@TIMECARD_LIB.TIMECARD(SCH_1):PAGE162_I228@PLD.XC7A200T_2FBG484C_FBG484(CHIPS)':
 'IO_L3P_T0_DQS_AD1P_15': CDS_PINID='IO_L3P_T0_DQS_AD1P_15';
NODE_NAME     U14 7
 '@TIMECARD_LIB.TIMECARD(SCH_1):PAGE12_I226@STDLOGIC.74HCT2G125DP_TSSOP8(CHIPS)':
 '2OE*': CDS_PINID='\2oe*\';
NODE_NAME     R379 2
 '@TIMECARD_LIB.TIMECARD(SCH_1):PAGE12_I234@PASSIVE.RESISTOR(CHIPS)':
 '2': CDS_PINID='\2\';
NODE_NAME     TP31 1
 '@TIMECARD_LIB.TIMECARD(SCH_1):PAGE16_I1679@CLS.TP_PIONT(CHIPS)':
 '1': CDS_PINID='\1\';
NET_NAME
'SMA4_SIG_IO_CONN'
 '@TIMECARD_LIB.TIMECARD(SCH_1):SMA4_SIG_IO_CONN':
 C_SIGNAL='@timecard_lib.timecard(sch_1):sma4_sig_io_conn';
NODE_NAME     CR5 2
 '@TIMECARD_LIB.TIMECARD(SCH_1):PAGE12_I42@DISCRETE.DIODE_4_V1(CHIPS)':
 'IO1': CDS_PINID='IO1';
NODE_NAME     R123 2
 '@TIMECARD_LIB.TIMECARD(SCH_1):PAGE12_I228@PASSIVE.RESISTOR(CHIPS)':
 '2': CDS_PINID='\2\';
NODE_NAME     J2 1
 '@TIMECARD_LIB.TIMECARD(SCH_1):PAGE12_I294@CONNECTOR.CONN_JACK_1P_GH4_S_TH(CHIPS)':
 '1': CDS_PINID='\1\';
NET_NAME
'SMA4_SIG_OUT_BF_EN_N'
 '@TIMECARD_LIB.TIMECARD(SCH_1):SMA4_SIG_OUT_BF_EN_N':
 C_SIGNAL='@timecard_lib.timecard(sch_1):sma4_sig_out_bf_en_n';
NODE_NAME     U24 H14
 '@TIMECARD_LIB.TIMECARD(SCH_1):PAGE162_I228@PLD.XC7A200T_2FBG484C_FBG484(CHIPS)':
 'IO_L3N_T0_DQS_AD1N_15': CDS_PINID='IO_L3N_T0_DQS_AD1N_15';
NODE_NAME     U14 1
 '@TIMECARD_LIB.TIMECARD(SCH_1):PAGE12_I226@STDLOGIC.74HCT2G125DP_TSSOP8(CHIPS)':
 '1OE*': CDS_PINID='\1oe*\';
NODE_NAME     R368 2
 '@TIMECARD_LIB.TIMECARD(SCH_1):PAGE12_I233@PASSIVE.RESISTOR(CHIPS)':
 '2': CDS_PINID='\2\';
NODE_NAME     TP35 1
 '@TIMECARD_LIB.TIMECARD(SCH_1):PAGE16_I1675@CLS.TP_PIONT(CHIPS)':
 '1': CDS_PINID='\1\';
NET_NAME
'SMA_ANALOG_TUNING_IN'
 '@TIMECARD_LIB.TIMECARD(SCH_1):SMA_ANALOG_TUNING_IN':
 C_SIGNAL='@timecard_lib.timecard(sch_1):sma_analog_tuning_in';
NODE_NAME     R91 2
 '@TIMECARD_LIB.TIMECARD(SCH_1):PAGE527_I187@PASSIVE.RESISTOR(CHIPS)':
 '2': CDS_PINID='\2\';
NODE_NAME     J18 2
 '@TIMECARD_LIB.TIMECARD(SCH_1):PAGE527_I198@CONNECTOR.CONN_HDR_1X3_M_S_SMT(CHIPS)':
 '2': CDS_PINID='\2\';
NET_NAME
'SN_EEPROM_WP'
 '@TIMECARD_LIB.TIMECARD(SCH_1):SN_EEPROM_WP':
 C_SIGNAL='@timecard_lib.timecard(sch_1):sn_eeprom_wp';
NODE_NAME     U7 5
 '@TIMECARD_LIB.TIMECARD(SCH_1):PAGE5_I89@MEMORY.AT24MAC402_SOT23_5(CHIPS)':
 'WP': CDS_PINID='WP';
NODE_NAME     R1992 2
 '@TIMECARD_LIB.TIMECARD(SCH_1):PAGE5_I94@PASSIVE.RESISTOR(CHIPS)':
 '2': CDS_PINID='\2\';
NODE_NAME     R344 1
 '@TIMECARD_LIB.TIMECARD(SCH_1):PAGE5_I97@PASSIVE.RESISTOR(CHIPS)':
 '1': CDS_PINID='\1\';
NODE_NAME     J17 1
 '@TIMECARD_LIB.TIMECARD(SCH_1):PAGE5_I127@CONNECTOR.CONN_HDR_2X2_M_S_SMT(CHIPS)':
 '1': CDS_PINID='\1\';
NODE_NAME     R1 2
 '@TIMECARD_LIB.TIMECARD(SCH_1):PAGE5_I130@PASSIVE.RESISTOR(CHIPS)':
 '2': CDS_PINID='\2\';
NODE_NAME     TP19 1
 '@TIMECARD_LIB.TIMECARD(SCH_1):PAGE16_I1634@CLS.TP_PIONT(CHIPS)':
 '1': CDS_PINID='\1\';
NET_NAME
'UART_FT4232_RX_FPGA_TX'
 '@TIMECARD_LIB.TIMECARD(SCH_1):UART_FT4232_RX_FPGA_TX':
 C_SIGNAL='@timecard_lib.timecard(sch_1):uart_ft4232_rx_fpga_tx';
NODE_NAME     U24 P15
 '@TIMECARD_LIB.TIMECARD(SCH_1):PAGE161_I2@PLD.XC7A200T_2FBG484C_FBG484(CHIPS)':
 'IO_L22P_T3_A05_D21_14': CDS_PINID='IO_L22P_T3_A05_D21_14';
NODE_NAME     R352 2
 '@TIMECARD_LIB.TIMECARD(SCH_1):PAGE524_I154@PASSIVE.RESISTOR(CHIPS)':
 '2': CDS_PINID='\2\';
NET_NAME
'UART_FT4232_TX_FPGA_RX'
 '@TIMECARD_LIB.TIMECARD(SCH_1):UART_FT4232_TX_FPGA_RX':
 C_SIGNAL='@timecard_lib.timecard(sch_1):uart_ft4232_tx_fpga_rx';
NODE_NAME     U24 P16
 '@TIMECARD_LIB.TIMECARD(SCH_1):PAGE161_I2@PLD.XC7A200T_2FBG484C_FBG484(CHIPS)':
 'IO_L24P_T3_A01_D17_14': CDS_PINID='IO_L24P_T3_A01_D17_14';
NODE_NAME     R480 1
 '@TIMECARD_LIB.TIMECARD(SCH_1):PAGE524_I149@PASSIVE.RESISTOR(CHIPS)':
 '1': CDS_PINID='\1\';
NODE_NAME     R353 2
 '@TIMECARD_LIB.TIMECARD(SCH_1):PAGE524_I153@PASSIVE.RESISTOR(CHIPS)':
 '2': CDS_PINID='\2\';
NET_NAME
'UART_GPS_RX_FPGA_TX'
 '@TIMECARD_LIB.TIMECARD(SCH_1):UART_GPS_RX_FPGA_TX':
 C_SIGNAL='@timecard_lib.timecard(sch_1):uart_gps_rx_fpga_tx';
NODE_NAME     R110 1
 '@TIMECARD_LIB.TIMECARD(SCH_1):PAGE11_I29@PASSIVE.RESISTOR(CHIPS)':
 '1': CDS_PINID='\1\';
NODE_NAME     U24 P20
 '@TIMECARD_LIB.TIMECARD(SCH_1):PAGE161_I2@PLD.XC7A200T_2FBG484C_FBG484(CHIPS)':
 'IO_0_14': CDS_PINID='IO_0_14';
NET_NAME
'UART_GPS_TX_FPGA_RX'
 '@TIMECARD_LIB.TIMECARD(SCH_1):UART_GPS_TX_FPGA_RX':
 C_SIGNAL='@timecard_lib.timecard(sch_1):uart_gps_tx_fpga_rx';
NODE_NAME     R109 1
 '@TIMECARD_LIB.TIMECARD(SCH_1):PAGE11_I11@PASSIVE.RESISTOR(CHIPS)':
 '1': CDS_PINID='\1\';
NODE_NAME     U24 N15
 '@TIMECARD_LIB.TIMECARD(SCH_1):PAGE161_I2@PLD.XC7A200T_2FBG484C_FBG484(CHIPS)':
 'IO_25_14': CDS_PINID='IO_25_14';
NODE_NAME     R269 2
 '@TIMECARD_LIB.TIMECARD(SCH_1):PAGE11_I40@PASSIVE.RESISTOR(CHIPS)':
 '2': CDS_PINID='\2\';
NET_NAME
'UART_MAC_RX_FPGA_TX'
 '@TIMECARD_LIB.TIMECARD(SCH_1):UART_MAC_RX_FPGA_TX':
 C_SIGNAL='@timecard_lib.timecard(sch_1):uart_mac_rx_fpga_tx';
NODE_NAME     U24 AA18
 '@TIMECARD_LIB.TIMECARD(SCH_1):PAGE161_I2@PLD.XC7A200T_2FBG484C_FBG484(CHIPS)':
 'IO_L17P_T2_A14_D30_14': CDS_PINID='IO_L17P_T2_A14_D30_14';
NODE_NAME     R95 2
 '@TIMECARD_LIB.TIMECARD(SCH_1):PAGE527_I52@PASSIVE.RESISTOR(CHIPS)':
 '2': CDS_PINID='\2\';
NET_NAME
'UART_MAC_TX_FPGA_RX'
 '@TIMECARD_LIB.TIMECARD(SCH_1):UART_MAC_TX_FPGA_RX':
 C_SIGNAL='@timecard_lib.timecard(sch_1):uart_mac_tx_fpga_rx';
NODE_NAME     U24 AB18
 '@TIMECARD_LIB.TIMECARD(SCH_1):PAGE161_I2@PLD.XC7A200T_2FBG484C_FBG484(CHIPS)':
 'IO_L17N_T2_A13_D29_14': CDS_PINID='IO_L17N_T2_A13_D29_14';
NODE_NAME     R94 2
 '@TIMECARD_LIB.TIMECARD(SCH_1):PAGE527_I54@PASSIVE.RESISTOR(CHIPS)':
 '2': CDS_PINID='\2\';
NODE_NAME     R265 2
 '@TIMECARD_LIB.TIMECARD(SCH_1):PAGE527_I221@PASSIVE.RESISTOR(CHIPS)':
 '2': CDS_PINID='\2\';
NET_NAME
'UNNAMED_127_G2001028301_I427_4'
 '@TIMECARD_LIB.TIMECARD(SCH_1):UNNAMED_127_G2001028301_I427_4':
 C_SIGNAL='@timecard_lib.timecard(sch_1):unnamed_127_g2001028301_i427_4';
NODE_NAME     J14 4
 '@TIMECARD_LIB.TIMECARD(SCH_1):PAGE127_I427@CONNECTOR.G200_10283_01(CHIPS)':
 '4': CDS_PINID='\4\';
NODE_NAME     R133 2
 '@TIMECARD_LIB.TIMECARD(SCH_1):PAGE127_I446@PASSIVE.RESISTOR(CHIPS)':
 '2': CDS_PINID='\2\';
NET_NAME
'UNNAMED_127_MT25QL128ABA1ESESOP'
 '@TIMECARD_LIB.TIMECARD(SCH_1):UNNAMED_127_MT25QL128ABA1ESESOP8_I456_DQ0':
 C_SIGNAL='@timecard_lib.timecard(sch_1):unnamed_127_mt25ql128aba1esesop8_i456_d~
q0';
NODE_NAME     U23 5
 '@TIMECARD_LIB.TIMECARD(SCH_1):PAGE127_I456@MEMORY.MT25QL128ABA1ESE_SOP8(CHIPS)':
 'DQ0': CDS_PINID='DQ0';
NODE_NAME     R199 1
 '@TIMECARD_LIB.TIMECARD(SCH_1):PAGE127_I462@PASSIVE.RESISTOR(CHIPS)':
 '1': CDS_PINID='\1\';
NODE_NAME     R203 1
 '@TIMECARD_LIB.TIMECARD(SCH_1):PAGE127_I467@PASSIVE.RESISTOR(CHIPS)':
 '1': CDS_PINID='\1\';
NET_NAME
'UNNAMED_127_MT25QL128ABA1ESES_1'
 '@TIMECARD_LIB.TIMECARD(SCH_1):UNNAMED_127_MT25QL128ABA1ESESOP8_I456_DQ1':
 C_SIGNAL='@timecard_lib.timecard(sch_1):unnamed_127_mt25ql128aba1esesop8_i456_d~
q1';
NODE_NAME     U23 2
 '@TIMECARD_LIB.TIMECARD(SCH_1):PAGE127_I456@MEMORY.MT25QL128ABA1ESE_SOP8(CHIPS)':
 'DQ1': CDS_PINID='DQ1';
NODE_NAME     R200 1
 '@TIMECARD_LIB.TIMECARD(SCH_1):PAGE127_I465@PASSIVE.RESISTOR(CHIPS)':
 '1': CDS_PINID='\1\';
NODE_NAME     R204 1
 '@TIMECARD_LIB.TIMECARD(SCH_1):PAGE127_I466@PASSIVE.RESISTOR(CHIPS)':
 '1': CDS_PINID='\1\';
NET_NAME
'UNNAMED_127_MT25QL128ABA1ESES_2'
 '@TIMECARD_LIB.TIMECARD(SCH_1):UNNAMED_127_MT25QL128ABA1ESESOP8_I456_HOLD':
 C_SIGNAL='@timecard_lib.timecard(sch_1):unnamed_127_mt25ql128aba1esesop8_i456_h~
old';
NODE_NAME     U23 7
 '@TIMECARD_LIB.TIMECARD(SCH_1):PAGE127_I456@MEMORY.MT25QL128ABA1ESE_SOP8(CHIPS)':
 'HOLD/DQ3*': CDS_PINID='\hold/dq3*\';
NODE_NAME     R202 1
 '@TIMECARD_LIB.TIMECARD(SCH_1):PAGE127_I464@PASSIVE.RESISTOR(CHIPS)':
 '1': CDS_PINID='\1\';
NODE_NAME     R206 1
 '@TIMECARD_LIB.TIMECARD(SCH_1):PAGE127_I469@PASSIVE.RESISTOR(CHIPS)':
 '1': CDS_PINID='\1\';
NET_NAME
'UNNAMED_127_MT25QL128ABA1ESES_3'
 '@TIMECARD_LIB.TIMECARD(SCH_1):UNNAMED_127_MT25QL128ABA1ESESOP8_I456_W':
 C_SIGNAL='@timecard_lib.timecard(sch_1):unnamed_127_mt25ql128aba1esesop8_i456_w~
';
NODE_NAME     U23 3
 '@TIMECARD_LIB.TIMECARD(SCH_1):PAGE127_I456@MEMORY.MT25QL128ABA1ESE_SOP8(CHIPS)':
 'W/DQ2*': CDS_PINID='\w/dq2*\';
NODE_NAME     R201 1
 '@TIMECARD_LIB.TIMECARD(SCH_1):PAGE127_I463@PASSIVE.RESISTOR(CHIPS)':
 '1': CDS_PINID='\1\';
NODE_NAME     R205 1
 '@TIMECARD_LIB.TIMECARD(SCH_1):PAGE127_I468@PASSIVE.RESISTOR(CHIPS)':
 '1': CDS_PINID='\1\';
NET_NAME
'UNNAMED_12_74HCT2G125DPTSSOP8_3'
 '@TIMECARD_LIB.TIMECARD(SCH_1):UNNAMED_12_74HCT2G125DPTSSOP8_I226_1A':
 C_SIGNAL='@timecard_lib.timecard(sch_1):unnamed_12_74hct2g125dptssop8_i226_1a';
NODE_NAME     U14 2
 '@TIMECARD_LIB.TIMECARD(SCH_1):PAGE12_I226@STDLOGIC.74HCT2G125DP_TSSOP8(CHIPS)':
 '1A': CDS_PINID='\1a\';
NODE_NAME     R157 2
 '@TIMECARD_LIB.TIMECARD(SCH_1):PAGE12_I237@PASSIVE.RESISTOR(CHIPS)':
 '2': CDS_PINID='\2\';
NODE_NAME     R493 2
 '@TIMECARD_LIB.TIMECARD(SCH_1):PAGE12_I323@PASSIVE.RESISTOR(CHIPS)':
 '2': CDS_PINID='\2\';
NET_NAME
'UNNAMED_12_74HCT2G125DPTSSOP8_6'
 '@TIMECARD_LIB.TIMECARD(SCH_1):UNNAMED_12_74HCT2G125DPTSSOP8_I255_1A':
 C_SIGNAL='@timecard_lib.timecard(sch_1):unnamed_12_74hct2g125dptssop8_i255_1a';
NODE_NAME     U15 2
 '@TIMECARD_LIB.TIMECARD(SCH_1):PAGE12_I255@STDLOGIC.74HCT2G125DP_TSSOP8(CHIPS)':
 '1A': CDS_PINID='\1a\';
NODE_NAME     R120 2
 '@TIMECARD_LIB.TIMECARD(SCH_1):PAGE12_I265@PASSIVE.RESISTOR(CHIPS)':
 '2': CDS_PINID='\2\';
NODE_NAME     R494 2
 '@TIMECARD_LIB.TIMECARD(SCH_1):PAGE12_I326@PASSIVE.RESISTOR(CHIPS)':
 '2': CDS_PINID='\2\';
NET_NAME
'UNNAMED_12_74HCT2G125DPTSSOP8_9'
 '@TIMECARD_LIB.TIMECARD(SCH_1):UNNAMED_12_74HCT2G125DPTSSOP8_I273_1A':
 C_SIGNAL='@timecard_lib.timecard(sch_1):unnamed_12_74hct2g125dptssop8_i273_1a';
NODE_NAME     U16 2
 '@TIMECARD_LIB.TIMECARD(SCH_1):PAGE12_I273@STDLOGIC.74HCT2G125DP_TSSOP8(CHIPS)':
 '1A': CDS_PINID='\1a\';
NODE_NAME     R121 2
 '@TIMECARD_LIB.TIMECARD(SCH_1):PAGE12_I284@PASSIVE.RESISTOR(CHIPS)':
 '2': CDS_PINID='\2\';
NODE_NAME     R495 2
 '@TIMECARD_LIB.TIMECARD(SCH_1):PAGE12_I330@PASSIVE.RESISTOR(CHIPS)':
 '2': CDS_PINID='\2\';
NET_NAME
'UNNAMED_12_74HCT2G125DPTSSOP8_I'
 '@TIMECARD_LIB.TIMECARD(SCH_1):UNNAMED_12_74HCT2G125DPTSSOP8_I204_1A':
 C_SIGNAL='@timecard_lib.timecard(sch_1):unnamed_12_74hct2g125dptssop8_i204_1a';
NODE_NAME     R156 2
 '@TIMECARD_LIB.TIMECARD(SCH_1):PAGE12_I63@PASSIVE.RESISTOR(CHIPS)':
 '2': CDS_PINID='\2\';
NODE_NAME     U13 2
 '@TIMECARD_LIB.TIMECARD(SCH_1):PAGE12_I204@STDLOGIC.74HCT2G125DP_TSSOP8(CHIPS)':
 '1A': CDS_PINID='\1a\';
NODE_NAME     R492 2
 '@TIMECARD_LIB.TIMECARD(SCH_1):PAGE12_I319@PASSIVE.RESISTOR(CHIPS)':
 '2': CDS_PINID='\2\';
NET_NAME
'UNNAMED_12_CAPACITOR_I318_2'
 '@TIMECARD_LIB.TIMECARD(SCH_1):UNNAMED_12_CAPACITOR_I318_2':
 C_SIGNAL='@timecard_lib.timecard(sch_1):unnamed_12_capacitor_i318_2';
NODE_NAME     C310 2
 '@TIMECARD_LIB.TIMECARD(SCH_1):PAGE12_I318@PASSIVE.CAPACITOR(CHIPS)':
 '2': CDS_PINID='\2\';
NODE_NAME     R492 1
 '@TIMECARD_LIB.TIMECARD(SCH_1):PAGE12_I319@PASSIVE.RESISTOR(CHIPS)':
 '1': CDS_PINID='\1\';
NET_NAME
'UNNAMED_12_CAPACITOR_I321_2'
 '@TIMECARD_LIB.TIMECARD(SCH_1):UNNAMED_12_CAPACITOR_I321_2':
 C_SIGNAL='@timecard_lib.timecard(sch_1):unnamed_12_capacitor_i321_2';
NODE_NAME     R493 1
 '@TIMECARD_LIB.TIMECARD(SCH_1):PAGE12_I323@PASSIVE.RESISTOR(CHIPS)':
 '1': CDS_PINID='\1\';
NODE_NAME     C311 2
 '@TIMECARD_LIB.TIMECARD(SCH_1):PAGE12_I321@PASSIVE.CAPACITOR(CHIPS)':
 '2': CDS_PINID='\2\';
NET_NAME
'UNNAMED_12_CAPACITOR_I328_2'
 '@TIMECARD_LIB.TIMECARD(SCH_1):UNNAMED_12_CAPACITOR_I328_2':
 C_SIGNAL='@timecard_lib.timecard(sch_1):unnamed_12_capacitor_i328_2';
NODE_NAME     R494 1
 '@TIMECARD_LIB.TIMECARD(SCH_1):PAGE12_I326@PASSIVE.RESISTOR(CHIPS)':
 '1': CDS_PINID='\1\';
NODE_NAME     C317 2
 '@TIMECARD_LIB.TIMECARD(SCH_1):PAGE12_I328@PASSIVE.CAPACITOR(CHIPS)':
 '2': CDS_PINID='\2\';
NET_NAME
'UNNAMED_12_CAPACITOR_I332_2'
 '@TIMECARD_LIB.TIMECARD(SCH_1):UNNAMED_12_CAPACITOR_I332_2':
 C_SIGNAL='@timecard_lib.timecard(sch_1):unnamed_12_capacitor_i332_2';
NODE_NAME     R495 1
 '@TIMECARD_LIB.TIMECARD(SCH_1):PAGE12_I330@PASSIVE.RESISTOR(CHIPS)':
 '1': CDS_PINID='\1\';
NODE_NAME     C318 2
 '@TIMECARD_LIB.TIMECARD(SCH_1):PAGE12_I332@PASSIVE.CAPACITOR(CHIPS)':
 '2': CDS_PINID='\2\';
NET_NAME
'UNNAMED_14_IS32FL3207QWLA3TRQFN'
 '@TIMECARD_LIB.TIMECARD(SCH_1):UNNAMED_14_IS32FL3207QWLA3TRQFN29_I219_AD':
 C_SIGNAL='@timecard_lib.timecard(sch_1):unnamed_14_is32fl3207qwla3trqfn29_i219_~
ad';
NODE_NAME     U33 2
 '@TIMECARD_LIB.TIMECARD(SCH_1):PAGE14_I219@INTERFACE.IS32FL3207_QWLA3_TR_QFN29(CHIPS)':
 'AD': CDS_PINID='AD';
NODE_NAME     R324 2
 '@TIMECARD_LIB.TIMECARD(SCH_1):PAGE14_I247@PASSIVE.RESISTOR(CHIPS)':
 '2': CDS_PINID='\2\';
NET_NAME
'UNNAMED_14_IS32FL3207QWLA3TRQ_1'
 '@TIMECARD_LIB.TIMECARD(SCH_1):UNNAMED_14_IS32FL3207QWLA3TRQFN29_I219_ISET':
 C_SIGNAL='@timecard_lib.timecard(sch_1):unnamed_14_is32fl3207qwla3trqfn29_i219_~
iset';
NODE_NAME     U33 5
 '@TIMECARD_LIB.TIMECARD(SCH_1):PAGE14_I219@INTERFACE.IS32FL3207_QWLA3_TR_QFN29(CHIPS)':
 'ISET': CDS_PINID='ISET';
NODE_NAME     R323 1
 '@TIMECARD_LIB.TIMECARD(SCH_1):PAGE14_I246@PASSIVE.RESISTOR(CHIPS)':
 '1': CDS_PINID='\1\';
NET_NAME
'UNNAMED_14_LED4PV14_I265_1'
 '@TIMECARD_LIB.TIMECARD(SCH_1):UNNAMED_14_LED4PV14_I265_1':
 C_SIGNAL='@timecard_lib.timecard(sch_1):unnamed_14_led4pv14_i265_1';
NODE_NAME     R385 2
 '@TIMECARD_LIB.TIMECARD(SCH_1):PAGE14_I107@PASSIVE.RESISTOR(CHIPS)':
 '2': CDS_PINID='\2\';
NODE_NAME     R124 2
 '@TIMECARD_LIB.TIMECARD(SCH_1):PAGE14_I160@PASSIVE.RESISTOR(CHIPS)':
 '2': CDS_PINID='\2\';
NODE_NAME     DS14 1
 '@TIMECARD_LIB.TIMECARD(SCH_1):PAGE14_I265@DISCRETE.LED_4P_V14(CHIPS)':
 '1': CDS_PINID='\1\';
NET_NAME
'UNNAMED_14_LED4PV14_I265_3'
 '@TIMECARD_LIB.TIMECARD(SCH_1):UNNAMED_14_LED4PV14_I265_3':
 C_SIGNAL='@timecard_lib.timecard(sch_1):unnamed_14_led4pv14_i265_3';
NODE_NAME     R387 2
 '@TIMECARD_LIB.TIMECARD(SCH_1):PAGE14_I110@PASSIVE.RESISTOR(CHIPS)':
 '2': CDS_PINID='\2\';
NODE_NAME     R272 2
 '@TIMECARD_LIB.TIMECARD(SCH_1):PAGE14_I163@PASSIVE.RESISTOR(CHIPS)':
 '2': CDS_PINID='\2\';
NODE_NAME     DS14 3
 '@TIMECARD_LIB.TIMECARD(SCH_1):PAGE14_I265@DISCRETE.LED_4P_V14(CHIPS)':
 '3': CDS_PINID='\3\';
NET_NAME
'UNNAMED_14_LED4PV14_I265_4'
 '@TIMECARD_LIB.TIMECARD(SCH_1):UNNAMED_14_LED4PV14_I265_4':
 C_SIGNAL='@timecard_lib.timecard(sch_1):unnamed_14_led4pv14_i265_4';
NODE_NAME     R386 2
 '@TIMECARD_LIB.TIMECARD(SCH_1):PAGE14_I108@PASSIVE.RESISTOR(CHIPS)':
 '2': CDS_PINID='\2\';
NODE_NAME     R125 2
 '@TIMECARD_LIB.TIMECARD(SCH_1):PAGE14_I161@PASSIVE.RESISTOR(CHIPS)':
 '2': CDS_PINID='\2\';
NODE_NAME     DS14 4
 '@TIMECARD_LIB.TIMECARD(SCH_1):PAGE14_I265@DISCRETE.LED_4P_V14(CHIPS)':
 '4': CDS_PINID='\4\';
NET_NAME
'UNNAMED_14_LED4PV14_I266_1'
 '@TIMECARD_LIB.TIMECARD(SCH_1):UNNAMED_14_LED4PV14_I266_1':
 C_SIGNAL='@timecard_lib.timecard(sch_1):unnamed_14_led4pv14_i266_1';
NODE_NAME     R388 2
 '@TIMECARD_LIB.TIMECARD(SCH_1):PAGE14_I147@PASSIVE.RESISTOR(CHIPS)':
 '2': CDS_PINID='\2\';
NODE_NAME     R273 2
 '@TIMECARD_LIB.TIMECARD(SCH_1):PAGE14_I165@PASSIVE.RESISTOR(CHIPS)':
 '2': CDS_PINID='\2\';
NODE_NAME     DS15 1
 '@TIMECARD_LIB.TIMECARD(SCH_1):PAGE14_I266@DISCRETE.LED_4P_V14(CHIPS)':
 '1': CDS_PINID='\1\';
NET_NAME
'UNNAMED_14_LED4PV14_I266_3'
 '@TIMECARD_LIB.TIMECARD(SCH_1):UNNAMED_14_LED4PV14_I266_3':
 C_SIGNAL='@timecard_lib.timecard(sch_1):unnamed_14_led4pv14_i266_3';
NODE_NAME     R390 2
 '@TIMECARD_LIB.TIMECARD(SCH_1):PAGE14_I146@PASSIVE.RESISTOR(CHIPS)':
 '2': CDS_PINID='\2\';
NODE_NAME     R373 2
 '@TIMECARD_LIB.TIMECARD(SCH_1):PAGE14_I181@PASSIVE.RESISTOR(CHIPS)':
 '2': CDS_PINID='\2\';
NODE_NAME     DS15 3
 '@TIMECARD_LIB.TIMECARD(SCH_1):PAGE14_I266@DISCRETE.LED_4P_V14(CHIPS)':
 '3': CDS_PINID='\3\';
NET_NAME
'UNNAMED_14_LED4PV14_I266_4'
 '@TIMECARD_LIB.TIMECARD(SCH_1):UNNAMED_14_LED4PV14_I266_4':
 C_SIGNAL='@timecard_lib.timecard(sch_1):unnamed_14_led4pv14_i266_4';
NODE_NAME     R389 2
 '@TIMECARD_LIB.TIMECARD(SCH_1):PAGE14_I148@PASSIVE.RESISTOR(CHIPS)':
 '2': CDS_PINID='\2\';
NODE_NAME     R274 2
 '@TIMECARD_LIB.TIMECARD(SCH_1):PAGE14_I171@PASSIVE.RESISTOR(CHIPS)':
 '2': CDS_PINID='\2\';
NODE_NAME     DS15 4
 '@TIMECARD_LIB.TIMECARD(SCH_1):PAGE14_I266@DISCRETE.LED_4P_V14(CHIPS)':
 '4': CDS_PINID='\4\';
NET_NAME
'UNNAMED_14_LED4PV14_I267_1'
 '@TIMECARD_LIB.TIMECARD(SCH_1):UNNAMED_14_LED4PV14_I267_1':
 C_SIGNAL='@timecard_lib.timecard(sch_1):unnamed_14_led4pv14_i267_1';
NODE_NAME     R391 2
 '@TIMECARD_LIB.TIMECARD(SCH_1):PAGE14_I150@PASSIVE.RESISTOR(CHIPS)':
 '2': CDS_PINID='\2\';
NODE_NAME     R374 2
 '@TIMECARD_LIB.TIMECARD(SCH_1):PAGE14_I168@PASSIVE.RESISTOR(CHIPS)':
 '2': CDS_PINID='\2\';
NODE_NAME     DS16 1
 '@TIMECARD_LIB.TIMECARD(SCH_1):PAGE14_I267@DISCRETE.LED_4P_V14(CHIPS)':
 '1': CDS_PINID='\1\';
NET_NAME
'UNNAMED_14_LED4PV14_I267_3'
 '@TIMECARD_LIB.TIMECARD(SCH_1):UNNAMED_14_LED4PV14_I267_3':
 C_SIGNAL='@timecard_lib.timecard(sch_1):unnamed_14_led4pv14_i267_3';
NODE_NAME     R393 2
 '@TIMECARD_LIB.TIMECARD(SCH_1):PAGE14_I151@PASSIVE.RESISTOR(CHIPS)':
 '2': CDS_PINID='\2\';
NODE_NAME     R376 2
 '@TIMECARD_LIB.TIMECARD(SCH_1):PAGE14_I184@PASSIVE.RESISTOR(CHIPS)':
 '2': CDS_PINID='\2\';
NODE_NAME     DS16 3
 '@TIMECARD_LIB.TIMECARD(SCH_1):PAGE14_I267@DISCRETE.LED_4P_V14(CHIPS)':
 '3': CDS_PINID='\3\';
NET_NAME
'UNNAMED_14_LED4PV14_I267_4'
 '@TIMECARD_LIB.TIMECARD(SCH_1):UNNAMED_14_LED4PV14_I267_4':
 C_SIGNAL='@timecard_lib.timecard(sch_1):unnamed_14_led4pv14_i267_4';
NODE_NAME     R392 2
 '@TIMECARD_LIB.TIMECARD(SCH_1):PAGE14_I149@PASSIVE.RESISTOR(CHIPS)':
 '2': CDS_PINID='\2\';
NODE_NAME     R375 2
 '@TIMECARD_LIB.TIMECARD(SCH_1):PAGE14_I174@PASSIVE.RESISTOR(CHIPS)':
 '2': CDS_PINID='\2\';
NODE_NAME     DS16 4
 '@TIMECARD_LIB.TIMECARD(SCH_1):PAGE14_I267@DISCRETE.LED_4P_V14(CHIPS)':
 '4': CDS_PINID='\4\';
NET_NAME
'UNNAMED_14_LED4PV14_I268_1'
 '@TIMECARD_LIB.TIMECARD(SCH_1):UNNAMED_14_LED4PV14_I268_1':
 C_SIGNAL='@timecard_lib.timecard(sch_1):unnamed_14_led4pv14_i268_1';
NODE_NAME     R394 2
 '@TIMECARD_LIB.TIMECARD(SCH_1):PAGE14_I153@PASSIVE.RESISTOR(CHIPS)':
 '2': CDS_PINID='\2\';
NODE_NAME     R400 2
 '@TIMECARD_LIB.TIMECARD(SCH_1):PAGE14_I177@PASSIVE.RESISTOR(CHIPS)':
 '2': CDS_PINID='\2\';
NODE_NAME     DS17 1
 '@TIMECARD_LIB.TIMECARD(SCH_1):PAGE14_I268@DISCRETE.LED_4P_V14(CHIPS)':
 '1': CDS_PINID='\1\';
NET_NAME
'UNNAMED_14_LED4PV14_I268_3'
 '@TIMECARD_LIB.TIMECARD(SCH_1):UNNAMED_14_LED4PV14_I268_3':
 C_SIGNAL='@timecard_lib.timecard(sch_1):unnamed_14_led4pv14_i268_3';
NODE_NAME     R396 2
 '@TIMECARD_LIB.TIMECARD(SCH_1):PAGE14_I154@PASSIVE.RESISTOR(CHIPS)':
 '2': CDS_PINID='\2\';
NODE_NAME     R424 2
 '@TIMECARD_LIB.TIMECARD(SCH_1):PAGE14_I186@PASSIVE.RESISTOR(CHIPS)':
 '2': CDS_PINID='\2\';
NODE_NAME     DS17 3
 '@TIMECARD_LIB.TIMECARD(SCH_1):PAGE14_I268@DISCRETE.LED_4P_V14(CHIPS)':
 '3': CDS_PINID='\3\';
NET_NAME
'UNNAMED_14_LED4PV14_I268_4'
 '@TIMECARD_LIB.TIMECARD(SCH_1):UNNAMED_14_LED4PV14_I268_4':
 C_SIGNAL='@timecard_lib.timecard(sch_1):unnamed_14_led4pv14_i268_4';
NODE_NAME     R395 2
 '@TIMECARD_LIB.TIMECARD(SCH_1):PAGE14_I152@PASSIVE.RESISTOR(CHIPS)':
 '2': CDS_PINID='\2\';
NODE_NAME     R401 2
 '@TIMECARD_LIB.TIMECARD(SCH_1):PAGE14_I176@PASSIVE.RESISTOR(CHIPS)':
 '2': CDS_PINID='\2\';
NODE_NAME     DS17 4
 '@TIMECARD_LIB.TIMECARD(SCH_1):PAGE14_I268@DISCRETE.LED_4P_V14(CHIPS)':
 '4': CDS_PINID='\4\';
NET_NAME
'UNNAMED_14_LED4PV14_I269_1'
 '@TIMECARD_LIB.TIMECARD(SCH_1):UNNAMED_14_LED4PV14_I269_1':
 C_SIGNAL='@timecard_lib.timecard(sch_1):unnamed_14_led4pv14_i269_1';
NODE_NAME     R397 2
 '@TIMECARD_LIB.TIMECARD(SCH_1):PAGE14_I156@PASSIVE.RESISTOR(CHIPS)':
 '2': CDS_PINID='\2\';
NODE_NAME     R425 2
 '@TIMECARD_LIB.TIMECARD(SCH_1):PAGE14_I170@PASSIVE.RESISTOR(CHIPS)':
 '2': CDS_PINID='\2\';
NODE_NAME     DS18 1
 '@TIMECARD_LIB.TIMECARD(SCH_1):PAGE14_I269@DISCRETE.LED_4P_V14(CHIPS)':
 '1': CDS_PINID='\1\';
NET_NAME
'UNNAMED_14_LED4PV14_I269_3'
 '@TIMECARD_LIB.TIMECARD(SCH_1):UNNAMED_14_LED4PV14_I269_3':
 C_SIGNAL='@timecard_lib.timecard(sch_1):unnamed_14_led4pv14_i269_3';
NODE_NAME     R399 2
 '@TIMECARD_LIB.TIMECARD(SCH_1):PAGE14_I157@PASSIVE.RESISTOR(CHIPS)':
 '2': CDS_PINID='\2\';
NODE_NAME     R427 2
 '@TIMECARD_LIB.TIMECARD(SCH_1):PAGE14_I188@PASSIVE.RESISTOR(CHIPS)':
 '2': CDS_PINID='\2\';
NODE_NAME     DS18 3
 '@TIMECARD_LIB.TIMECARD(SCH_1):PAGE14_I269@DISCRETE.LED_4P_V14(CHIPS)':
 '3': CDS_PINID='\3\';
NET_NAME
'UNNAMED_14_LED4PV14_I269_4'
 '@TIMECARD_LIB.TIMECARD(SCH_1):UNNAMED_14_LED4PV14_I269_4':
 C_SIGNAL='@timecard_lib.timecard(sch_1):unnamed_14_led4pv14_i269_4';
NODE_NAME     R398 2
 '@TIMECARD_LIB.TIMECARD(SCH_1):PAGE14_I155@PASSIVE.RESISTOR(CHIPS)':
 '2': CDS_PINID='\2\';
NODE_NAME     R426 2
 '@TIMECARD_LIB.TIMECARD(SCH_1):PAGE14_I179@PASSIVE.RESISTOR(CHIPS)':
 '2': CDS_PINID='\2\';
NODE_NAME     DS18 4
 '@TIMECARD_LIB.TIMECARD(SCH_1):PAGE14_I269@DISCRETE.LED_4P_V14(CHIPS)':
 '4': CDS_PINID='\4\';
NET_NAME
'UNNAMED_14_OPTICAL_I11_A'
 '@TIMECARD_LIB.TIMECARD(SCH_1):UNNAMED_14_OPTICAL_I11_A':
 C_SIGNAL='@timecard_lib.timecard(sch_1):unnamed_14_optical_i11_a';
NODE_NAME     DS2 A
 '@TIMECARD_LIB.TIMECARD(SCH_1):PAGE14_I11@DISCRETE.OPTICAL(CHIPS)':
 'A': CDS_PINID='A';
NODE_NAME     R258 1
 '@TIMECARD_LIB.TIMECARD(SCH_1):PAGE14_I68@PASSIVE.RESISTOR(CHIPS)':
 '1': CDS_PINID='\1\';
NET_NAME
'UNNAMED_14_OPTICAL_I12_A'
 '@TIMECARD_LIB.TIMECARD(SCH_1):UNNAMED_14_OPTICAL_I12_A':
 C_SIGNAL='@timecard_lib.timecard(sch_1):unnamed_14_optical_i12_a';
NODE_NAME     DS1 A
 '@TIMECARD_LIB.TIMECARD(SCH_1):PAGE14_I12@DISCRETE.OPTICAL(CHIPS)':
 'A': CDS_PINID='A';
NODE_NAME     R257 1
 '@TIMECARD_LIB.TIMECARD(SCH_1):PAGE14_I67@PASSIVE.RESISTOR(CHIPS)':
 '1': CDS_PINID='\1\';
NET_NAME
'UNNAMED_14_OPTICAL_I136_A'
 '@TIMECARD_LIB.TIMECARD(SCH_1):UNNAMED_14_OPTICAL_I136_A':
 C_SIGNAL='@timecard_lib.timecard(sch_1):unnamed_14_optical_i136_a';
NODE_NAME     R259 1
 '@TIMECARD_LIB.TIMECARD(SCH_1):PAGE14_I69@PASSIVE.RESISTOR(CHIPS)':
 '1': CDS_PINID='\1\';
NODE_NAME     DS3 A
 '@TIMECARD_LIB.TIMECARD(SCH_1):PAGE14_I136@DISCRETE.OPTICAL(CHIPS)':
 'A': CDS_PINID='A';
NET_NAME
'UNNAMED_14_OPTICAL_I137_A'
 '@TIMECARD_LIB.TIMECARD(SCH_1):UNNAMED_14_OPTICAL_I137_A':
 C_SIGNAL='@timecard_lib.timecard(sch_1):unnamed_14_optical_i137_a';
NODE_NAME     R261 1
 '@TIMECARD_LIB.TIMECARD(SCH_1):PAGE14_I70@PASSIVE.RESISTOR(CHIPS)':
 '1': CDS_PINID='\1\';
NODE_NAME     DS4 A
 '@TIMECARD_LIB.TIMECARD(SCH_1):PAGE14_I137@DISCRETE.OPTICAL(CHIPS)':
 'A': CDS_PINID='A';
NET_NAME
'UNNAMED_14_OPTICAL_I138_A'
 '@TIMECARD_LIB.TIMECARD(SCH_1):UNNAMED_14_OPTICAL_I138_A':
 C_SIGNAL='@timecard_lib.timecard(sch_1):unnamed_14_optical_i138_a';
NODE_NAME     R279 1
 '@TIMECARD_LIB.TIMECARD(SCH_1):PAGE14_I72@PASSIVE.RESISTOR(CHIPS)':
 '1': CDS_PINID='\1\';
NODE_NAME     DS10 A
 '@TIMECARD_LIB.TIMECARD(SCH_1):PAGE14_I138@DISCRETE.OPTICAL(CHIPS)':
 'A': CDS_PINID='A';
NET_NAME
'UNNAMED_14_OPTICAL_I139_A'
 '@TIMECARD_LIB.TIMECARD(SCH_1):UNNAMED_14_OPTICAL_I139_A':
 C_SIGNAL='@timecard_lib.timecard(sch_1):unnamed_14_optical_i139_a';
NODE_NAME     R280 1
 '@TIMECARD_LIB.TIMECARD(SCH_1):PAGE14_I74@PASSIVE.RESISTOR(CHIPS)':
 '1': CDS_PINID='\1\';
NODE_NAME     DS11 A
 '@TIMECARD_LIB.TIMECARD(SCH_1):PAGE14_I139@DISCRETE.OPTICAL(CHIPS)':
 'A': CDS_PINID='A';
NET_NAME
'UNNAMED_14_OPTICAL_I140_A'
 '@TIMECARD_LIB.TIMECARD(SCH_1):UNNAMED_14_OPTICAL_I140_A':
 C_SIGNAL='@timecard_lib.timecard(sch_1):unnamed_14_optical_i140_a';
NODE_NAME     R138 1
 '@TIMECARD_LIB.TIMECARD(SCH_1):PAGE14_I63@PASSIVE.RESISTOR(CHIPS)':
 '1': CDS_PINID='\1\';
NODE_NAME     DS6 A
 '@TIMECARD_LIB.TIMECARD(SCH_1):PAGE14_I140@DISCRETE.OPTICAL(CHIPS)':
 'A': CDS_PINID='A';
NET_NAME
'UNNAMED_14_OPTICAL_I141_A'
 '@TIMECARD_LIB.TIMECARD(SCH_1):UNNAMED_14_OPTICAL_I141_A':
 C_SIGNAL='@timecard_lib.timecard(sch_1):unnamed_14_optical_i141_a';
NODE_NAME     R108 1
 '@TIMECARD_LIB.TIMECARD(SCH_1):PAGE14_I58@PASSIVE.RESISTOR(CHIPS)':
 '1': CDS_PINID='\1\';
NODE_NAME     DS7 A
 '@TIMECARD_LIB.TIMECARD(SCH_1):PAGE14_I141@DISCRETE.OPTICAL(CHIPS)':
 'A': CDS_PINID='A';
NET_NAME
'UNNAMED_14_OPTICAL_I142_A'
 '@TIMECARD_LIB.TIMECARD(SCH_1):UNNAMED_14_OPTICAL_I142_A':
 C_SIGNAL='@timecard_lib.timecard(sch_1):unnamed_14_optical_i142_a';
NODE_NAME     R180 1
 '@TIMECARD_LIB.TIMECARD(SCH_1):PAGE14_I44@PASSIVE.RESISTOR(CHIPS)':
 '1': CDS_PINID='\1\';
NODE_NAME     DS8 A
 '@TIMECARD_LIB.TIMECARD(SCH_1):PAGE14_I142@DISCRETE.OPTICAL(CHIPS)':
 'A': CDS_PINID='A';
NET_NAME
'UNNAMED_14_OPTICAL_I143_A'
 '@TIMECARD_LIB.TIMECARD(SCH_1):UNNAMED_14_OPTICAL_I143_A':
 C_SIGNAL='@timecard_lib.timecard(sch_1):unnamed_14_optical_i143_a';
NODE_NAME     R256 1
 '@TIMECARD_LIB.TIMECARD(SCH_1):PAGE14_I65@PASSIVE.RESISTOR(CHIPS)':
 '1': CDS_PINID='\1\';
NODE_NAME     DS5 A
 '@TIMECARD_LIB.TIMECARD(SCH_1):PAGE14_I143@DISCRETE.OPTICAL(CHIPS)':
 'A': CDS_PINID='A';
NET_NAME
'UNNAMED_14_OPTICAL_I191_A'
 '@TIMECARD_LIB.TIMECARD(SCH_1):UNNAMED_14_OPTICAL_I191_A':
 C_SIGNAL='@timecard_lib.timecard(sch_1):unnamed_14_optical_i191_a';
NODE_NAME     R118 1
 '@TIMECARD_LIB.TIMECARD(SCH_1):PAGE14_I190@PASSIVE.RESISTOR(CHIPS)':
 '1': CDS_PINID='\1\';
NODE_NAME     DS19 A
 '@TIMECARD_LIB.TIMECARD(SCH_1):PAGE14_I191@DISCRETE.OPTICAL(CHIPS)':
 'A': CDS_PINID='A';
NET_NAME
'UNNAMED_14_OPTICAL_I194_A'
 '@TIMECARD_LIB.TIMECARD(SCH_1):UNNAMED_14_OPTICAL_I194_A':
 C_SIGNAL='@timecard_lib.timecard(sch_1):unnamed_14_optical_i194_a';
NODE_NAME     R119 1
 '@TIMECARD_LIB.TIMECARD(SCH_1):PAGE14_I192@PASSIVE.RESISTOR(CHIPS)':
 '1': CDS_PINID='\1\';
NODE_NAME     DS20 A
 '@TIMECARD_LIB.TIMECARD(SCH_1):PAGE14_I194@DISCRETE.OPTICAL(CHIPS)':
 'A': CDS_PINID='A';
NET_NAME
'UNNAMED_14_OPTICAL_I289_A'
 '@TIMECARD_LIB.TIMECARD(SCH_1):UNNAMED_14_OPTICAL_I289_A':
 C_SIGNAL='@timecard_lib.timecard(sch_1):unnamed_14_optical_i289_a';
NODE_NAME     R169 1
 '@TIMECARD_LIB.TIMECARD(SCH_1):PAGE14_I288@PASSIVE.RESISTOR(CHIPS)':
 '1': CDS_PINID='\1\';
NODE_NAME     DS12 A
 '@TIMECARD_LIB.TIMECARD(SCH_1):PAGE14_I289@DISCRETE.OPTICAL(CHIPS)':
 'A': CDS_PINID='A';
NET_NAME
'UNNAMED_14_OPTICAL_I292_A'
 '@TIMECARD_LIB.TIMECARD(SCH_1):UNNAMED_14_OPTICAL_I292_A':
 C_SIGNAL='@timecard_lib.timecard(sch_1):unnamed_14_optical_i292_a';
NODE_NAME     DS9 A
 '@TIMECARD_LIB.TIMECARD(SCH_1):PAGE14_I292@DISCRETE.OPTICAL(CHIPS)':
 'A': CDS_PINID='A';
NODE_NAME     R208 1
 '@TIMECARD_LIB.TIMECARD(SCH_1):PAGE14_I293@PASSIVE.RESISTOR(CHIPS)':
 '1': CDS_PINID='\1\';
NET_NAME
'UNNAMED_14_RESISTOR_I58_2'
 '@TIMECARD_LIB.TIMECARD(SCH_1):UNNAMED_14_RESISTOR_I58_2':
 C_SIGNAL='@timecard_lib.timecard(sch_1):unnamed_14_resistor_i58_2';
NODE_NAME     R108 2
 '@TIMECARD_LIB.TIMECARD(SCH_1):PAGE14_I58@PASSIVE.RESISTOR(CHIPS)':
 '2': CDS_PINID='\2\';
NODE_NAME     R139 1
 '@TIMECARD_LIB.TIMECARD(SCH_1):PAGE14_I60@PASSIVE.RESISTOR(CHIPS)':
 '1': CDS_PINID='\1\';
NET_NAME
'UNNAMED_14_RESISTOR_I65_2'
 '@TIMECARD_LIB.TIMECARD(SCH_1):UNNAMED_14_RESISTOR_I65_2':
 C_SIGNAL='@timecard_lib.timecard(sch_1):unnamed_14_resistor_i65_2';
NODE_NAME     R256 2
 '@TIMECARD_LIB.TIMECARD(SCH_1):PAGE14_I65@PASSIVE.RESISTOR(CHIPS)':
 '2': CDS_PINID='\2\';
NODE_NAME     R262 1
 '@TIMECARD_LIB.TIMECARD(SCH_1):PAGE14_I66@PASSIVE.RESISTOR(CHIPS)':
 '1': CDS_PINID='\1\';
NET_NAME
'UNNAMED_15_MP5022CGQVZQFN22_I21'
 '@TIMECARD_LIB.TIMECARD(SCH_1):UNNAMED_15_MP5022CGQVZQFN22_I212_ENTM':
 C_SIGNAL='@timecard_lib.timecard(sch_1):unnamed_15_mp5022cgqvzqfn22_i212_entm';
NODE_NAME     R8 2
 '@TIMECARD_LIB.TIMECARD(SCH_1):PAGE15_I173@PASSIVE.RESISTOR(CHIPS)':
 '2': CDS_PINID='\2\';
NODE_NAME     U1 3
 '@TIMECARD_LIB.TIMECARD(SCH_1):PAGE15_I212@STDLOGIC.MP5022CGQV_Z_QFN22(CHIPS)':
 'ENTM': CDS_PINID='ENTM';
NET_NAME
'UNNAMED_15_MP5022CGQVZQFN22_I_2'
 '@TIMECARD_LIB.TIMECARD(SCH_1):UNNAMED_15_MP5022CGQVZQFN22_I212_LOADEN':
 C_SIGNAL='@timecard_lib.timecard(sch_1):unnamed_15_mp5022cgqvzqfn22_i212_loaden~
';
NODE_NAME     R7 2
 '@TIMECARD_LIB.TIMECARD(SCH_1):PAGE15_I174@PASSIVE.RESISTOR(CHIPS)':
 '2': CDS_PINID='\2\';
NODE_NAME     U1 2
 '@TIMECARD_LIB.TIMECARD(SCH_1):PAGE15_I212@STDLOGIC.MP5022CGQV_Z_QFN22(CHIPS)':
 'LOADEN': CDS_PINID='LOADEN';
NET_NAME
'UNNAMED_16_CONNHDR2X6FSSMT_I161'
 '@TIMECARD_LIB.TIMECARD(SCH_1):UNNAMED_16_CONNHDR2X6FSSMT_I1614_1':
 C_SIGNAL='@timecard_lib.timecard(sch_1):unnamed_16_connhdr2x6fssmt_i1614_1';
NODE_NAME     J5 1
 '@TIMECARD_LIB.TIMECARD(SCH_1):PAGE16_I1614@CONNECTOR.CONN_HDR_2X6_F_S_SMT(CHIPS)':
 '1': CDS_PINID='\1\';
NODE_NAME     R430 2
 '@TIMECARD_LIB.TIMECARD(SCH_1):PAGE16_I1706@PASSIVE.RESISTOR(CHIPS)':
 '2': CDS_PINID='\2\';
NET_NAME
'UNNAMED_16_CONNHDR2X6FSSMT_I1_1'
 '@TIMECARD_LIB.TIMECARD(SCH_1):UNNAMED_16_CONNHDR2X6FSSMT_I1614_2':
 C_SIGNAL='@timecard_lib.timecard(sch_1):unnamed_16_connhdr2x6fssmt_i1614_2';
NODE_NAME     J5 2
 '@TIMECARD_LIB.TIMECARD(SCH_1):PAGE16_I1614@CONNECTOR.CONN_HDR_2X6_F_S_SMT(CHIPS)':
 '2': CDS_PINID='\2\';
NODE_NAME     R434 1
 '@TIMECARD_LIB.TIMECARD(SCH_1):PAGE16_I1721@PASSIVE.RESISTOR(CHIPS)':
 '1': CDS_PINID='\1\';
NET_NAME
'UNNAMED_16_CONNHDR2X6FSSMT_I1_2'
 '@TIMECARD_LIB.TIMECARD(SCH_1):UNNAMED_16_CONNHDR2X6FSSMT_I1614_3':
 C_SIGNAL='@timecard_lib.timecard(sch_1):unnamed_16_connhdr2x6fssmt_i1614_3';
NODE_NAME     J5 3
 '@TIMECARD_LIB.TIMECARD(SCH_1):PAGE16_I1614@CONNECTOR.CONN_HDR_2X6_F_S_SMT(CHIPS)':
 '3': CDS_PINID='\3\';
NODE_NAME     R429 2
 '@TIMECARD_LIB.TIMECARD(SCH_1):PAGE16_I1709@PASSIVE.RESISTOR(CHIPS)':
 '2': CDS_PINID='\2\';
NET_NAME
'UNNAMED_16_CONNHDR2X6FSSMT_I1_3'
 '@TIMECARD_LIB.TIMECARD(SCH_1):UNNAMED_16_CONNHDR2X6FSSMT_I1614_4':
 C_SIGNAL='@timecard_lib.timecard(sch_1):unnamed_16_connhdr2x6fssmt_i1614_4';
NODE_NAME     J5 4
 '@TIMECARD_LIB.TIMECARD(SCH_1):PAGE16_I1614@CONNECTOR.CONN_HDR_2X6_F_S_SMT(CHIPS)':
 '4': CDS_PINID='\4\';
NODE_NAME     R433 1
 '@TIMECARD_LIB.TIMECARD(SCH_1):PAGE16_I1720@PASSIVE.RESISTOR(CHIPS)':
 '1': CDS_PINID='\1\';
NET_NAME
'UNNAMED_16_CONNHDR2X6FSSMT_I1_4'
 '@TIMECARD_LIB.TIMECARD(SCH_1):UNNAMED_16_CONNHDR2X6FSSMT_I1614_7':
 C_SIGNAL='@timecard_lib.timecard(sch_1):unnamed_16_connhdr2x6fssmt_i1614_7';
NODE_NAME     J5 7
 '@TIMECARD_LIB.TIMECARD(SCH_1):PAGE16_I1614@CONNECTOR.CONN_HDR_2X6_F_S_SMT(CHIPS)':
 '7': CDS_PINID='\7\';
NODE_NAME     R329 2
 '@TIMECARD_LIB.TIMECARD(SCH_1):PAGE16_I1707@PASSIVE.RESISTOR(CHIPS)':
 '2': CDS_PINID='\2\';
NET_NAME
'UNNAMED_16_CONNHDR2X6FSSMT_I1_5'
 '@TIMECARD_LIB.TIMECARD(SCH_1):UNNAMED_16_CONNHDR2X6FSSMT_I1614_8':
 C_SIGNAL='@timecard_lib.timecard(sch_1):unnamed_16_connhdr2x6fssmt_i1614_8';
NODE_NAME     J5 8
 '@TIMECARD_LIB.TIMECARD(SCH_1):PAGE16_I1614@CONNECTOR.CONN_HDR_2X6_F_S_SMT(CHIPS)':
 '8': CDS_PINID='\8\';
NODE_NAME     R431 1
 '@TIMECARD_LIB.TIMECARD(SCH_1):PAGE16_I1718@PASSIVE.RESISTOR(CHIPS)':
 '1': CDS_PINID='\1\';
NET_NAME
'UNNAMED_16_CONNHDR2X6FSSMT_I1_6'
 '@TIMECARD_LIB.TIMECARD(SCH_1):UNNAMED_16_CONNHDR2X6FSSMT_I1614_5':
 C_SIGNAL='@timecard_lib.timecard(sch_1):unnamed_16_connhdr2x6fssmt_i1614_5';
NODE_NAME     J5 5
 '@TIMECARD_LIB.TIMECARD(SCH_1):PAGE16_I1614@CONNECTOR.CONN_HDR_2X6_F_S_SMT(CHIPS)':
 '5': CDS_PINID='\5\';
NODE_NAME     R428 2
 '@TIMECARD_LIB.TIMECARD(SCH_1):PAGE16_I1708@PASSIVE.RESISTOR(CHIPS)':
 '2': CDS_PINID='\2\';
NET_NAME
'UNNAMED_16_CONNHDR2X6FSSMT_I1_7'
 '@TIMECARD_LIB.TIMECARD(SCH_1):UNNAMED_16_CONNHDR2X6FSSMT_I1614_6':
 C_SIGNAL='@timecard_lib.timecard(sch_1):unnamed_16_connhdr2x6fssmt_i1614_6';
NODE_NAME     J5 6
 '@TIMECARD_LIB.TIMECARD(SCH_1):PAGE16_I1614@CONNECTOR.CONN_HDR_2X6_F_S_SMT(CHIPS)':
 '6': CDS_PINID='\6\';
NODE_NAME     R432 1
 '@TIMECARD_LIB.TIMECARD(SCH_1):PAGE16_I1719@PASSIVE.RESISTOR(CHIPS)':
 '1': CDS_PINID='\1\';
NET_NAME
'UNNAMED_3_CONN64PGF_I61_PRSNT21'
 '@TIMECARD_LIB.TIMECARD(SCH_1):UNNAMED_3_CONN64PGF_I61_PRSNT21':
 C_SIGNAL='@timecard_lib.timecard(sch_1):unnamed_3_conn64pgf_i61_prsnt21';
NODE_NAME     R22 2
 '@TIMECARD_LIB.TIMECARD(SCH_1):PAGE3_I16@PASSIVE.RESISTOR(CHIPS)':
 '2': CDS_PINID='\2\';
NODE_NAME     GF1 B17
 '@TIMECARD_LIB.TIMECARD(SCH_1):PAGE3_I61@CONNECTOR.CONN_64P_GF(CHIPS)':
 'PRSNT2_1*': CDS_PINID='\prsnt2_1*\';
NET_NAME
'UNNAMED_3_CONN64PGF_I61_PRSNT22'
 '@TIMECARD_LIB.TIMECARD(SCH_1):UNNAMED_3_CONN64PGF_I61_PRSNT22':
 C_SIGNAL='@timecard_lib.timecard(sch_1):unnamed_3_conn64pgf_i61_prsnt22';
NODE_NAME     R23 2
 '@TIMECARD_LIB.TIMECARD(SCH_1):PAGE3_I15@PASSIVE.RESISTOR(CHIPS)':
 '2': CDS_PINID='\2\';
NODE_NAME     GF1 B31
 '@TIMECARD_LIB.TIMECARD(SCH_1):PAGE3_I61@CONNECTOR.CONN_64P_GF(CHIPS)':
 'PRSNT2_2*': CDS_PINID='\prsnt2_2*\';
NET_NAME
'UNNAMED_3_G2201019801_I100_EN'
 '@TIMECARD_LIB.TIMECARD(SCH_1):UNNAMED_3_G2201019801_I100_EN':
 C_SIGNAL='@timecard_lib.timecard(sch_1):unnamed_3_g2201019801_i100_en';
NODE_NAME     U2 1
 '@TIMECARD_LIB.TIMECARD(SCH_1):PAGE3_I100@STDLOGIC.G220_10198_01(CHIPS)':
 'EN': CDS_PINID='EN';
NODE_NAME     R25 2
 '@TIMECARD_LIB.TIMECARD(SCH_1):PAGE3_I103@PASSIVE.RESISTOR(CHIPS)':
 '2': CDS_PINID='\2\';
NODE_NAME     R354 2
 '@TIMECARD_LIB.TIMECARD(SCH_1):PAGE3_I114@PASSIVE.RESISTOR(CHIPS)':
 '2': CDS_PINID='\2\';
NET_NAME
'UNNAMED_3_RESISTOR_I151_2'
 '@TIMECARD_LIB.TIMECARD(SCH_1):UNNAMED_3_RESISTOR_I151_2':
 C_SIGNAL='@timecard_lib.timecard(sch_1):unnamed_3_resistor_i151_2';
NODE_NAME     U34 4
 '@TIMECARD_LIB.TIMECARD(SCH_1):PAGE3_I139@ANALOG.TPS3808G18DBVR_SOT23_6(CHIPS)':
 'CT': CDS_PINID='CT';
NODE_NAME     R164 2
 '@TIMECARD_LIB.TIMECARD(SCH_1):PAGE3_I151@PASSIVE.RESISTOR(CHIPS)':
 '2': CDS_PINID='\2\';
NODE_NAME     C250 1
 '@TIMECARD_LIB.TIMECARD(SCH_1):PAGE3_I152@PASSIVE.CAPACITOR(CHIPS)':
 '1': CDS_PINID='\1\';
NET_NAME
'UNNAMED_515_CAPACITOR_I128_1'
 '@TIMECARD_LIB.TIMECARD(SCH_1):UNNAMED_515_CAPACITOR_I128_1':
 C_SIGNAL='@timecard_lib.timecard(sch_1):unnamed_515_capacitor_i128_1';
NODE_NAME     R227 1
 '@TIMECARD_LIB.TIMECARD(SCH_1):PAGE515_I127@PASSIVE.RESISTOR(CHIPS)':
 '1': CDS_PINID='\1\';
NODE_NAME     C227 1
 '@TIMECARD_LIB.TIMECARD(SCH_1):PAGE515_I128@PASSIVE.CAPACITOR(CHIPS)':
 '1': CDS_PINID='\1\';
NODE_NAME     R228 2
 '@TIMECARD_LIB.TIMECARD(SCH_1):PAGE515_I129@PASSIVE.RESISTOR(CHIPS)':
 '2': CDS_PINID='\2\';
NODE_NAME     U25 7
 '@TIMECARD_LIB.TIMECARD(SCH_1):PAGE515_I151@ANALOG.ISL80101IRAJZ_DFN10(CHIPS)':
 'ENABLE': CDS_PINID='ENABLE';
NODE_NAME     R225 2
 '@TIMECARD_LIB.TIMECARD(SCH_1):PAGE515_I152@PASSIVE.RESISTOR(CHIPS)':
 '2': CDS_PINID='\2\';
NODE_NAME     C293 1
 '@TIMECARD_LIB.TIMECARD(SCH_1):PAGE515_I168@PASSIVE.CAPACITOR(CHIPS)':
 '1': CDS_PINID='\1\';
NET_NAME
'UNNAMED_515_CAPACITOR_I130_1'
 '@TIMECARD_LIB.TIMECARD(SCH_1):UNNAMED_515_CAPACITOR_I130_1':
 C_SIGNAL='@timecard_lib.timecard(sch_1):unnamed_515_capacitor_i130_1';
NODE_NAME     R228 1
 '@TIMECARD_LIB.TIMECARD(SCH_1):PAGE515_I129@PASSIVE.RESISTOR(CHIPS)':
 '1': CDS_PINID='\1\';
NODE_NAME     C228 1
 '@TIMECARD_LIB.TIMECARD(SCH_1):PAGE515_I130@PASSIVE.CAPACITOR(CHIPS)':
 '1': CDS_PINID='\1\';
NODE_NAME     C230 1
 '@TIMECARD_LIB.TIMECARD(SCH_1):PAGE515_I134@PASSIVE.CAPACITOR(CHIPS)':
 '1': CDS_PINID='\1\';
NODE_NAME     L13 2
 '@TIMECARD_LIB.TIMECARD(SCH_1):PAGE515_I135@PASSIVE.FERRITEBEAD(CHIPS)':
 '2': CDS_PINID='\2\';
NODE_NAME     U25 9
 '@TIMECARD_LIB.TIMECARD(SCH_1):PAGE515_I151@ANALOG.ISL80101IRAJZ_DFN10(CHIPS)':
 'VIN_1': CDS_PINID='VIN_1';
NODE_NAME     U25 10
 '@TIMECARD_LIB.TIMECARD(SCH_1):PAGE515_I151@ANALOG.ISL80101IRAJZ_DFN10(CHIPS)':
 'VIN_2': CDS_PINID='VIN_2';
NET_NAME
'UNNAMED_515_CAPACITOR_I132_1'
 '@TIMECARD_LIB.TIMECARD(SCH_1):UNNAMED_515_CAPACITOR_I132_1':
 C_SIGNAL='@timecard_lib.timecard(sch_1):unnamed_515_capacitor_i132_1';
NODE_NAME     C231 1
 '@TIMECARD_LIB.TIMECARD(SCH_1):PAGE515_I132@PASSIVE.CAPACITOR(CHIPS)':
 '1': CDS_PINID='\1\';
NODE_NAME     U25 6
 '@TIMECARD_LIB.TIMECARD(SCH_1):PAGE515_I151@ANALOG.ISL80101IRAJZ_DFN10(CHIPS)':
 'SS': CDS_PINID='SS';
NET_NAME
'UNNAMED_515_CAPACITOR_I138_1'
 '@TIMECARD_LIB.TIMECARD(SCH_1):UNNAMED_515_CAPACITOR_I138_1':
 C_SIGNAL='@timecard_lib.timecard(sch_1):unnamed_515_capacitor_i138_1';
NODE_NAME     C234 1
 '@TIMECARD_LIB.TIMECARD(SCH_1):PAGE515_I138@PASSIVE.CAPACITOR(CHIPS)':
 '1': CDS_PINID='\1\';
NODE_NAME     R229 2
 '@TIMECARD_LIB.TIMECARD(SCH_1):PAGE515_I139@PASSIVE.RESISTOR(CHIPS)':
 '2': CDS_PINID='\2\';
NODE_NAME     R230 1
 '@TIMECARD_LIB.TIMECARD(SCH_1):PAGE515_I140@PASSIVE.RESISTOR(CHIPS)':
 '1': CDS_PINID='\1\';
NODE_NAME     U25 4
 '@TIMECARD_LIB.TIMECARD(SCH_1):PAGE515_I151@ANALOG.ISL80101IRAJZ_DFN10(CHIPS)':
 'PG': CDS_PINID='PG';
NET_NAME
'UNNAMED_515_ISL80101IRAJZDFN10_'
 '@TIMECARD_LIB.TIMECARD(SCH_1):UNNAMED_515_ISL80101IRAJZDFN10_I151_SENSE':
 C_SIGNAL='@timecard_lib.timecard(sch_1):unnamed_515_isl80101irajzdfn10_i151_sen~
se';
NODE_NAME     R232 2
 '@TIMECARD_LIB.TIMECARD(SCH_1):PAGE515_I143@PASSIVE.RESISTOR(CHIPS)':
 '2': CDS_PINID='\2\';
NODE_NAME     R233 2
 '@TIMECARD_LIB.TIMECARD(SCH_1):PAGE515_I145@PASSIVE.RESISTOR(CHIPS)':
 '2': CDS_PINID='\2\';
NODE_NAME     R231 2
 '@TIMECARD_LIB.TIMECARD(SCH_1):PAGE515_I146@PASSIVE.RESISTOR(CHIPS)':
 '2': CDS_PINID='\2\';
NODE_NAME     U25 3
 '@TIMECARD_LIB.TIMECARD(SCH_1):PAGE515_I151@ANALOG.ISL80101IRAJZ_DFN10(CHIPS)':
 'SENSE/ADJ': CDS_PINID='\sense/adj\';
NET_NAME
'UNNAMED_515_NCP45560IMNTWGHDFN1'
 '@TIMECARD_LIB.TIMECARD(SCH_1):UNNAMED_515_NCP45560IMNTWGHDFN12_I82_PG':
 C_SIGNAL='@timecard_lib.timecard(sch_1):unnamed_515_ncp45560imntwghdfn12_i82_pg~
';
NODE_NAME     R295 2
 '@TIMECARD_LIB.TIMECARD(SCH_1):PAGE515_I69@PASSIVE.RESISTOR(CHIPS)':
 '2': CDS_PINID='\2\';
NODE_NAME     U22 6
 '@TIMECARD_LIB.TIMECARD(SCH_1):PAGE515_I82@ANALOG.NCP45560IMNTWG_H_DFN12(CHIPS)':
 'PG': CDS_PINID='PG';
NODE_NAME     R143 2
 '@TIMECARD_LIB.TIMECARD(SCH_1):PAGE515_I167@PASSIVE.RESISTOR(CHIPS)':
 '2': CDS_PINID='\2\';
NET_NAME
'UNNAMED_516_CAPACITOR_I13_1'
 '@TIMECARD_LIB.TIMECARD(SCH_1):UNNAMED_516_CAPACITOR_I13_1':
 C_SIGNAL='@timecard_lib.timecard(sch_1):unnamed_516_capacitor_i13_1';
NODE_NAME     C42 1
 '@TIMECARD_LIB.TIMECARD(SCH_1):PAGE516_I13@PASSIVE.CAPACITOR(CHIPS)':
 '1': CDS_PINID='\1\';
NODE_NAME     R30 2
 '@TIMECARD_LIB.TIMECARD(SCH_1):PAGE516_I14@PASSIVE.RESISTOR(CHIPS)':
 '2': CDS_PINID='\2\';
NET_NAME
'UNNAMED_516_CAPACITOR_I27_1'
 '@TIMECARD_LIB.TIMECARD(SCH_1):UNNAMED_516_CAPACITOR_I27_1':
 C_SIGNAL='@timecard_lib.timecard(sch_1):unnamed_516_capacitor_i27_1';
NODE_NAME     R31 2
 '@TIMECARD_LIB.TIMECARD(SCH_1):PAGE516_I26@PASSIVE.RESISTOR(CHIPS)':
 '2': CDS_PINID='\2\';
NODE_NAME     C44 1
 '@TIMECARD_LIB.TIMECARD(SCH_1):PAGE516_I27@PASSIVE.CAPACITOR(CHIPS)':
 '1': CDS_PINID='\1\';
NET_NAME
'UNNAMED_516_CAPACITOR_I29_1'
 '@TIMECARD_LIB.TIMECARD(SCH_1):UNNAMED_516_CAPACITOR_I29_1':
 C_SIGNAL='@timecard_lib.timecard(sch_1):unnamed_516_capacitor_i29_1';
NODE_NAME     C11 1
 '@TIMECARD_LIB.TIMECARD(SCH_1):PAGE516_I29@PASSIVE.CAPACITOR(CHIPS)':
 '1': CDS_PINID='\1\';
NODE_NAME     R34 1
 '@TIMECARD_LIB.TIMECARD(SCH_1):PAGE516_I30@PASSIVE.RESISTOR(CHIPS)':
 '1': CDS_PINID='\1\';
NODE_NAME     R6 2
 '@TIMECARD_LIB.TIMECARD(SCH_1):PAGE516_I31@PASSIVE.RESISTOR(CHIPS)':
 '2': CDS_PINID='\2\';
NET_NAME
'UNNAMED_516_CAPACITOR_I37_2'
 '@TIMECARD_LIB.TIMECARD(SCH_1):UNNAMED_516_CAPACITOR_I37_2':
 C_SIGNAL='@timecard_lib.timecard(sch_1):unnamed_516_capacitor_i37_2';
NODE_NAME     C45 2
 '@TIMECARD_LIB.TIMECARD(SCH_1):PAGE516_I37@PASSIVE.CAPACITOR(CHIPS)':
 '2': CDS_PINID='\2\';
NODE_NAME     R33 1
 '@TIMECARD_LIB.TIMECARD(SCH_1):PAGE516_I38@PASSIVE.RESISTOR(CHIPS)':
 '1': CDS_PINID='\1\';
NET_NAME
'UNNAMED_517_CAPACITOR_I17_1'
 '@TIMECARD_LIB.TIMECARD(SCH_1):UNNAMED_517_CAPACITOR_I17_1':
 C_SIGNAL='@timecard_lib.timecard(sch_1):unnamed_517_capacitor_i17_1';
NODE_NAME     C54 1
 '@TIMECARD_LIB.TIMECARD(SCH_1):PAGE517_I17@PASSIVE.CAPACITOR(CHIPS)':
 '1': CDS_PINID='\1\';
NODE_NAME     R36 2
 '@TIMECARD_LIB.TIMECARD(SCH_1):PAGE517_I18@PASSIVE.RESISTOR(CHIPS)':
 '2': CDS_PINID='\2\';
NET_NAME
'UNNAMED_517_CAPACITOR_I27_1'
 '@TIMECARD_LIB.TIMECARD(SCH_1):UNNAMED_517_CAPACITOR_I27_1':
 C_SIGNAL='@timecard_lib.timecard(sch_1):unnamed_517_capacitor_i27_1';
NODE_NAME     R37 2
 '@TIMECARD_LIB.TIMECARD(SCH_1):PAGE517_I25@PASSIVE.RESISTOR(CHIPS)':
 '2': CDS_PINID='\2\';
NODE_NAME     C56 1
 '@TIMECARD_LIB.TIMECARD(SCH_1):PAGE517_I27@PASSIVE.CAPACITOR(CHIPS)':
 '1': CDS_PINID='\1\';
NET_NAME
'UNNAMED_517_CAPACITOR_I29_2'
 '@TIMECARD_LIB.TIMECARD(SCH_1):UNNAMED_517_CAPACITOR_I29_2':
 C_SIGNAL='@timecard_lib.timecard(sch_1):unnamed_517_capacitor_i29_2';
NODE_NAME     C57 2
 '@TIMECARD_LIB.TIMECARD(SCH_1):PAGE517_I29@PASSIVE.CAPACITOR(CHIPS)':
 '2': CDS_PINID='\2\';
NODE_NAME     R39 1
 '@TIMECARD_LIB.TIMECARD(SCH_1):PAGE517_I32@PASSIVE.RESISTOR(CHIPS)':
 '1': CDS_PINID='\1\';
NET_NAME
'UNNAMED_517_CAPACITOR_I30_1'
 '@TIMECARD_LIB.TIMECARD(SCH_1):UNNAMED_517_CAPACITOR_I30_1':
 C_SIGNAL='@timecard_lib.timecard(sch_1):unnamed_517_capacitor_i30_1';
NODE_NAME     C16 1
 '@TIMECARD_LIB.TIMECARD(SCH_1):PAGE517_I30@PASSIVE.CAPACITOR(CHIPS)':
 '1': CDS_PINID='\1\';
NODE_NAME     R40 1
 '@TIMECARD_LIB.TIMECARD(SCH_1):PAGE517_I31@PASSIVE.RESISTOR(CHIPS)':
 '1': CDS_PINID='\1\';
NODE_NAME     R17 2
 '@TIMECARD_LIB.TIMECARD(SCH_1):PAGE517_I33@PASSIVE.RESISTOR(CHIPS)':
 '2': CDS_PINID='\2\';
NET_NAME
'UNNAMED_523_CAPACITOR_I24_1'
 '@TIMECARD_LIB.TIMECARD(SCH_1):UNNAMED_523_CAPACITOR_I24_1':
 C_SIGNAL='@timecard_lib.timecard(sch_1):unnamed_523_capacitor_i24_1';
NODE_NAME     R250 2
 '@TIMECARD_LIB.TIMECARD(SCH_1):PAGE523_I23@PASSIVE.RESISTOR(CHIPS)':
 '2': CDS_PINID='\2\';
NODE_NAME     C265 1
 '@TIMECARD_LIB.TIMECARD(SCH_1):PAGE523_I24@PASSIVE.CAPACITOR(CHIPS)':
 '1': CDS_PINID='\1\';
NET_NAME
'UNNAMED_523_CAPACITOR_I28_1'
 '@TIMECARD_LIB.TIMECARD(SCH_1):UNNAMED_523_CAPACITOR_I28_1':
 C_SIGNAL='@timecard_lib.timecard(sch_1):unnamed_523_capacitor_i28_1';
NODE_NAME     C267 1
 '@TIMECARD_LIB.TIMECARD(SCH_1):PAGE523_I28@PASSIVE.CAPACITOR(CHIPS)':
 '1': CDS_PINID='\1\';
NODE_NAME     R255 1
 '@TIMECARD_LIB.TIMECARD(SCH_1):PAGE523_I29@PASSIVE.RESISTOR(CHIPS)':
 '1': CDS_PINID='\1\';
NODE_NAME     R254 2
 '@TIMECARD_LIB.TIMECARD(SCH_1):PAGE523_I30@PASSIVE.RESISTOR(CHIPS)':
 '2': CDS_PINID='\2\';
NET_NAME
'UNNAMED_523_CAPACITOR_I31_2'
 '@TIMECARD_LIB.TIMECARD(SCH_1):UNNAMED_523_CAPACITOR_I31_2':
 C_SIGNAL='@timecard_lib.timecard(sch_1):unnamed_523_capacitor_i31_2';
NODE_NAME     R253 1
 '@TIMECARD_LIB.TIMECARD(SCH_1):PAGE523_I26@PASSIVE.RESISTOR(CHIPS)':
 '1': CDS_PINID='\1\';
NODE_NAME     C266 2
 '@TIMECARD_LIB.TIMECARD(SCH_1):PAGE523_I31@PASSIVE.CAPACITOR(CHIPS)':
 '2': CDS_PINID='\2\';
NET_NAME
'UNNAMED_523_CAPACITOR_I7_1'
 '@TIMECARD_LIB.TIMECARD(SCH_1):UNNAMED_523_CAPACITOR_I7_1':
 C_SIGNAL='@timecard_lib.timecard(sch_1):unnamed_523_capacitor_i7_1';
NODE_NAME     C256 1
 '@TIMECARD_LIB.TIMECARD(SCH_1):PAGE523_I7@PASSIVE.CAPACITOR(CHIPS)':
 '1': CDS_PINID='\1\';
NODE_NAME     U26 17
 '@TIMECARD_LIB.TIMECARD(SCH_1):PAGE523_I11@STDLOGIC.TPS54824RNVR_VQFN18(CHIPS)':
 'EN': CDS_PINID='EN';
NODE_NAME     R246 1
 '@TIMECARD_LIB.TIMECARD(SCH_1):PAGE523_I51@PASSIVE.RESISTOR(CHIPS)':
 '1': CDS_PINID='\1\';
NODE_NAME     R247 2
 '@TIMECARD_LIB.TIMECARD(SCH_1):PAGE523_I54@PASSIVE.RESISTOR(CHIPS)':
 '2': CDS_PINID='\2\';
NODE_NAME     R244 2
 '@TIMECARD_LIB.TIMECARD(SCH_1):PAGE523_I109@PASSIVE.RESISTOR(CHIPS)':
 '2': CDS_PINID='\2\';
NET_NAME
'UNNAMED_523_CAPACITOR_I9_1'
 '@TIMECARD_LIB.TIMECARD(SCH_1):UNNAMED_523_CAPACITOR_I9_1':
 C_SIGNAL='@timecard_lib.timecard(sch_1):unnamed_523_capacitor_i9_1';
NODE_NAME     C263 1
 '@TIMECARD_LIB.TIMECARD(SCH_1):PAGE523_I9@PASSIVE.CAPACITOR(CHIPS)':
 '1': CDS_PINID='\1\';
NODE_NAME     R249 2
 '@TIMECARD_LIB.TIMECARD(SCH_1):PAGE523_I16@PASSIVE.RESISTOR(CHIPS)':
 '2': CDS_PINID='\2\';
NET_NAME
'UNNAMED_524_CAPACITOR_I10_2'
 '@TIMECARD_LIB.TIMECARD(SCH_1):UNNAMED_524_CAPACITOR_I10_2':
 C_SIGNAL='@timecard_lib.timecard(sch_1):unnamed_524_capacitor_i10_2';
NODE_NAME     Y2 3
 '@TIMECARD_LIB.TIMECARD(SCH_1):PAGE524_I8@CLOCK.XTAL_4(CHIPS)':
 '3': CDS_PINID='\3\';
NODE_NAME     C87 2
 '@TIMECARD_LIB.TIMECARD(SCH_1):PAGE524_I10@PASSIVE.CAPACITOR(CHIPS)':
 '2': CDS_PINID='\2\';
NODE_NAME     U18 3
 '@TIMECARD_LIB.TIMECARD(SCH_1):PAGE524_I64@INTERFACE.FT4232HL_REEL_QFP64(CHIPS)':
 'OSCO': CDS_PINID='OSCO';
NODE_NAME     R455 2
 '@TIMECARD_LIB.TIMECARD(SCH_1):PAGE524_I287@PASSIVE.RESISTOR(CHIPS)':
 '2': CDS_PINID='\2\';
NET_NAME
'UNNAMED_524_CAPACITOR_I7_2'
 '@TIMECARD_LIB.TIMECARD(SCH_1):UNNAMED_524_CAPACITOR_I7_2':
 C_SIGNAL='@timecard_lib.timecard(sch_1):unnamed_524_capacitor_i7_2';
NODE_NAME     C86 2
 '@TIMECARD_LIB.TIMECARD(SCH_1):PAGE524_I7@PASSIVE.CAPACITOR(CHIPS)':
 '2': CDS_PINID='\2\';
NODE_NAME     Y2 1
 '@TIMECARD_LIB.TIMECARD(SCH_1):PAGE524_I8@CLOCK.XTAL_4(CHIPS)':
 '1': CDS_PINID='\1\';
NODE_NAME     U18 2
 '@TIMECARD_LIB.TIMECARD(SCH_1):PAGE524_I64@INTERFACE.FT4232HL_REEL_QFP64(CHIPS)':
 'OSCI': CDS_PINID='OSCI';
NODE_NAME     R455 1
 '@TIMECARD_LIB.TIMECARD(SCH_1):PAGE524_I287@PASSIVE.RESISTOR(CHIPS)':
 '1': CDS_PINID='\1\';
NET_NAME
'UNNAMED_524_CONNUSB14PGH4FRATH_'
 '@TIMECARD_LIB.TIMECARD(SCH_1):UNNAMED_524_CONNUSB14PGH4FRATH_I495_CC1':
 C_SIGNAL='@timecard_lib.timecard(sch_1):unnamed_524_connusb14pgh4frath_i495_cc1~
';
NODE_NAME     J13 A5
 '@TIMECARD_LIB.TIMECARD(SCH_1):PAGE524_I495@CONNECTOR.CONN_USB_14P_GH4_F_RA_TH(CHIPS)':
 'CC1': CDS_PINID='CC1';
NODE_NAME     R442 1
 '@TIMECARD_LIB.TIMECARD(SCH_1):PAGE524_I497@PASSIVE.RESISTOR(CHIPS)':
 '1': CDS_PINID='\1\';
NET_NAME
'UNNAMED_524_CONNUSB14PGH4FRAT_1'
 '@TIMECARD_LIB.TIMECARD(SCH_1):UNNAMED_524_CONNUSB14PGH4FRATH_I495_CC2':
 C_SIGNAL='@timecard_lib.timecard(sch_1):unnamed_524_connusb14pgh4frath_i495_cc2~
';
NODE_NAME     R445 1
 '@TIMECARD_LIB.TIMECARD(SCH_1):PAGE524_I395@PASSIVE.RESISTOR(CHIPS)':
 '1': CDS_PINID='\1\';
NODE_NAME     J13 B5
 '@TIMECARD_LIB.TIMECARD(SCH_1):PAGE524_I495@CONNECTOR.CONN_USB_14P_GH4_F_RA_TH(CHIPS)':
 'CC2': CDS_PINID='CC2';
NET_NAME
'UNNAMED_524_FT4232HLREELQFP64_1'
 '@TIMECARD_LIB.TIMECARD(SCH_1):UNNAMED_524_FT4232HLREELQFP64_I64_BDBUS3':
 C_SIGNAL='@timecard_lib.timecard(sch_1):unnamed_524_ft4232hlreelqfp64_i64_bdbus~
3';
NODE_NAME     U18 29
 '@TIMECARD_LIB.TIMECARD(SCH_1):PAGE524_I64@INTERFACE.FT4232HL_REEL_QFP64(CHIPS)':
 'BDBUS3': CDS_PINID='BDBUS3';
NODE_NAME     TP6 1
 '@TIMECARD_LIB.TIMECARD(SCH_1):PAGE524_I312@CLS.TP_PIONT(CHIPS)':
 '1': CDS_PINID='\1\';
NET_NAME
'UNNAMED_524_FT4232HLREELQFP64_2'
 '@TIMECARD_LIB.TIMECARD(SCH_1):UNNAMED_524_FT4232HLREELQFP64_I64_BDBUS4':
 C_SIGNAL='@timecard_lib.timecard(sch_1):unnamed_524_ft4232hlreelqfp64_i64_bdbus~
4';
NODE_NAME     U18 30
 '@TIMECARD_LIB.TIMECARD(SCH_1):PAGE524_I64@INTERFACE.FT4232HL_REEL_QFP64(CHIPS)':
 'BDBUS4': CDS_PINID='BDBUS4';
NODE_NAME     TP7 1
 '@TIMECARD_LIB.TIMECARD(SCH_1):PAGE524_I313@CLS.TP_PIONT(CHIPS)':
 '1': CDS_PINID='\1\';
NET_NAME
'UNNAMED_524_FT4232HLREELQFP64_3'
 '@TIMECARD_LIB.TIMECARD(SCH_1):UNNAMED_524_FT4232HLREELQFP64_I64_BDBUS5':
 C_SIGNAL='@timecard_lib.timecard(sch_1):unnamed_524_ft4232hlreelqfp64_i64_bdbus~
5';
NODE_NAME     U18 32
 '@TIMECARD_LIB.TIMECARD(SCH_1):PAGE524_I64@INTERFACE.FT4232HL_REEL_QFP64(CHIPS)':
 'BDBUS5': CDS_PINID='BDBUS5';
NODE_NAME     TP8 1
 '@TIMECARD_LIB.TIMECARD(SCH_1):PAGE524_I315@CLS.TP_PIONT(CHIPS)':
 '1': CDS_PINID='\1\';
NET_NAME
'UNNAMED_524_FT4232HLREELQFP64_4'
 '@TIMECARD_LIB.TIMECARD(SCH_1):UNNAMED_524_FT4232HLREELQFP64_I64_BDBUS6':
 C_SIGNAL='@timecard_lib.timecard(sch_1):unnamed_524_ft4232hlreelqfp64_i64_bdbus~
6';
NODE_NAME     U18 33
 '@TIMECARD_LIB.TIMECARD(SCH_1):PAGE524_I64@INTERFACE.FT4232HL_REEL_QFP64(CHIPS)':
 'BDBUS6': CDS_PINID='BDBUS6';
NODE_NAME     TP9 1
 '@TIMECARD_LIB.TIMECARD(SCH_1):PAGE524_I314@CLS.TP_PIONT(CHIPS)':
 '1': CDS_PINID='\1\';
NET_NAME
'UNNAMED_524_FT4232HLREELQFP64_5'
 '@TIMECARD_LIB.TIMECARD(SCH_1):UNNAMED_524_FT4232HLREELQFP64_I64_BDBUS7':
 C_SIGNAL='@timecard_lib.timecard(sch_1):unnamed_524_ft4232hlreelqfp64_i64_bdbus~
7';
NODE_NAME     U18 34
 '@TIMECARD_LIB.TIMECARD(SCH_1):PAGE524_I64@INTERFACE.FT4232HL_REEL_QFP64(CHIPS)':
 'BDBUS7': CDS_PINID='BDBUS7';
NODE_NAME     TP10 1
 '@TIMECARD_LIB.TIMECARD(SCH_1):PAGE524_I316@CLS.TP_PIONT(CHIPS)':
 '1': CDS_PINID='\1\';
NET_NAME
'UNNAMED_524_FT4232HLREELQFP64_6'
 '@TIMECARD_LIB.TIMECARD(SCH_1):UNNAMED_524_FT4232HLREELQFP64_I64_REF':
 C_SIGNAL='@timecard_lib.timecard(sch_1):unnamed_524_ft4232hlreelqfp64_i64_ref';
NODE_NAME     U18 6
 '@TIMECARD_LIB.TIMECARD(SCH_1):PAGE524_I64@INTERFACE.FT4232HL_REEL_QFP64(CHIPS)':
 'REF': CDS_PINID='REF';
NODE_NAME     R463 1
 '@TIMECARD_LIB.TIMECARD(SCH_1):PAGE524_I106@PASSIVE.RESISTOR(CHIPS)':
 '1': CDS_PINID='\1\';
NET_NAME
'UNNAMED_524_FT4232HLREELQFP64_7'
 '@TIMECARD_LIB.TIMECARD(SCH_1):UNNAMED_524_FT4232HLREELQFP64_I64_RESET':
 C_SIGNAL='@timecard_lib.timecard(sch_1):unnamed_524_ft4232hlreelqfp64_i64_reset~
';
NODE_NAME     U18 14
 '@TIMECARD_LIB.TIMECARD(SCH_1):PAGE524_I64@INTERFACE.FT4232HL_REEL_QFP64(CHIPS)':
 'RESET*': CDS_PINID='\reset*\';
NODE_NAME     R460 2
 '@TIMECARD_LIB.TIMECARD(SCH_1):PAGE524_I121@PASSIVE.RESISTOR(CHIPS)':
 '2': CDS_PINID='\2\';
NET_NAME
'UNNAMED_524_FT4232HLREELQFP64_I'
 '@TIMECARD_LIB.TIMECARD(SCH_1):UNNAMED_524_FT4232HLREELQFP64_I64_ADBUS7':
 C_SIGNAL='@timecard_lib.timecard(sch_1):unnamed_524_ft4232hlreelqfp64_i64_adbus~
7';
NODE_NAME     U18 24
 '@TIMECARD_LIB.TIMECARD(SCH_1):PAGE524_I64@INTERFACE.FT4232HL_REEL_QFP64(CHIPS)':
 'ADBUS7': CDS_PINID='ADBUS7';
NODE_NAME     TP5 1
 '@TIMECARD_LIB.TIMECARD(SCH_1):PAGE524_I311@CLS.TP_PIONT(CHIPS)':
 '1': CDS_PINID='\1\';
NET_NAME
'UNNAMED_524_POWERMOS3PNCHV1_I44'
 '@TIMECARD_LIB.TIMECARD(SCH_1):UNNAMED_524_POWERMOS3PNCHV1_I445_D':
 C_SIGNAL='@timecard_lib.timecard(sch_1):unnamed_524_powermos3pnchv1_i445_d';
NODE_NAME     U30 15
 '@TIMECARD_LIB.TIMECARD(SCH_1):PAGE524_I425@STDLOGIC.TS3A5018PWR_TSSOP16(CHIPS)':
 'EN*': CDS_PINID='\en*\';
NODE_NAME     R453 1
 '@TIMECARD_LIB.TIMECARD(SCH_1):PAGE524_I442@PASSIVE.RESISTOR(CHIPS)':
 '1': CDS_PINID='\1\';
NODE_NAME     R452 1
 '@TIMECARD_LIB.TIMECARD(SCH_1):PAGE524_I443@PASSIVE.RESISTOR(CHIPS)':
 '1': CDS_PINID='\1\';
NODE_NAME     Q1 3
 '@TIMECARD_LIB.TIMECARD(SCH_1):PAGE524_I445@DISCRETE.POWERMOS_3P_NCH_V1(CHIPS)':
 'D': CDS_PINID='D';
NET_NAME
'UNNAMED_524_RESISTOR_I432_2'
 '@TIMECARD_LIB.TIMECARD(SCH_1):UNNAMED_524_RESISTOR_I432_2':
 C_SIGNAL='@timecard_lib.timecard(sch_1):unnamed_524_resistor_i432_2';
NODE_NAME     U38 15
 '@TIMECARD_LIB.TIMECARD(SCH_1):PAGE524_I400@STDLOGIC.TS3A5018PWR_TSSOP16(CHIPS)':
 'EN*': CDS_PINID='\en*\';
NODE_NAME     R459 2
 '@TIMECARD_LIB.TIMECARD(SCH_1):PAGE524_I432@PASSIVE.RESISTOR(CHIPS)':
 '2': CDS_PINID='\2\';
NET_NAME
'UNNAMED_524_RESISTOR_I463_2'
 '@TIMECARD_LIB.TIMECARD(SCH_1):UNNAMED_524_RESISTOR_I463_2':
 C_SIGNAL='@timecard_lib.timecard(sch_1):unnamed_524_resistor_i463_2';
NODE_NAME     U37 15
 '@TIMECARD_LIB.TIMECARD(SCH_1):PAGE524_I448@STDLOGIC.TS3A5018PWR_TSSOP16(CHIPS)':
 'EN*': CDS_PINID='\en*\';
NODE_NAME     R484 2
 '@TIMECARD_LIB.TIMECARD(SCH_1):PAGE524_I463@PASSIVE.RESISTOR(CHIPS)':
 '2': CDS_PINID='\2\';
NET_NAME
'UNNAMED_525_CAPACITOR_I14_1'
 '@TIMECARD_LIB.TIMECARD(SCH_1):UNNAMED_525_CAPACITOR_I14_1':
 C_SIGNAL='@timecard_lib.timecard(sch_1):unnamed_525_capacitor_i14_1';
NODE_NAME     R488 1
 '@TIMECARD_LIB.TIMECARD(SCH_1):PAGE525_I13@PASSIVE.RESISTOR(CHIPS)':
 '1': CDS_PINID='\1\';
NODE_NAME     C302 1
 '@TIMECARD_LIB.TIMECARD(SCH_1):PAGE525_I14@PASSIVE.CAPACITOR(CHIPS)':
 '1': CDS_PINID='\1\';
NODE_NAME     U41 7
 '@TIMECARD_LIB.TIMECARD(SCH_1):PAGE525_I29@ANALOG.ISL80101IRAJZ_DFN10(CHIPS)':
 'ENABLE': CDS_PINID='ENABLE';
NODE_NAME     R487 2
 '@TIMECARD_LIB.TIMECARD(SCH_1):PAGE525_I65@PASSIVE.RESISTOR(CHIPS)':
 '2': CDS_PINID='\2\';
NET_NAME
'UNNAMED_525_CAPACITOR_I16_1'
 '@TIMECARD_LIB.TIMECARD(SCH_1):UNNAMED_525_CAPACITOR_I16_1':
 C_SIGNAL='@timecard_lib.timecard(sch_1):unnamed_525_capacitor_i16_1';
NODE_NAME     L23 2
 '@TIMECARD_LIB.TIMECARD(SCH_1):PAGE525_I10@PASSIVE.FERRITEBEAD(CHIPS)':
 '2': CDS_PINID='\2\';
NODE_NAME     C300 1
 '@TIMECARD_LIB.TIMECARD(SCH_1):PAGE525_I16@PASSIVE.CAPACITOR(CHIPS)':
 '1': CDS_PINID='\1\';
NODE_NAME     C304 1
 '@TIMECARD_LIB.TIMECARD(SCH_1):PAGE525_I20@PASSIVE.CAPACITOR(CHIPS)':
 '1': CDS_PINID='\1\';
NODE_NAME     U41 9
 '@TIMECARD_LIB.TIMECARD(SCH_1):PAGE525_I29@ANALOG.ISL80101IRAJZ_DFN10(CHIPS)':
 'VIN_1': CDS_PINID='VIN_1';
NODE_NAME     U41 10
 '@TIMECARD_LIB.TIMECARD(SCH_1):PAGE525_I29@ANALOG.ISL80101IRAJZ_DFN10(CHIPS)':
 'VIN_2': CDS_PINID='VIN_2';
NODE_NAME     R487 1
 '@TIMECARD_LIB.TIMECARD(SCH_1):PAGE525_I65@PASSIVE.RESISTOR(CHIPS)':
 '1': CDS_PINID='\1\';
NET_NAME
'UNNAMED_525_CAPACITOR_I18_1'
 '@TIMECARD_LIB.TIMECARD(SCH_1):UNNAMED_525_CAPACITOR_I18_1':
 C_SIGNAL='@timecard_lib.timecard(sch_1):unnamed_525_capacitor_i18_1';
NODE_NAME     C307 1
 '@TIMECARD_LIB.TIMECARD(SCH_1):PAGE525_I18@PASSIVE.CAPACITOR(CHIPS)':
 '1': CDS_PINID='\1\';
NODE_NAME     U41 6
 '@TIMECARD_LIB.TIMECARD(SCH_1):PAGE525_I29@ANALOG.ISL80101IRAJZ_DFN10(CHIPS)':
 'SS': CDS_PINID='SS';
NET_NAME
'UNNAMED_525_CAPACITOR_I7_1'
 '@TIMECARD_LIB.TIMECARD(SCH_1):UNNAMED_525_CAPACITOR_I7_1':
 C_SIGNAL='@timecard_lib.timecard(sch_1):unnamed_525_capacitor_i7_1';
NODE_NAME     C284 1
 '@TIMECARD_LIB.TIMECARD(SCH_1):PAGE525_I7@PASSIVE.CAPACITOR(CHIPS)':
 '1': CDS_PINID='\1\';
NODE_NAME     C298 1
 '@TIMECARD_LIB.TIMECARD(SCH_1):PAGE525_I8@PASSIVE.CAPACITOR(CHIPS)':
 '1': CDS_PINID='\1\';
NODE_NAME     L23 1
 '@TIMECARD_LIB.TIMECARD(SCH_1):PAGE525_I10@PASSIVE.FERRITEBEAD(CHIPS)':
 '1': CDS_PINID='\1\';
NODE_NAME     CR1 C
 '@TIMECARD_LIB.TIMECARD(SCH_1):PAGE525_I102@DISCRETE.DIODE_2F(CHIPS)':
 'C': CDS_PINID='C';
NODE_NAME     CR2 C
 '@TIMECARD_LIB.TIMECARD(SCH_1):PAGE525_I104@DISCRETE.DIODE_2F(CHIPS)':
 'C': CDS_PINID='C';
NET_NAME
'UNNAMED_525_ISL80101IRAJZDFN10_'
 '@TIMECARD_LIB.TIMECARD(SCH_1):UNNAMED_525_ISL80101IRAJZDFN10_I29_SENSE':
 C_SIGNAL='@timecard_lib.timecard(sch_1):unnamed_525_isl80101irajzdfn10_i29_sens~
e';
NODE_NAME     U41 3
 '@TIMECARD_LIB.TIMECARD(SCH_1):PAGE525_I29@ANALOG.ISL80101IRAJZ_DFN10(CHIPS)':
 'SENSE/ADJ': CDS_PINID='\sense/adj\';
NODE_NAME     R490 2
 '@TIMECARD_LIB.TIMECARD(SCH_1):PAGE525_I66@PASSIVE.RESISTOR(CHIPS)':
 '2': CDS_PINID='\2\';
NODE_NAME     R491 1
 '@TIMECARD_LIB.TIMECARD(SCH_1):PAGE525_I67@PASSIVE.RESISTOR(CHIPS)':
 '1': CDS_PINID='\1\';
NODE_NAME     R489 1
 '@TIMECARD_LIB.TIMECARD(SCH_1):PAGE525_I68@PASSIVE.RESISTOR(CHIPS)':
 '1': CDS_PINID='\1\';
NET_NAME
'UNNAMED_527_FUSE_I244_1'
 '@TIMECARD_LIB.TIMECARD(SCH_1):UNNAMED_527_FUSE_I244_1':
 C_SIGNAL='@timecard_lib.timecard(sch_1):unnamed_527_fuse_i244_1';
NODE_NAME     Q3 3
 '@TIMECARD_LIB.TIMECARD(SCH_1):PAGE527_I231@DISCRETE.POWERMOS_3P_PCH(CHIPS)':
 'D': CDS_PINID='D';
NODE_NAME     FU3 1
 '@TIMECARD_LIB.TIMECARD(SCH_1):PAGE527_I244@PASSIVE.FUSE(CHIPS)':
 '1': CDS_PINID='\1\';
NODE_NAME     R357 2
 '@TIMECARD_LIB.TIMECARD(SCH_1):PAGE527_I245@PASSIVE.RESISTOR(CHIPS)':
 '2': CDS_PINID='\2\';
NET_NAME
'UNNAMED_527_POWERMOS3PNCHV1_I23'
 '@TIMECARD_LIB.TIMECARD(SCH_1):UNNAMED_527_POWERMOS3PNCHV1_I232_D':
 C_SIGNAL='@timecard_lib.timecard(sch_1):unnamed_527_powermos3pnchv1_i232_d';
NODE_NAME     Q3 1
 '@TIMECARD_LIB.TIMECARD(SCH_1):PAGE527_I231@DISCRETE.POWERMOS_3P_PCH(CHIPS)':
 'G': CDS_PINID='G';
NODE_NAME     Q2 3
 '@TIMECARD_LIB.TIMECARD(SCH_1):PAGE527_I232@DISCRETE.POWERMOS_3P_NCH_V1(CHIPS)':
 'D': CDS_PINID='D';
NODE_NAME     R44 2
 '@TIMECARD_LIB.TIMECARD(SCH_1):PAGE527_I233@PASSIVE.RESISTOR(CHIPS)':
 '2': CDS_PINID='\2\';
NET_NAME
'UNNAMED_527_RESISTOR_I126_1'
 '@TIMECARD_LIB.TIMECARD(SCH_1):UNNAMED_527_RESISTOR_I126_1':
 C_SIGNAL='@timecard_lib.timecard(sch_1):unnamed_527_resistor_i126_1';
NODE_NAME     U11 2
 '@TIMECARD_LIB.TIMECARD(SCH_1):PAGE527_I108@STDLOGIC.TS3USB3031RMGR_WQFN12(CHIPS)':
 'SEL1': CDS_PINID='SEL1';
NODE_NAME     R104 1
 '@TIMECARD_LIB.TIMECARD(SCH_1):PAGE527_I126@PASSIVE.RESISTOR(CHIPS)':
 '1': CDS_PINID='\1\';
NET_NAME
'UNNAMED_527_RESISTOR_I201_2'
 '@TIMECARD_LIB.TIMECARD(SCH_1):UNNAMED_527_RESISTOR_I201_2':
 C_SIGNAL='@timecard_lib.timecard(sch_1):unnamed_527_resistor_i201_2';
NODE_NAME     R102 2
 '@TIMECARD_LIB.TIMECARD(SCH_1):PAGE527_I201@PASSIVE.RESISTOR(CHIPS)':
 '2': CDS_PINID='\2\';
NODE_NAME     R103 1
 '@TIMECARD_LIB.TIMECARD(SCH_1):PAGE527_I202@PASSIVE.RESISTOR(CHIPS)':
 '1': CDS_PINID='\1\';
NET_NAME
'UNNAMED_527_RESISTOR_I206_1'
 '@TIMECARD_LIB.TIMECARD(SCH_1):UNNAMED_527_RESISTOR_I206_1':
 C_SIGNAL='@timecard_lib.timecard(sch_1):unnamed_527_resistor_i206_1';
NODE_NAME     U12 3
 '@TIMECARD_LIB.TIMECARD(SCH_1):PAGE527_I79@STDLOGIC.TPS2051BDBVT_SOT23_5(CHIPS)':
 'OC*': CDS_PINID='\oc*\';
NODE_NAME     R267 1
 '@TIMECARD_LIB.TIMECARD(SCH_1):PAGE527_I206@PASSIVE.RESISTOR(CHIPS)':
 '1': CDS_PINID='\1\';
NET_NAME
'UNNAMED_5_24LC16BTISTTSSOP8_I15'
 '@TIMECARD_LIB.TIMECARD(SCH_1):UNNAMED_5_24LC16BTISTTSSOP8_I151_A0':
 C_SIGNAL='@timecard_lib.timecard(sch_1):unnamed_5_24lc16btisttssop8_i151_a0';
NODE_NAME     U19 1
 '@TIMECARD_LIB.TIMECARD(SCH_1):PAGE5_I151@MEMORY.24LC16BT_I_ST_TSSOP8(CHIPS)':
 'A0': CDS_PINID='A0';
NODE_NAME     R158 2
 '@TIMECARD_LIB.TIMECARD(SCH_1):PAGE5_I153@PASSIVE.RESISTOR(CHIPS)':
 '2': CDS_PINID='\2\';
NODE_NAME     R159 1
 '@TIMECARD_LIB.TIMECARD(SCH_1):PAGE5_I156@PASSIVE.RESISTOR(CHIPS)':
 '1': CDS_PINID='\1\';
NET_NAME
'UNNAMED_5_24LC16BTISTTSSOP8_I_1'
 '@TIMECARD_LIB.TIMECARD(SCH_1):UNNAMED_5_24LC16BTISTTSSOP8_I151_A1':
 C_SIGNAL='@timecard_lib.timecard(sch_1):unnamed_5_24lc16btisttssop8_i151_a1';
NODE_NAME     U19 2
 '@TIMECARD_LIB.TIMECARD(SCH_1):PAGE5_I151@MEMORY.24LC16BT_I_ST_TSSOP8(CHIPS)':
 'A1': CDS_PINID='A1';
NODE_NAME     R160 2
 '@TIMECARD_LIB.TIMECARD(SCH_1):PAGE5_I160@PASSIVE.RESISTOR(CHIPS)':
 '2': CDS_PINID='\2\';
NODE_NAME     R161 1
 '@TIMECARD_LIB.TIMECARD(SCH_1):PAGE5_I165@PASSIVE.RESISTOR(CHIPS)':
 '1': CDS_PINID='\1\';
NET_NAME
'UNNAMED_5_24LC16BTISTTSSOP8_I_2'
 '@TIMECARD_LIB.TIMECARD(SCH_1):UNNAMED_5_24LC16BTISTTSSOP8_I151_A2':
 C_SIGNAL='@timecard_lib.timecard(sch_1):unnamed_5_24lc16btisttssop8_i151_a2';
NODE_NAME     U19 3
 '@TIMECARD_LIB.TIMECARD(SCH_1):PAGE5_I151@MEMORY.24LC16BT_I_ST_TSSOP8(CHIPS)':
 'A2': CDS_PINID='A2';
NODE_NAME     R162 2
 '@TIMECARD_LIB.TIMECARD(SCH_1):PAGE5_I161@PASSIVE.RESISTOR(CHIPS)':
 '2': CDS_PINID='\2\';
NODE_NAME     R163 1
 '@TIMECARD_LIB.TIMECARD(SCH_1):PAGE5_I166@PASSIVE.RESISTOR(CHIPS)':
 '1': CDS_PINID='\1\';
NET_NAME
'UNNAMED_5_CONNHDR2X2MSSMT_I126_'
 '@TIMECARD_LIB.TIMECARD(SCH_1):UNNAMED_5_CONNHDR2X2MSSMT_I126_1':
 C_SIGNAL='@timecard_lib.timecard(sch_1):unnamed_5_connhdr2x2mssmt_i126_1';
NODE_NAME     R58 1
 '@TIMECARD_LIB.TIMECARD(SCH_1):PAGE5_I88@PASSIVE.RESISTOR(CHIPS)':
 '1': CDS_PINID='\1\';
NODE_NAME     J9 1
 '@TIMECARD_LIB.TIMECARD(SCH_1):PAGE5_I126@CONNECTOR.CONN_HDR_2X2_M_S_SMT(CHIPS)':
 '1': CDS_PINID='\1\';
NET_NAME
'UNNAMED_5_CONNHDR2X2MSSMT_I12_1'
 '@TIMECARD_LIB.TIMECARD(SCH_1):UNNAMED_5_CONNHDR2X2MSSMT_I126_3':
 C_SIGNAL='@timecard_lib.timecard(sch_1):unnamed_5_connhdr2x2mssmt_i126_3';
NODE_NAME     R59 1
 '@TIMECARD_LIB.TIMECARD(SCH_1):PAGE5_I4@PASSIVE.RESISTOR(CHIPS)':
 '1': CDS_PINID='\1\';
NODE_NAME     J9 3
 '@TIMECARD_LIB.TIMECARD(SCH_1):PAGE5_I126@CONNECTOR.CONN_HDR_2X2_M_S_SMT(CHIPS)':
 '3': CDS_PINID='\3\';
NET_NAME
'UNNAMED_5_PCA9546APWTSSOP16_I33'
 '@TIMECARD_LIB.TIMECARD(SCH_1):UNNAMED_5_PCA9546APWTSSOP16_I33_A0':
 C_SIGNAL='@timecard_lib.timecard(sch_1):unnamed_5_pca9546apwtssop16_i33_a0';
NODE_NAME     U4 1
 '@TIMECARD_LIB.TIMECARD(SCH_1):PAGE5_I33@INTERFACE.PCA9546APW_TSSOP16(CHIPS)':
 'A0': CDS_PINID='A0';
NODE_NAME     R149 2
 '@TIMECARD_LIB.TIMECARD(SCH_1):PAGE5_I82@PASSIVE.RESISTOR(CHIPS)':
 '2': CDS_PINID='\2\';
NODE_NAME     R152 2
 '@TIMECARD_LIB.TIMECARD(SCH_1):PAGE5_I85@PASSIVE.RESISTOR(CHIPS)':
 '2': CDS_PINID='\2\';
NET_NAME
'UNNAMED_5_PCA9546APWTSSOP16_I_1'
 '@TIMECARD_LIB.TIMECARD(SCH_1):UNNAMED_5_PCA9546APWTSSOP16_I33_A1':
 C_SIGNAL='@timecard_lib.timecard(sch_1):unnamed_5_pca9546apwtssop16_i33_a1';
NODE_NAME     U4 2
 '@TIMECARD_LIB.TIMECARD(SCH_1):PAGE5_I33@INTERFACE.PCA9546APW_TSSOP16(CHIPS)':
 'A1': CDS_PINID='A1';
NODE_NAME     R150 2
 '@TIMECARD_LIB.TIMECARD(SCH_1):PAGE5_I83@PASSIVE.RESISTOR(CHIPS)':
 '2': CDS_PINID='\2\';
NODE_NAME     R153 2
 '@TIMECARD_LIB.TIMECARD(SCH_1):PAGE5_I86@PASSIVE.RESISTOR(CHIPS)':
 '2': CDS_PINID='\2\';
NET_NAME
'UNNAMED_5_PCA9546APWTSSOP16_I_2'
 '@TIMECARD_LIB.TIMECARD(SCH_1):UNNAMED_5_PCA9546APWTSSOP16_I33_A2':
 C_SIGNAL='@timecard_lib.timecard(sch_1):unnamed_5_pca9546apwtssop16_i33_a2';
NODE_NAME     U4 13
 '@TIMECARD_LIB.TIMECARD(SCH_1):PAGE5_I33@INTERFACE.PCA9546APW_TSSOP16(CHIPS)':
 'A2': CDS_PINID='A2';
NODE_NAME     R151 2
 '@TIMECARD_LIB.TIMECARD(SCH_1):PAGE5_I84@PASSIVE.RESISTOR(CHIPS)':
 '2': CDS_PINID='\2\';
NODE_NAME     R154 2
 '@TIMECARD_LIB.TIMECARD(SCH_1):PAGE5_I87@PASSIVE.RESISTOR(CHIPS)':
 '2': CDS_PINID='\2\';
NET_NAME
'UNNAMED_6_LM75BDPTSSOP8_I34_A0'
 '@TIMECARD_LIB.TIMECARD(SCH_1):UNNAMED_6_LM75BDPTSSOP8_I34_A0':
 C_SIGNAL='@timecard_lib.timecard(sch_1):unnamed_6_lm75bdptssop8_i34_a0';
NODE_NAME     R338 1
 '@TIMECARD_LIB.TIMECARD(SCH_1):PAGE6_I33@PASSIVE.RESISTOR(CHIPS)':
 '1': CDS_PINID='\1\';
NODE_NAME     U8 7
 '@TIMECARD_LIB.TIMECARD(SCH_1):PAGE6_I34@INTERFACE.LM75BDP_TSSOP8(CHIPS)':
 'A0': CDS_PINID='A0';
NODE_NAME     R337 2
 '@TIMECARD_LIB.TIMECARD(SCH_1):PAGE6_I36@PASSIVE.RESISTOR(CHIPS)':
 '2': CDS_PINID='\2\';
NET_NAME
'UNNAMED_6_LM75BDPTSSOP8_I34_A1'
 '@TIMECARD_LIB.TIMECARD(SCH_1):UNNAMED_6_LM75BDPTSSOP8_I34_A1':
 C_SIGNAL='@timecard_lib.timecard(sch_1):unnamed_6_lm75bdptssop8_i34_a1';
NODE_NAME     R336 1
 '@TIMECARD_LIB.TIMECARD(SCH_1):PAGE6_I32@PASSIVE.RESISTOR(CHIPS)':
 '1': CDS_PINID='\1\';
NODE_NAME     U8 6
 '@TIMECARD_LIB.TIMECARD(SCH_1):PAGE6_I34@INTERFACE.LM75BDP_TSSOP8(CHIPS)':
 'A1': CDS_PINID='A1';
NODE_NAME     R335 2
 '@TIMECARD_LIB.TIMECARD(SCH_1):PAGE6_I35@PASSIVE.RESISTOR(CHIPS)':
 '2': CDS_PINID='\2\';
NET_NAME
'UNNAMED_6_LM75BDPTSSOP8_I34_A2'
 '@TIMECARD_LIB.TIMECARD(SCH_1):UNNAMED_6_LM75BDPTSSOP8_I34_A2':
 C_SIGNAL='@timecard_lib.timecard(sch_1):unnamed_6_lm75bdptssop8_i34_a2';
NODE_NAME     R334 1
 '@TIMECARD_LIB.TIMECARD(SCH_1):PAGE6_I30@PASSIVE.RESISTOR(CHIPS)':
 '1': CDS_PINID='\1\';
NODE_NAME     R333 2
 '@TIMECARD_LIB.TIMECARD(SCH_1):PAGE6_I31@PASSIVE.RESISTOR(CHIPS)':
 '2': CDS_PINID='\2\';
NODE_NAME     U8 5
 '@TIMECARD_LIB.TIMECARD(SCH_1):PAGE6_I34@INTERFACE.LM75BDP_TSSOP8(CHIPS)':
 'A2': CDS_PINID='A2';
NET_NAME
'UNNAMED_6_LM75BDPTSSOP8_I59_A0'
 '@TIMECARD_LIB.TIMECARD(SCH_1):UNNAMED_6_LM75BDPTSSOP8_I59_A0':
 C_SIGNAL='@timecard_lib.timecard(sch_1):unnamed_6_lm75bdptssop8_i59_a0';
NODE_NAME     U35 7
 '@TIMECARD_LIB.TIMECARD(SCH_1):PAGE6_I59@INTERFACE.LM75BDP_TSSOP8(CHIPS)':
 'A0': CDS_PINID='A0';
NODE_NAME     R418 2
 '@TIMECARD_LIB.TIMECARD(SCH_1):PAGE6_I69@PASSIVE.RESISTOR(CHIPS)':
 '2': CDS_PINID='\2\';
NODE_NAME     R416 1
 '@TIMECARD_LIB.TIMECARD(SCH_1):PAGE6_I72@PASSIVE.RESISTOR(CHIPS)':
 '1': CDS_PINID='\1\';
NET_NAME
'UNNAMED_6_LM75BDPTSSOP8_I59_A1'
 '@TIMECARD_LIB.TIMECARD(SCH_1):UNNAMED_6_LM75BDPTSSOP8_I59_A1':
 C_SIGNAL='@timecard_lib.timecard(sch_1):unnamed_6_lm75bdptssop8_i59_a1';
NODE_NAME     U35 6
 '@TIMECARD_LIB.TIMECARD(SCH_1):PAGE6_I59@INTERFACE.LM75BDP_TSSOP8(CHIPS)':
 'A1': CDS_PINID='A1';
NODE_NAME     R413 1
 '@TIMECARD_LIB.TIMECARD(SCH_1):PAGE6_I60@PASSIVE.RESISTOR(CHIPS)':
 '1': CDS_PINID='\1\';
NODE_NAME     R412 2
 '@TIMECARD_LIB.TIMECARD(SCH_1):PAGE6_I70@PASSIVE.RESISTOR(CHIPS)':
 '2': CDS_PINID='\2\';
NET_NAME
'UNNAMED_6_LM75BDPTSSOP8_I59_A2'
 '@TIMECARD_LIB.TIMECARD(SCH_1):UNNAMED_6_LM75BDPTSSOP8_I59_A2':
 C_SIGNAL='@timecard_lib.timecard(sch_1):unnamed_6_lm75bdptssop8_i59_a2';
NODE_NAME     U35 5
 '@TIMECARD_LIB.TIMECARD(SCH_1):PAGE6_I59@INTERFACE.LM75BDP_TSSOP8(CHIPS)':
 'A2': CDS_PINID='A2';
NODE_NAME     R408 2
 '@TIMECARD_LIB.TIMECARD(SCH_1):PAGE6_I71@PASSIVE.RESISTOR(CHIPS)':
 '2': CDS_PINID='\2\';
NODE_NAME     R409 1
 '@TIMECARD_LIB.TIMECARD(SCH_1):PAGE6_I73@PASSIVE.RESISTOR(CHIPS)':
 '1': CDS_PINID='\1\';
NET_NAME
'UNNAMED_6_LM75BDPTSSOP8_I81_A0'
 '@TIMECARD_LIB.TIMECARD(SCH_1):UNNAMED_6_LM75BDPTSSOP8_I81_A0':
 C_SIGNAL='@timecard_lib.timecard(sch_1):unnamed_6_lm75bdptssop8_i81_a0';
NODE_NAME     U36 7
 '@TIMECARD_LIB.TIMECARD(SCH_1):PAGE6_I81@INTERFACE.LM75BDP_TSSOP8(CHIPS)':
 'A0': CDS_PINID='A0';
NODE_NAME     R419 2
 '@TIMECARD_LIB.TIMECARD(SCH_1):PAGE6_I84@PASSIVE.RESISTOR(CHIPS)':
 '2': CDS_PINID='\2\';
NODE_NAME     R417 1
 '@TIMECARD_LIB.TIMECARD(SCH_1):PAGE6_I93@PASSIVE.RESISTOR(CHIPS)':
 '1': CDS_PINID='\1\';
NET_NAME
'UNNAMED_6_LM75BDPTSSOP8_I81_A1'
 '@TIMECARD_LIB.TIMECARD(SCH_1):UNNAMED_6_LM75BDPTSSOP8_I81_A1':
 C_SIGNAL='@timecard_lib.timecard(sch_1):unnamed_6_lm75bdptssop8_i81_a1';
NODE_NAME     U36 6
 '@TIMECARD_LIB.TIMECARD(SCH_1):PAGE6_I81@INTERFACE.LM75BDP_TSSOP8(CHIPS)':
 'A1': CDS_PINID='A1';
NODE_NAME     R414 2
 '@TIMECARD_LIB.TIMECARD(SCH_1):PAGE6_I85@PASSIVE.RESISTOR(CHIPS)':
 '2': CDS_PINID='\2\';
NODE_NAME     R415 1
 '@TIMECARD_LIB.TIMECARD(SCH_1):PAGE6_I94@PASSIVE.RESISTOR(CHIPS)':
 '1': CDS_PINID='\1\';
NET_NAME
'UNNAMED_6_LM75BDPTSSOP8_I81_A2'
 '@TIMECARD_LIB.TIMECARD(SCH_1):UNNAMED_6_LM75BDPTSSOP8_I81_A2':
 C_SIGNAL='@timecard_lib.timecard(sch_1):unnamed_6_lm75bdptssop8_i81_a2';
NODE_NAME     U36 5
 '@TIMECARD_LIB.TIMECARD(SCH_1):PAGE6_I81@INTERFACE.LM75BDP_TSSOP8(CHIPS)':
 'A2': CDS_PINID='A2';
NODE_NAME     R410 2
 '@TIMECARD_LIB.TIMECARD(SCH_1):PAGE6_I86@PASSIVE.RESISTOR(CHIPS)':
 '2': CDS_PINID='\2\';
NODE_NAME     R411 1
 '@TIMECARD_LIB.TIMECARD(SCH_1):PAGE6_I95@PASSIVE.RESISTOR(CHIPS)':
 '1': CDS_PINID='\1\';
NET_NAME
'UNNAMED_8_ICP10100LGA10_I24_RES'
 '@TIMECARD_LIB.TIMECARD(SCH_1):UNNAMED_8_ICP10100LGA10_I24_RESV1':
 C_SIGNAL='@timecard_lib.timecard(sch_1):unnamed_8_icp10100lga10_i24_resv1';
NODE_NAME     U28 1
 '@TIMECARD_LIB.TIMECARD(SCH_1):PAGE8_I24@ANALOG.ICP_10100_LGA10(CHIPS)':
 'RESV_1': CDS_PINID='RESV_1';
NODE_NAME     R343 1
 '@TIMECARD_LIB.TIMECARD(SCH_1):PAGE8_I34@PASSIVE.RESISTOR(CHIPS)':
 '1': CDS_PINID='\1\';
NET_NAME
'UNNAMED_8_ICP10100LGA10_I24_R_1'
 '@TIMECARD_LIB.TIMECARD(SCH_1):UNNAMED_8_ICP10100LGA10_I24_RESV2':
 C_SIGNAL='@timecard_lib.timecard(sch_1):unnamed_8_icp10100lga10_i24_resv2';
NODE_NAME     U28 3
 '@TIMECARD_LIB.TIMECARD(SCH_1):PAGE8_I24@ANALOG.ICP_10100_LGA10(CHIPS)':
 'RESV_2': CDS_PINID='RESV_2';
NODE_NAME     R346 1
 '@TIMECARD_LIB.TIMECARD(SCH_1):PAGE8_I33@PASSIVE.RESISTOR(CHIPS)':
 '1': CDS_PINID='\1\';
NET_NAME
'UNNAMED_8_ICP10100LGA10_I24_R_2'
 '@TIMECARD_LIB.TIMECARD(SCH_1):UNNAMED_8_ICP10100LGA10_I24_RESV3':
 C_SIGNAL='@timecard_lib.timecard(sch_1):unnamed_8_icp10100lga10_i24_resv3';
NODE_NAME     U28 5
 '@TIMECARD_LIB.TIMECARD(SCH_1):PAGE8_I24@ANALOG.ICP_10100_LGA10(CHIPS)':
 'RESV_3': CDS_PINID='RESV_3';
NODE_NAME     R347 1
 '@TIMECARD_LIB.TIMECARD(SCH_1):PAGE8_I32@PASSIVE.RESISTOR(CHIPS)':
 '1': CDS_PINID='\1\';
NET_NAME
'UNNAMED_8_ICP10100LGA10_I24_R_3'
 '@TIMECARD_LIB.TIMECARD(SCH_1):UNNAMED_8_ICP10100LGA10_I24_RESV4':
 C_SIGNAL='@timecard_lib.timecard(sch_1):unnamed_8_icp10100lga10_i24_resv4';
NODE_NAME     U28 6
 '@TIMECARD_LIB.TIMECARD(SCH_1):PAGE8_I24@ANALOG.ICP_10100_LGA10(CHIPS)':
 'RESV_4': CDS_PINID='RESV_4';
NODE_NAME     R350 1
 '@TIMECARD_LIB.TIMECARD(SCH_1):PAGE8_I31@PASSIVE.RESISTOR(CHIPS)':
 '1': CDS_PINID='\1\';
NET_NAME
'UNNAMED_8_ICP10100LGA10_I24_R_4'
 '@TIMECARD_LIB.TIMECARD(SCH_1):UNNAMED_8_ICP10100LGA10_I24_RESV5':
 C_SIGNAL='@timecard_lib.timecard(sch_1):unnamed_8_icp10100lga10_i24_resv5';
NODE_NAME     U28 7
 '@TIMECARD_LIB.TIMECARD(SCH_1):PAGE8_I24@ANALOG.ICP_10100_LGA10(CHIPS)':
 'RESV_5': CDS_PINID='RESV_5';
NODE_NAME     R351 1
 '@TIMECARD_LIB.TIMECARD(SCH_1):PAGE8_I30@PASSIVE.RESISTOR(CHIPS)':
 '1': CDS_PINID='\1\';
NET_NAME
'UNNAMED_8_PCA9508DPTSSOP8_I51_E'
 '@TIMECARD_LIB.TIMECARD(SCH_1):UNNAMED_8_PCA9508DPTSSOP8_I51_EN':
 C_SIGNAL='@timecard_lib.timecard(sch_1):unnamed_8_pca9508dptssop8_i51_en';
NODE_NAME     U32 5
 '@TIMECARD_LIB.TIMECARD(SCH_1):PAGE8_I51@STDLOGIC.PCA9508DP_TSSOP8(CHIPS)':
 'EN': CDS_PINID='EN';
NODE_NAME     R314 2
 '@TIMECARD_LIB.TIMECARD(SCH_1):PAGE8_I71@PASSIVE.RESISTOR(CHIPS)':
 '2': CDS_PINID='\2\';
NET_NAME
'UNNAMED_9_BNO080LGA28_I29_CAP'
 '@TIMECARD_LIB.TIMECARD(SCH_1):UNNAMED_9_BNO080LGA28_I29_CAP':
 C_SIGNAL='@timecard_lib.timecard(sch_1):unnamed_9_bno080lga28_i29_cap';
NODE_NAME     U29 9
 '@TIMECARD_LIB.TIMECARD(SCH_1):PAGE9_I29@LSI.BNO080_LGA_28(CHIPS)':
 'CAP': CDS_PINID='CAP';
NODE_NAME     C285 1
 '@TIMECARD_LIB.TIMECARD(SCH_1):PAGE9_I53@PASSIVE.CAPACITOR(CHIPS)':
 '1': CDS_PINID='\1\';
NET_NAME
'UNNAMED_9_BNO080LGA28_I29_CLKSE'
 '@TIMECARD_LIB.TIMECARD(SCH_1):UNNAMED_9_BNO080LGA28_I29_CLKSEL0':
 C_SIGNAL='@timecard_lib.timecard(sch_1):unnamed_9_bno080lga28_i29_clksel0';
NODE_NAME     U29 10
 '@TIMECARD_LIB.TIMECARD(SCH_1):PAGE9_I29@LSI.BNO080_LGA_28(CHIPS)':
 'CLKSEL0': CDS_PINID='CLKSEL0';
NODE_NAME     R307 1
 '@TIMECARD_LIB.TIMECARD(SCH_1):PAGE9_I47@PASSIVE.RESISTOR(CHIPS)':
 '1': CDS_PINID='\1\';
NODE_NAME     R306 2
 '@TIMECARD_LIB.TIMECARD(SCH_1):PAGE9_I55@PASSIVE.RESISTOR(CHIPS)':
 '2': CDS_PINID='\2\';
NET_NAME
'UNNAMED_9_BNO080LGA28_I29_HCS'
 '@TIMECARD_LIB.TIMECARD(SCH_1):UNNAMED_9_BNO080LGA28_I29_HCS':
 C_SIGNAL='@timecard_lib.timecard(sch_1):unnamed_9_bno080lga28_i29_hcs';
NODE_NAME     U29 18
 '@TIMECARD_LIB.TIMECARD(SCH_1):PAGE9_I29@LSI.BNO080_LGA_28(CHIPS)':
 'H_CS*': CDS_PINID='\h_cs*\';
NODE_NAME     TP61 1
 '@TIMECARD_LIB.TIMECARD(SCH_1):PAGE9_I63@CLS.TP_PIONT(CHIPS)':
 '1': CDS_PINID='\1\';
NET_NAME
'UNNAMED_9_BNO080LGA28_I29_PS0'
 '@TIMECARD_LIB.TIMECARD(SCH_1):UNNAMED_9_BNO080LGA28_I29_PS0':
 C_SIGNAL='@timecard_lib.timecard(sch_1):unnamed_9_bno080lga28_i29_ps0';
NODE_NAME     U29 6
 '@TIMECARD_LIB.TIMECARD(SCH_1):PAGE9_I29@LSI.BNO080_LGA_28(CHIPS)':
 'PS0/WAKE': CDS_PINID='\ps0/wake\';
NODE_NAME     R305 1
 '@TIMECARD_LIB.TIMECARD(SCH_1):PAGE9_I49@PASSIVE.RESISTOR(CHIPS)':
 '1': CDS_PINID='\1\';
NET_NAME
'UNNAMED_9_BNO080LGA28_I29_PS1'
 '@TIMECARD_LIB.TIMECARD(SCH_1):UNNAMED_9_BNO080LGA28_I29_PS1':
 C_SIGNAL='@timecard_lib.timecard(sch_1):unnamed_9_bno080lga28_i29_ps1';
NODE_NAME     U29 5
 '@TIMECARD_LIB.TIMECARD(SCH_1):PAGE9_I29@LSI.BNO080_LGA_28(CHIPS)':
 'PS1': CDS_PINID='PS1';
NODE_NAME     R303 1
 '@TIMECARD_LIB.TIMECARD(SCH_1):PAGE9_I50@PASSIVE.RESISTOR(CHIPS)':
 '1': CDS_PINID='\1\';
NET_NAME
'UNNAMED_9_BNO080LGA28_I29_XOUT3'
 '@TIMECARD_LIB.TIMECARD(SCH_1):UNNAMED_9_BNO080LGA28_I29_XOUT32':
 C_SIGNAL='@timecard_lib.timecard(sch_1):unnamed_9_bno080lga28_i29_xout32';
NODE_NAME     Y1 1
 '@TIMECARD_LIB.TIMECARD(SCH_1):PAGE9_I16@CLOCK.XTAL_2(CHIPS)':
 '1': CDS_PINID='\1\';
NODE_NAME     U29 26
 '@TIMECARD_LIB.TIMECARD(SCH_1):PAGE9_I29@LSI.BNO080_LGA_28(CHIPS)':
 'XOUT32/CLKSEL1': CDS_PINID='\xout32/clksel1\';
NODE_NAME     C47 1
 '@TIMECARD_LIB.TIMECARD(SCH_1):PAGE9_I54@PASSIVE.CAPACITOR(CHIPS)':
 '1': CDS_PINID='\1\';
NODE_NAME     R168 2
 '@TIMECARD_LIB.TIMECARD(SCH_1):PAGE9_I70@PASSIVE.RESISTOR(CHIPS)':
 '2': CDS_PINID='\2\';
NET_NAME
'UNNAMED_9_CAPACITOR_I17_1'
 '@TIMECARD_LIB.TIMECARD(SCH_1):UNNAMED_9_CAPACITOR_I17_1':
 C_SIGNAL='@timecard_lib.timecard(sch_1):unnamed_9_capacitor_i17_1';
NODE_NAME     Y1 2
 '@TIMECARD_LIB.TIMECARD(SCH_1):PAGE9_I16@CLOCK.XTAL_2(CHIPS)':
 '2': CDS_PINID='\2\';
NODE_NAME     C51 1
 '@TIMECARD_LIB.TIMECARD(SCH_1):PAGE9_I17@PASSIVE.CAPACITOR(CHIPS)':
 '1': CDS_PINID='\1\';
NODE_NAME     U29 27
 '@TIMECARD_LIB.TIMECARD(SCH_1):PAGE9_I29@LSI.BNO080_LGA_28(CHIPS)':
 'XIN32': CDS_PINID='XIN32';
NODE_NAME     R168 1
 '@TIMECARD_LIB.TIMECARD(SCH_1):PAGE9_I70@PASSIVE.RESISTOR(CHIPS)':
 '1': CDS_PINID='\1\';
NET_NAME
'USB_PWR_EN'
 '@TIMECARD_LIB.TIMECARD(SCH_1):USB_PWR_EN':
 C_SIGNAL='@timecard_lib.timecard(sch_1):usb_pwr_en';
NODE_NAME     C69 1
 '@TIMECARD_LIB.TIMECARD(SCH_1):PAGE527_I74@PASSIVE.CAPACITOR(CHIPS)':
 '1': CDS_PINID='\1\';
NODE_NAME     U12 4
 '@TIMECARD_LIB.TIMECARD(SCH_1):PAGE527_I79@STDLOGIC.TPS2051BDBVT_SOT23_5(CHIPS)':
 'EN': CDS_PINID='EN';
NODE_NAME     U10 4
 '@TIMECARD_LIB.TIMECARD(SCH_1):PAGE527_I147@STDLOGIC.CL5003148A(CHIPS)':
 'Y': CDS_PINID='Y';
NODE_NAME     R100 2
 '@TIMECARD_LIB.TIMECARD(SCH_1):PAGE527_I155@PASSIVE.RESISTOR(CHIPS)':
 '2': CDS_PINID='\2\';
NODE_NAME     Q2 1
 '@TIMECARD_LIB.TIMECARD(SCH_1):PAGE527_I232@DISCRETE.POWERMOS_3P_NCH_V1(CHIPS)':
 'G': CDS_PINID='G';
NET_NAME
'VDD3V3_OSC_125M'
 '@TIMECARD_LIB.TIMECARD(SCH_1):VDD3V3_OSC_125M':
 C_SIGNAL='@timecard_lib.timecard(sch_1):vdd3v3_osc_125m';
NODE_NAME     Y4 6
 '@TIMECARD_LIB.TIMECARD(SCH_1):PAGE522_I145@CLOCK.OSC6P_V2(CHIPS)':
 'VDD': CDS_PINID='VDD';
NODE_NAME     C247 1
 '@TIMECARD_LIB.TIMECARD(SCH_1):PAGE522_I154@PASSIVE.CAPACITOR(CHIPS)':
 '1': CDS_PINID='\1\';
NODE_NAME     R236 1
 '@TIMECARD_LIB.TIMECARD(SCH_1):PAGE522_I156@PASSIVE.RESISTOR(CHIPS)':
 '1': CDS_PINID='\1\';
NODE_NAME     C249 1
 '@TIMECARD_LIB.TIMECARD(SCH_1):PAGE522_I158@PASSIVE.CAPACITOR(CHIPS)':
 '1': CDS_PINID='\1\';
NODE_NAME     L10 1
 '@TIMECARD_LIB.TIMECARD(SCH_1):PAGE522_I159@PASSIVE.FERRITEBEAD(CHIPS)':
 '1': CDS_PINID='\1\';
NET_NAME
'VDD3V3_OSC_200M'
 '@TIMECARD_LIB.TIMECARD(SCH_1):VDD3V3_OSC_200M':
 C_SIGNAL='@timecard_lib.timecard(sch_1):vdd3v3_osc_200m';
NODE_NAME     Y3 6
 '@TIMECARD_LIB.TIMECARD(SCH_1):PAGE522_I144@CLOCK.OSC6P_V2(CHIPS)':
 'VDD': CDS_PINID='VDD';
NODE_NAME     L14 1
 '@TIMECARD_LIB.TIMECARD(SCH_1):PAGE522_I146@PASSIVE.FERRITEBEAD(CHIPS)':
 '1': CDS_PINID='\1\';
NODE_NAME     C248 1
 '@TIMECARD_LIB.TIMECARD(SCH_1):PAGE522_I147@PASSIVE.CAPACITOR(CHIPS)':
 '1': CDS_PINID='\1\';
NODE_NAME     R235 1
 '@TIMECARD_LIB.TIMECARD(SCH_1):PAGE522_I149@PASSIVE.RESISTOR(CHIPS)':
 '1': CDS_PINID='\1\';
NODE_NAME     C246 1
 '@TIMECARD_LIB.TIMECARD(SCH_1):PAGE522_I151@PASSIVE.CAPACITOR(CHIPS)':
 '1': CDS_PINID='\1\';
NET_NAME
'VDD3V3_SHT31A'
 '@TIMECARD_LIB.TIMECARD(SCH_1):VDD3V3_SHT31A':
 C_SIGNAL='@timecard_lib.timecard(sch_1):vdd3v3_sht31a';
NODE_NAME     C275 1
 '@TIMECARD_LIB.TIMECARD(SCH_1):PAGE7_I19@PASSIVE.CAPACITOR(CHIPS)':
 '1': CDS_PINID='\1\';
NODE_NAME     L17 2
 '@TIMECARD_LIB.TIMECARD(SCH_1):PAGE7_I21@PASSIVE.FERRITEBEAD(CHIPS)':
 '2': CDS_PINID='\2\';
NODE_NAME     C274 1
 '@TIMECARD_LIB.TIMECARD(SCH_1):PAGE7_I23@PASSIVE.CAPACITOR(CHIPS)':
 '1': CDS_PINID='\1\';
NODE_NAME     U27 5
 '@TIMECARD_LIB.TIMECARD(SCH_1):PAGE7_I44@ANALOG.SHT31A_DIS_B10KS_DFN8(CHIPS)':
 'VDD': CDS_PINID='VDD';
NET_NAME
'VDD_BNO085'
 '@TIMECARD_LIB.TIMECARD(SCH_1):VDD_BNO085':
 C_SIGNAL='@timecard_lib.timecard(sch_1):vdd_bno085';
NODE_NAME     L19 1
 '@TIMECARD_LIB.TIMECARD(SCH_1):PAGE9_I22@PASSIVE.FERRITEBEAD(CHIPS)':
 '1': CDS_PINID='\1\';
NODE_NAME     C280 1
 '@TIMECARD_LIB.TIMECARD(SCH_1):PAGE9_I23@PASSIVE.CAPACITOR(CHIPS)':
 '1': CDS_PINID='\1\';
NODE_NAME     C281 1
 '@TIMECARD_LIB.TIMECARD(SCH_1):PAGE9_I24@PASSIVE.CAPACITOR(CHIPS)':
 '1': CDS_PINID='\1\';
NODE_NAME     U29 3
 '@TIMECARD_LIB.TIMECARD(SCH_1):PAGE9_I29@LSI.BNO080_LGA_28(CHIPS)':
 'VDD': CDS_PINID='VDD';
NODE_NAME     U29 28
 '@TIMECARD_LIB.TIMECARD(SCH_1):PAGE9_I29@LSI.BNO080_LGA_28(CHIPS)':
 'VDDIO': CDS_PINID='VDDIO';
NET_NAME
'VDD_PCA9546A'
 '@TIMECARD_LIB.TIMECARD(SCH_1):VDD_PCA9546A':
 C_SIGNAL='@timecard_lib.timecard(sch_1):vdd_pca9546a';
NODE_NAME     C38 1
 '@TIMECARD_LIB.TIMECARD(SCH_1):PAGE5_I45@PASSIVE.CAPACITOR(CHIPS)':
 '1': CDS_PINID='\1\';
NODE_NAME     R61 1
 '@TIMECARD_LIB.TIMECARD(SCH_1):PAGE5_I52@PASSIVE.RESISTOR(CHIPS)':
 '1': CDS_PINID='\1\';
NODE_NAME     U4 16
 '@TIMECARD_LIB.TIMECARD(SCH_1):PAGE5_I54@INTERFACE.PCA9546APW_TSSOP16(CHIPS)':
 'VDD': CDS_PINID='VDD';
NODE_NAME     R62 1
 '@TIMECARD_LIB.TIMECARD(SCH_1):PAGE5_I55@PASSIVE.RESISTOR(CHIPS)':
 '1': CDS_PINID='\1\';
NET_NAME
'VIN_XP1R0V'
 '@TIMECARD_LIB.TIMECARD(SCH_1):VIN_XP1R0V':
 C_SIGNAL='@timecard_lib.timecard(sch_1):vin_xp1r0v';
NODE_NAME     U26 2
 '@TIMECARD_LIB.TIMECARD(SCH_1):PAGE523_I11@STDLOGIC.TPS54824RNVR_VQFN18(CHIPS)':
 'VIN_1': CDS_PINID='VIN_1';
NODE_NAME     U26 11
 '@TIMECARD_LIB.TIMECARD(SCH_1):PAGE523_I11@STDLOGIC.TPS54824RNVR_VQFN18(CHIPS)':
 'VIN_2': CDS_PINID='VIN_2';
NODE_NAME     C257 1
 '@TIMECARD_LIB.TIMECARD(SCH_1):PAGE523_I13@PASSIVE.CAPACITOR(CHIPS)':
 '1': CDS_PINID='\1\';
NODE_NAME     C260 1
 '@TIMECARD_LIB.TIMECARD(SCH_1):PAGE523_I14@PASSIVE.CAPACITOR(CHIPS)':
 '1': CDS_PINID='\1\';
NODE_NAME     C261 1
 '@TIMECARD_LIB.TIMECARD(SCH_1):PAGE523_I17@PASSIVE.CAPACITOR(CHIPS)':
 '1': CDS_PINID='\1\';
NODE_NAME     C262 1
 '@TIMECARD_LIB.TIMECARD(SCH_1):PAGE523_I19@PASSIVE.CAPACITOR(CHIPS)':
 '1': CDS_PINID='\1\';
NODE_NAME     L9 2
 '@TIMECARD_LIB.TIMECARD(SCH_1):PAGE523_I48@PASSIVE.FERRITEBEAD(CHIPS)':
 '2': CDS_PINID='\2\';
NODE_NAME     R247 1
 '@TIMECARD_LIB.TIMECARD(SCH_1):PAGE523_I54@PASSIVE.RESISTOR(CHIPS)':
 '1': CDS_PINID='\1\';
NET_NAME
'VIN_XP3R3'
 '@TIMECARD_LIB.TIMECARD(SCH_1):VIN_XP3R3':
 C_SIGNAL='@timecard_lib.timecard(sch_1):vin_xp3r3';
NODE_NAME     L8 2
 '@TIMECARD_LIB.TIMECARD(SCH_1):PAGE517_I7@PASSIVE.FERRITEBEAD(CHIPS)':
 '2': CDS_PINID='\2\';
NODE_NAME     R53 1
 '@TIMECARD_LIB.TIMECARD(SCH_1):PAGE517_I13@PASSIVE.RESISTOR(CHIPS)':
 '1': CDS_PINID='\1\';
NODE_NAME     C48 1
 '@TIMECARD_LIB.TIMECARD(SCH_1):PAGE517_I14@PASSIVE.CAPACITOR(CHIPS)':
 '1': CDS_PINID='\1\';
NODE_NAME     C50 1
 '@TIMECARD_LIB.TIMECARD(SCH_1):PAGE517_I15@PASSIVE.CAPACITOR(CHIPS)':
 '1': CDS_PINID='\1\';
NODE_NAME     C52 1
 '@TIMECARD_LIB.TIMECARD(SCH_1):PAGE517_I16@PASSIVE.CAPACITOR(CHIPS)':
 '1': CDS_PINID='\1\';
NODE_NAME     C53 1
 '@TIMECARD_LIB.TIMECARD(SCH_1):PAGE517_I21@PASSIVE.CAPACITOR(CHIPS)':
 '1': CDS_PINID='\1\';
NODE_NAME     U6 2
 '@TIMECARD_LIB.TIMECARD(SCH_1):PAGE517_I42@STDLOGIC.TPS54824RNVR_VQFN18(CHIPS)':
 'VIN_1': CDS_PINID='VIN_1';
NODE_NAME     U6 11
 '@TIMECARD_LIB.TIMECARD(SCH_1):PAGE517_I42@STDLOGIC.TPS54824RNVR_VQFN18(CHIPS)':
 'VIN_2': CDS_PINID='VIN_2';
NET_NAME
'VIN_XP5R0V'
 '@TIMECARD_LIB.TIMECARD(SCH_1):VIN_XP5R0V':
 C_SIGNAL='@timecard_lib.timecard(sch_1):vin_xp5r0v';
NODE_NAME     R49 1
 '@TIMECARD_LIB.TIMECARD(SCH_1):PAGE516_I16@PASSIVE.RESISTOR(CHIPS)':
 '1': CDS_PINID='\1\';
NODE_NAME     L7 2
 '@TIMECARD_LIB.TIMECARD(SCH_1):PAGE516_I17@PASSIVE.FERRITEBEAD(CHIPS)':
 '2': CDS_PINID='\2\';
NODE_NAME     C30 1
 '@TIMECARD_LIB.TIMECARD(SCH_1):PAGE516_I18@PASSIVE.CAPACITOR(CHIPS)':
 '1': CDS_PINID='\1\';
NODE_NAME     C32 1
 '@TIMECARD_LIB.TIMECARD(SCH_1):PAGE516_I19@PASSIVE.CAPACITOR(CHIPS)':
 '1': CDS_PINID='\1\';
NODE_NAME     C33 1
 '@TIMECARD_LIB.TIMECARD(SCH_1):PAGE516_I20@PASSIVE.CAPACITOR(CHIPS)':
 '1': CDS_PINID='\1\';
NODE_NAME     C41 1
 '@TIMECARD_LIB.TIMECARD(SCH_1):PAGE516_I22@PASSIVE.CAPACITOR(CHIPS)':
 '1': CDS_PINID='\1\';
NODE_NAME     U5 2
 '@TIMECARD_LIB.TIMECARD(SCH_1):PAGE516_I42@STDLOGIC.TPS54824RNVR_VQFN18(CHIPS)':
 'VIN_1': CDS_PINID='VIN_1';
NODE_NAME     U5 11
 '@TIMECARD_LIB.TIMECARD(SCH_1):PAGE516_I42@STDLOGIC.TPS54824RNVR_VQFN18(CHIPS)':
 'VIN_2': CDS_PINID='VIN_2';
NET_NAME
'XP12R0V'
 '@TIMECARD_LIB.TIMECARD(SCH_1):XP12R0V':
 C_SIGNAL='@timecard_lib.timecard(sch_1):xp12r0v',
 CDS_GLOBAL_NET='TRUE';
NODE_NAME     C76 1
 '@TIMECARD_LIB.TIMECARD(SCH_1):PAGE517_I6@PASSIVE.CAPACITOR(CHIPS)':
 '1': CDS_PINID='\1\';
NODE_NAME     L8 1
 '@TIMECARD_LIB.TIMECARD(SCH_1):PAGE517_I7@PASSIVE.FERRITEBEAD(CHIPS)':
 '1': CDS_PINID='\1\';
NODE_NAME     C74 1
 '@TIMECARD_LIB.TIMECARD(SCH_1):PAGE516_I4@PASSIVE.CAPACITOR(CHIPS)':
 '1': CDS_PINID='\1\';
NODE_NAME     L7 1
 '@TIMECARD_LIB.TIMECARD(SCH_1):PAGE516_I17@PASSIVE.FERRITEBEAD(CHIPS)':
 '1': CDS_PINID='\1\';
NODE_NAME     R13 1
 '@TIMECARD_LIB.TIMECARD(SCH_1):PAGE15_I202@PASSIVE.RESISTOR(CHIPS)':
 '1': CDS_PINID='\1\';
NODE_NAME     R15 1
 '@TIMECARD_LIB.TIMECARD(SCH_1):PAGE15_I203@PASSIVE.RESISTOR(CHIPS)':
 '1': CDS_PINID='\1\';
NODE_NAME     CR3 C
 '@TIMECARD_LIB.TIMECARD(SCH_1):PAGE15_I204@DISCRETE.DIODE_2(CHIPS)':
 'C': CDS_PINID='C';
NODE_NAME     C9 1
 '@TIMECARD_LIB.TIMECARD(SCH_1):PAGE15_I206@PASSIVE.CAPACITOR(CHIPS)':
 '1': CDS_PINID='\1\';
NODE_NAME     C10 1
 '@TIMECARD_LIB.TIMECARD(SCH_1):PAGE15_I207@PASSIVE.CAPACITOR(CHIPS)':
 '1': CDS_PINID='\1\';
NODE_NAME     U1 13
 '@TIMECARD_LIB.TIMECARD(SCH_1):PAGE15_I212@STDLOGIC.MP5022CGQV_Z_QFN22(CHIPS)':
 'VOUT_1': CDS_PINID='VOUT_1';
NODE_NAME     U1 14
 '@TIMECARD_LIB.TIMECARD(SCH_1):PAGE15_I212@STDLOGIC.MP5022CGQV_Z_QFN22(CHIPS)':
 'VOUT_2': CDS_PINID='VOUT_2';
NODE_NAME     U1 15
 '@TIMECARD_LIB.TIMECARD(SCH_1):PAGE15_I212@STDLOGIC.MP5022CGQV_Z_QFN22(CHIPS)':
 'VOUT_3': CDS_PINID='VOUT_3';
NODE_NAME     U1 16
 '@TIMECARD_LIB.TIMECARD(SCH_1):PAGE15_I212@STDLOGIC.MP5022CGQV_Z_QFN22(CHIPS)':
 'VOUT_4': CDS_PINID='VOUT_4';
NODE_NAME     U1 17
 '@TIMECARD_LIB.TIMECARD(SCH_1):PAGE15_I212@STDLOGIC.MP5022CGQV_Z_QFN22(CHIPS)':
 'VOUT_5': CDS_PINID='VOUT_5';
NODE_NAME     U1 18
 '@TIMECARD_LIB.TIMECARD(SCH_1):PAGE15_I212@STDLOGIC.MP5022CGQV_Z_QFN22(CHIPS)':
 'VOUT_6': CDS_PINID='VOUT_6';
NODE_NAME     U1 19
 '@TIMECARD_LIB.TIMECARD(SCH_1):PAGE15_I212@STDLOGIC.MP5022CGQV_Z_QFN22(CHIPS)':
 'VOUT_7': CDS_PINID='VOUT_7';
NODE_NAME     U1 20
 '@TIMECARD_LIB.TIMECARD(SCH_1):PAGE15_I212@STDLOGIC.MP5022CGQV_Z_QFN22(CHIPS)':
 'VOUT_8': CDS_PINID='VOUT_8';
NODE_NAME     C255 1
 '@TIMECARD_LIB.TIMECARD(SCH_1):PAGE523_I46@PASSIVE.CAPACITOR(CHIPS)':
 '1': CDS_PINID='\1\';
NODE_NAME     L9 1
 '@TIMECARD_LIB.TIMECARD(SCH_1):PAGE523_I48@PASSIVE.FERRITEBEAD(CHIPS)':
 '1': CDS_PINID='\1\';
NODE_NAME     FU1 2
 '@TIMECARD_LIB.TIMECARD(SCH_1):PAGE15_I223@PASSIVE.FUSE(CHIPS)':
 '2': CDS_PINID='\2\';
NODE_NAME     R262 2
 '@TIMECARD_LIB.TIMECARD(SCH_1):PAGE14_I66@PASSIVE.RESISTOR(CHIPS)':
 '2': CDS_PINID='\2\';
NODE_NAME     TP52 1
 '@TIMECARD_LIB.TIMECARD(SCH_1):PAGE16_I1206@CLS.TP_PIONT(CHIPS)':
 '1': CDS_PINID='\1\';
NET_NAME
'XP12R0V_A_AVIN'
 '@TIMECARD_LIB.TIMECARD(SCH_1):XP12R0V_A_AVIN':
 C_SIGNAL='@timecard_lib.timecard(sch_1):xp12r0v_a_avin';
NODE_NAME     C6 1
 '@TIMECARD_LIB.TIMECARD(SCH_1):PAGE15_I196@PASSIVE.CAPACITOR(CHIPS)':
 '1': CDS_PINID='\1\';
NODE_NAME     R9 2
 '@TIMECARD_LIB.TIMECARD(SCH_1):PAGE15_I198@PASSIVE.RESISTOR(CHIPS)':
 '2': CDS_PINID='\2\';
NODE_NAME     U1 12
 '@TIMECARD_LIB.TIMECARD(SCH_1):PAGE15_I212@STDLOGIC.MP5022CGQV_Z_QFN22(CHIPS)':
 'AVIN': CDS_PINID='AVIN';
NET_NAME
'XP12R0V_A_EN'
 '@TIMECARD_LIB.TIMECARD(SCH_1):XP12R0V_A_EN':
 C_SIGNAL='@timecard_lib.timecard(sch_1):xp12r0v_a_en';
NODE_NAME     C3 1
 '@TIMECARD_LIB.TIMECARD(SCH_1):PAGE15_I156@PASSIVE.CAPACITOR(CHIPS)':
 '1': CDS_PINID='\1\';
NODE_NAME     R5 1
 '@TIMECARD_LIB.TIMECARD(SCH_1):PAGE15_I169@PASSIVE.RESISTOR(CHIPS)':
 '1': CDS_PINID='\1\';
NODE_NAME     R4 2
 '@TIMECARD_LIB.TIMECARD(SCH_1):PAGE15_I170@PASSIVE.RESISTOR(CHIPS)':
 '2': CDS_PINID='\2\';
NODE_NAME     U1 1
 '@TIMECARD_LIB.TIMECARD(SCH_1):PAGE15_I212@STDLOGIC.MP5022CGQV_Z_QFN22(CHIPS)':
 'EN': CDS_PINID='EN';
NODE_NAME     TP43 1
 '@TIMECARD_LIB.TIMECARD(SCH_1):PAGE16_I1691@CLS.TP_PIONT(CHIPS)':
 '1': CDS_PINID='\1\';
NET_NAME
'XP12R0V_A_FLTB'
 '@TIMECARD_LIB.TIMECARD(SCH_1):XP12R0V_A_FLTB':
 C_SIGNAL='@timecard_lib.timecard(sch_1):xp12r0v_a_fltb';
NODE_NAME     R16 1
 '@TIMECARD_LIB.TIMECARD(SCH_1):PAGE15_I188@PASSIVE.RESISTOR(CHIPS)':
 '1': CDS_PINID='\1\';
NODE_NAME     R15 2
 '@TIMECARD_LIB.TIMECARD(SCH_1):PAGE15_I203@PASSIVE.RESISTOR(CHIPS)':
 '2': CDS_PINID='\2\';
NODE_NAME     U1 9
 '@TIMECARD_LIB.TIMECARD(SCH_1):PAGE15_I212@STDLOGIC.MP5022CGQV_Z_QFN22(CHIPS)':
 'FLTB': CDS_PINID='FLTB';
NODE_NAME     TP37 1
 '@TIMECARD_LIB.TIMECARD(SCH_1):PAGE16_I1682@CLS.TP_PIONT(CHIPS)':
 '1': CDS_PINID='\1\';
NET_NAME
'XP12R0V_A_IMON'
 '@TIMECARD_LIB.TIMECARD(SCH_1):XP12R0V_A_IMON':
 C_SIGNAL='@timecard_lib.timecard(sch_1):xp12r0v_a_imon';
NODE_NAME     R10 1
 '@TIMECARD_LIB.TIMECARD(SCH_1):PAGE15_I183@PASSIVE.RESISTOR(CHIPS)':
 '1': CDS_PINID='\1\';
NODE_NAME     C7 1
 '@TIMECARD_LIB.TIMECARD(SCH_1):PAGE15_I185@PASSIVE.CAPACITOR(CHIPS)':
 '1': CDS_PINID='\1\';
NODE_NAME     U1 8
 '@TIMECARD_LIB.TIMECARD(SCH_1):PAGE15_I212@STDLOGIC.MP5022CGQV_Z_QFN22(CHIPS)':
 'IMON': CDS_PINID='IMON';
NET_NAME
'XP12R0V_A_ISET'
 '@TIMECARD_LIB.TIMECARD(SCH_1):XP12R0V_A_ISET':
 C_SIGNAL='@timecard_lib.timecard(sch_1):xp12r0v_a_iset';
NODE_NAME     R46 2
 '@TIMECARD_LIB.TIMECARD(SCH_1):PAGE15_I171@PASSIVE.RESISTOR(CHIPS)':
 '2': CDS_PINID='\2\';
NODE_NAME     U1 5
 '@TIMECARD_LIB.TIMECARD(SCH_1):PAGE15_I212@STDLOGIC.MP5022CGQV_Z_QFN22(CHIPS)':
 'ISET': CDS_PINID='ISET';
NET_NAME
'XP12R0V_A_OV'
 '@TIMECARD_LIB.TIMECARD(SCH_1):XP12R0V_A_OV':
 C_SIGNAL='@timecard_lib.timecard(sch_1):xp12r0v_a_ov';
NODE_NAME     R12 1
 '@TIMECARD_LIB.TIMECARD(SCH_1):PAGE15_I197@PASSIVE.RESISTOR(CHIPS)':
 '1': CDS_PINID='\1\';
NODE_NAME     R11 2
 '@TIMECARD_LIB.TIMECARD(SCH_1):PAGE15_I199@PASSIVE.RESISTOR(CHIPS)':
 '2': CDS_PINID='\2\';
NODE_NAME     C8 1
 '@TIMECARD_LIB.TIMECARD(SCH_1):PAGE15_I201@PASSIVE.CAPACITOR(CHIPS)':
 '1': CDS_PINID='\1\';
NODE_NAME     U1 11
 '@TIMECARD_LIB.TIMECARD(SCH_1):PAGE15_I212@STDLOGIC.MP5022CGQV_Z_QFN22(CHIPS)':
 'OV': CDS_PINID='OV';
NET_NAME
'XP12R0V_A_PG'
 '@TIMECARD_LIB.TIMECARD(SCH_1):XP12R0V_A_PG':
 C_SIGNAL='@timecard_lib.timecard(sch_1):xp12r0v_a_pg';
NODE_NAME     R14 1
 '@TIMECARD_LIB.TIMECARD(SCH_1):PAGE15_I186@PASSIVE.RESISTOR(CHIPS)':
 '1': CDS_PINID='\1\';
NODE_NAME     R13 2
 '@TIMECARD_LIB.TIMECARD(SCH_1):PAGE15_I202@PASSIVE.RESISTOR(CHIPS)':
 '2': CDS_PINID='\2\';
NODE_NAME     U1 10
 '@TIMECARD_LIB.TIMECARD(SCH_1):PAGE15_I212@STDLOGIC.MP5022CGQV_Z_QFN22(CHIPS)':
 'PG': CDS_PINID='PG';
NODE_NAME     TP36 1
 '@TIMECARD_LIB.TIMECARD(SCH_1):PAGE16_I1650@CLS.TP_PIONT(CHIPS)':
 '1': CDS_PINID='\1\';
NET_NAME
'XP12R0V_A_SS'
 '@TIMECARD_LIB.TIMECARD(SCH_1):XP12R0V_A_SS':
 C_SIGNAL='@timecard_lib.timecard(sch_1):xp12r0v_a_ss';
NODE_NAME     C5 1
 '@TIMECARD_LIB.TIMECARD(SCH_1):PAGE15_I211@PASSIVE.CAPACITOR(CHIPS)':
 '1': CDS_PINID='\1\';
NODE_NAME     U1 6
 '@TIMECARD_LIB.TIMECARD(SCH_1):PAGE15_I212@STDLOGIC.MP5022CGQV_Z_QFN22(CHIPS)':
 'SS': CDS_PINID='SS';
NET_NAME
'XP12R0V_A_TIMER'
 '@TIMECARD_LIB.TIMECARD(SCH_1):XP12R0V_A_TIMER':
 C_SIGNAL='@timecard_lib.timecard(sch_1):xp12r0v_a_timer';
NODE_NAME     C4 2
 '@TIMECARD_LIB.TIMECARD(SCH_1):PAGE15_I172@PASSIVE.CAPACITOR(CHIPS)':
 '2': CDS_PINID='\2\';
NODE_NAME     U1 4
 '@TIMECARD_LIB.TIMECARD(SCH_1):PAGE15_I212@STDLOGIC.MP5022CGQV_Z_QFN22(CHIPS)':
 'TIMER': CDS_PINID='TIMER';
NET_NAME
'XP12R0V_EXT'
 '@TIMECARD_LIB.TIMECARD(SCH_1):XP12R0V_EXT':
 C_SIGNAL='@timecard_lib.timecard(sch_1):xp12r0v_ext',
 CDS_GLOBAL_NET='TRUE';
NODE_NAME     P3 1
 '@TIMECARD_LIB.TIMECARD(SCH_1):PAGE15_I238@CONNECTOR.CONN_HDR_2X3_M_RA_TH(CHIPS)':
 '1': CDS_PINID='\1\';
NODE_NAME     P3 2
 '@TIMECARD_LIB.TIMECARD(SCH_1):PAGE15_I238@CONNECTOR.CONN_HDR_2X3_M_RA_TH(CHIPS)':
 '2': CDS_PINID='\2\';
NODE_NAME     P3 3
 '@TIMECARD_LIB.TIMECARD(SCH_1):PAGE15_I238@CONNECTOR.CONN_HDR_2X3_M_RA_TH(CHIPS)':
 '3': CDS_PINID='\3\';
NODE_NAME     CR12 2
 '@TIMECARD_LIB.TIMECARD(SCH_1):PAGE15_I239@DISCRETE.DIODE_3F(CHIPS)':
 'A_2': CDS_PINID='A_2';
NET_NAME
'XP12R0V_IN'
 '@TIMECARD_LIB.TIMECARD(SCH_1):XP12R0V_IN':
 C_SIGNAL='@timecard_lib.timecard(sch_1):xp12r0v_in',
 CDS_GLOBAL_NET='TRUE';
NODE_NAME     CR10 C
 '@TIMECARD_LIB.TIMECARD(SCH_1):PAGE15_I159@DISCRETE.DIODE_2E(CHIPS)':
 'C': CDS_PINID='C';
NODE_NAME     C2 1
 '@TIMECARD_LIB.TIMECARD(SCH_1):PAGE15_I160@PASSIVE.CAPACITOR(CHIPS)':
 '1': CDS_PINID='\1\';
NODE_NAME     R4 1
 '@TIMECARD_LIB.TIMECARD(SCH_1):PAGE15_I170@PASSIVE.RESISTOR(CHIPS)':
 '1': CDS_PINID='\1\';
NODE_NAME     R9 1
 '@TIMECARD_LIB.TIMECARD(SCH_1):PAGE15_I198@PASSIVE.RESISTOR(CHIPS)':
 '1': CDS_PINID='\1\';
NODE_NAME     R11 1
 '@TIMECARD_LIB.TIMECARD(SCH_1):PAGE15_I199@PASSIVE.RESISTOR(CHIPS)':
 '1': CDS_PINID='\1\';
NODE_NAME     U1 21
 '@TIMECARD_LIB.TIMECARD(SCH_1):PAGE15_I212@STDLOGIC.MP5022CGQV_Z_QFN22(CHIPS)':
 'VIN_1': CDS_PINID='VIN_1';
NODE_NAME     U1 22
 '@TIMECARD_LIB.TIMECARD(SCH_1):PAGE15_I212@STDLOGIC.MP5022CGQV_Z_QFN22(CHIPS)':
 'VIN_2': CDS_PINID='VIN_2';
NODE_NAME     U1 23
 '@TIMECARD_LIB.TIMECARD(SCH_1):PAGE15_I212@STDLOGIC.MP5022CGQV_Z_QFN22(CHIPS)':
 'VIN_3': CDS_PINID='VIN_3';
NODE_NAME     U1 24
 '@TIMECARD_LIB.TIMECARD(SCH_1):PAGE15_I212@STDLOGIC.MP5022CGQV_Z_QFN22(CHIPS)':
 'VIN_4': CDS_PINID='VIN_4';
NODE_NAME     U1 25
 '@TIMECARD_LIB.TIMECARD(SCH_1):PAGE15_I212@STDLOGIC.MP5022CGQV_Z_QFN22(CHIPS)':
 'VIN_5': CDS_PINID='VIN_5';
NODE_NAME     U1 26
 '@TIMECARD_LIB.TIMECARD(SCH_1):PAGE15_I212@STDLOGIC.MP5022CGQV_Z_QFN22(CHIPS)':
 'VIN_6': CDS_PINID='VIN_6';
NODE_NAME     FU1 1
 '@TIMECARD_LIB.TIMECARD(SCH_1):PAGE15_I223@PASSIVE.FUSE(CHIPS)':
 '1': CDS_PINID='\1\';
NODE_NAME     C297 1
 '@TIMECARD_LIB.TIMECARD(SCH_1):PAGE15_I229@PASSIVE.CAPACITOR(CHIPS)':
 '1': CDS_PINID='\1\';
NODE_NAME     C299 1
 '@TIMECARD_LIB.TIMECARD(SCH_1):PAGE15_I230@PASSIVE.CAPACITOR(CHIPS)':
 '1': CDS_PINID='\1\';
NODE_NAME     C303 1
 '@TIMECARD_LIB.TIMECARD(SCH_1):PAGE15_I231@PASSIVE.CAPACITOR(CHIPS)':
 '1': CDS_PINID='\1\';
NODE_NAME     C301 1
 '@TIMECARD_LIB.TIMECARD(SCH_1):PAGE15_I232@PASSIVE.CAPACITOR(CHIPS)':
 '1': CDS_PINID='\1\';
NODE_NAME     CR12 3
 '@TIMECARD_LIB.TIMECARD(SCH_1):PAGE15_I239@DISCRETE.DIODE_3F(CHIPS)':
 'C': CDS_PINID='C';
NODE_NAME     L20 2
 '@TIMECARD_LIB.TIMECARD(SCH_1):PAGE15_I240@PASSIVE.FERRITEBEAD(CHIPS)':
 '2': CDS_PINID='\2\';
NODE_NAME     TP42 1
 '@TIMECARD_LIB.TIMECARD(SCH_1):PAGE16_I1665@CLS.TP_PIONT(CHIPS)':
 '1': CDS_PINID='\1\';
NET_NAME
'XP12R0V_PCIE'
 '@TIMECARD_LIB.TIMECARD(SCH_1):XP12R0V_PCIE':
 C_SIGNAL='@timecard_lib.timecard(sch_1):xp12r0v_pcie',
 CDS_GLOBAL_NET='TRUE';
NODE_NAME     GF1 B1
 '@TIMECARD_LIB.TIMECARD(SCH_1):PAGE3_I61@CONNECTOR.CONN_64P_GF(CHIPS)':
 'P_12V1': CDS_PINID='P_12V1';
NODE_NAME     GF1 B2
 '@TIMECARD_LIB.TIMECARD(SCH_1):PAGE3_I61@CONNECTOR.CONN_64P_GF(CHIPS)':
 'P_12V2': CDS_PINID='P_12V2';
NODE_NAME     GF1 A2
 '@TIMECARD_LIB.TIMECARD(SCH_1):PAGE3_I61@CONNECTOR.CONN_64P_GF(CHIPS)':
 'P_12V3': CDS_PINID='P_12V3';
NODE_NAME     GF1 B3
 '@TIMECARD_LIB.TIMECARD(SCH_1):PAGE3_I61@CONNECTOR.CONN_64P_GF(CHIPS)':
 'P_12V4': CDS_PINID='P_12V4';
NODE_NAME     GF1 A3
 '@TIMECARD_LIB.TIMECARD(SCH_1):PAGE3_I61@CONNECTOR.CONN_64P_GF(CHIPS)':
 'P_12V5': CDS_PINID='P_12V5';
NODE_NAME     CR12 1
 '@TIMECARD_LIB.TIMECARD(SCH_1):PAGE15_I239@DISCRETE.DIODE_3F(CHIPS)':
 'A_1': CDS_PINID='A_1';
NODE_NAME     L20 1
 '@TIMECARD_LIB.TIMECARD(SCH_1):PAGE15_I240@PASSIVE.FERRITEBEAD(CHIPS)':
 '1': CDS_PINID='\1\';
NET_NAME
'XP1R0V_AGND'
 '@TIMECARD_LIB.TIMECARD(SCH_1):XP1R0V_AGND':
 C_SIGNAL='@timecard_lib.timecard(sch_1):xp1r0v_agnd';
NODE_NAME     C263 2
 '@TIMECARD_LIB.TIMECARD(SCH_1):PAGE523_I9@PASSIVE.CAPACITOR(CHIPS)':
 '2': CDS_PINID='\2\';
NODE_NAME     C264 2
 '@TIMECARD_LIB.TIMECARD(SCH_1):PAGE523_I10@PASSIVE.CAPACITOR(CHIPS)':
 '2': CDS_PINID='\2\';
NODE_NAME     U26 12
 '@TIMECARD_LIB.TIMECARD(SCH_1):PAGE523_I11@STDLOGIC.TPS54824RNVR_VQFN18(CHIPS)':
 'AGND': CDS_PINID='AGND';
NODE_NAME     C259 2
 '@TIMECARD_LIB.TIMECARD(SCH_1):PAGE523_I12@PASSIVE.CAPACITOR(CHIPS)':
 '2': CDS_PINID='\2\';
NODE_NAME     R248 2
 '@TIMECARD_LIB.TIMECARD(SCH_1):PAGE523_I15@PASSIVE.RESISTOR(CHIPS)':
 '2': CDS_PINID='\2\';
NODE_NAME     SP3 2
 '@TIMECARD_LIB.TIMECARD(SCH_1):PAGE523_I39@MECH.SOLDER_PREFORM(CHIPS)':
 '2': CDS_PINID='\2\';
NODE_NAME     R251 1
 '@TIMECARD_LIB.TIMECARD(SCH_1):PAGE523_I56@PASSIVE.RESISTOR(CHIPS)':
 '1': CDS_PINID='\1\';
NODE_NAME     R252 1
 '@TIMECARD_LIB.TIMECARD(SCH_1):PAGE523_I57@PASSIVE.RESISTOR(CHIPS)':
 '1': CDS_PINID='\1\';
NET_NAME
'XP1R0V_BT'
 '@TIMECARD_LIB.TIMECARD(SCH_1):XP1R0V_BT':
 C_SIGNAL='@timecard_lib.timecard(sch_1):xp1r0v_bt';
NODE_NAME     U26 1
 '@TIMECARD_LIB.TIMECARD(SCH_1):PAGE523_I11@STDLOGIC.TPS54824RNVR_VQFN18(CHIPS)':
 'BOOT': CDS_PINID='BOOT';
NODE_NAME     R250 1
 '@TIMECARD_LIB.TIMECARD(SCH_1):PAGE523_I23@PASSIVE.RESISTOR(CHIPS)':
 '1': CDS_PINID='\1\';
NET_NAME
'XP1R0V_COMP'
 '@TIMECARD_LIB.TIMECARD(SCH_1):XP1R0V_COMP':
 C_SIGNAL='@timecard_lib.timecard(sch_1):xp1r0v_comp';
NODE_NAME     C264 1
 '@TIMECARD_LIB.TIMECARD(SCH_1):PAGE523_I10@PASSIVE.CAPACITOR(CHIPS)':
 '1': CDS_PINID='\1\';
NODE_NAME     U26 15
 '@TIMECARD_LIB.TIMECARD(SCH_1):PAGE523_I11@STDLOGIC.TPS54824RNVR_VQFN18(CHIPS)':
 'COMP': CDS_PINID='COMP';
NODE_NAME     R249 1
 '@TIMECARD_LIB.TIMECARD(SCH_1):PAGE523_I16@PASSIVE.RESISTOR(CHIPS)':
 '1': CDS_PINID='\1\';
NET_NAME
'XP1R0V_FB_R_TO_AGND'
 '@TIMECARD_LIB.TIMECARD(SCH_1):XP1R0V_FB_R_TO_AGND':
 C_SIGNAL='@timecard_lib.timecard(sch_1):xp1r0v_fb_r_to_agnd';
NODE_NAME     U26 14
 '@TIMECARD_LIB.TIMECARD(SCH_1):PAGE523_I11@STDLOGIC.TPS54824RNVR_VQFN18(CHIPS)':
 'FB': CDS_PINID='FB';
NODE_NAME     C267 2
 '@TIMECARD_LIB.TIMECARD(SCH_1):PAGE523_I28@PASSIVE.CAPACITOR(CHIPS)':
 '2': CDS_PINID='\2\';
NODE_NAME     R255 2
 '@TIMECARD_LIB.TIMECARD(SCH_1):PAGE523_I29@PASSIVE.RESISTOR(CHIPS)':
 '2': CDS_PINID='\2\';
NODE_NAME     R251 2
 '@TIMECARD_LIB.TIMECARD(SCH_1):PAGE523_I56@PASSIVE.RESISTOR(CHIPS)':
 '2': CDS_PINID='\2\';
NODE_NAME     R252 2
 '@TIMECARD_LIB.TIMECARD(SCH_1):PAGE523_I57@PASSIVE.RESISTOR(CHIPS)':
 '2': CDS_PINID='\2\';
NET_NAME
'XP1R0V_FPGA'
 '@TIMECARD_LIB.TIMECARD(SCH_1):XP1R0V_FPGA':
 C_SIGNAL='@timecard_lib.timecard(sch_1):xp1r0v_fpga',
 CDS_GLOBAL_NET='TRUE';
NODE_NAME     L34 2
 '@TIMECARD_LIB.TIMECARD(SCH_1):PAGE164_I37@PASSIVE.FERRITEBEAD(CHIPS)':
 '2': CDS_PINID='\2\';
NODE_NAME     L12 2
 '@TIMECARD_LIB.TIMECARD(SCH_1):PAGE164_I139@PASSIVE.FERRITEBEAD(CHIPS)':
 '2': CDS_PINID='\2\';
NODE_NAME     C148 1
 '@TIMECARD_LIB.TIMECARD(SCH_1):PAGE164_I250@PASSIVE.CAPACITOR(CHIPS)':
 '1': CDS_PINID='\1\';
NODE_NAME     C155 1
 '@TIMECARD_LIB.TIMECARD(SCH_1):PAGE164_I266@PASSIVE.CAPACITOR(CHIPS)':
 '1': CDS_PINID='\1\';
NODE_NAME     C179 1
 '@TIMECARD_LIB.TIMECARD(SCH_1):PAGE164_I274@PASSIVE.CAPACITOR(CHIPS)':
 '1': CDS_PINID='\1\';
NODE_NAME     C178 1
 '@TIMECARD_LIB.TIMECARD(SCH_1):PAGE164_I283@PASSIVE.CAPACITOR(CHIPS)':
 '1': CDS_PINID='\1\';
NODE_NAME     L5 2
 '@TIMECARD_LIB.TIMECARD(SCH_1):PAGE523_I25@PASSIVE.INDUCTOR_2(CHIPS)':
 '2': CDS_PINID='\2\';
NODE_NAME     R254 1
 '@TIMECARD_LIB.TIMECARD(SCH_1):PAGE523_I30@PASSIVE.RESISTOR(CHIPS)':
 '1': CDS_PINID='\1\';
NODE_NAME     C268 1
 '@TIMECARD_LIB.TIMECARD(SCH_1):PAGE523_I33@PASSIVE.CAPACITOR(CHIPS)':
 '1': CDS_PINID='\1\';
NODE_NAME     C269 1
 '@TIMECARD_LIB.TIMECARD(SCH_1):PAGE523_I34@PASSIVE.CAPACITOR(CHIPS)':
 '1': CDS_PINID='\1\';
NODE_NAME     C270 1
 '@TIMECARD_LIB.TIMECARD(SCH_1):PAGE523_I35@PASSIVE.CAPACITOR(CHIPS)':
 '1': CDS_PINID='\1\';
NODE_NAME     C271 1
 '@TIMECARD_LIB.TIMECARD(SCH_1):PAGE523_I37@PASSIVE.CAPACITOR(CHIPS)':
 '1': CDS_PINID='\1\';
NODE_NAME     TP54 1
 '@TIMECARD_LIB.TIMECARD(SCH_1):PAGE16_I1210@CLS.TP_PIONT(CHIPS)':
 '1': CDS_PINID='\1\';
NET_NAME
'XP1R0V_FPGA_MGTAVCC'
 '@TIMECARD_LIB.TIMECARD(SCH_1):XP1R0V_FPGA_MGTAVCC':
 C_SIGNAL='@timecard_lib.timecard(sch_1):xp1r0v_fpga_mgtavcc';
NODE_NAME     L34 1
 '@TIMECARD_LIB.TIMECARD(SCH_1):PAGE164_I37@PASSIVE.FERRITEBEAD(CHIPS)':
 '1': CDS_PINID='\1\';
NODE_NAME     U24 D10
 '@TIMECARD_LIB.TIMECARD(SCH_1):PAGE164_I138@PLD.XC7A200T_2FBG484C_FBG484(CHIPS)':
 'MGTAVCC_1': CDS_PINID='MGTAVCC_1';
NODE_NAME     U24 D6
 '@TIMECARD_LIB.TIMECARD(SCH_1):PAGE164_I138@PLD.XC7A200T_2FBG484C_FBG484(CHIPS)':
 'MGTAVCC_2': CDS_PINID='MGTAVCC_2';
NODE_NAME     U24 E8
 '@TIMECARD_LIB.TIMECARD(SCH_1):PAGE164_I138@PLD.XC7A200T_2FBG484C_FBG484(CHIPS)':
 'MGTAVCC_3': CDS_PINID='MGTAVCC_3';
NODE_NAME     U24 F7
 '@TIMECARD_LIB.TIMECARD(SCH_1):PAGE164_I138@PLD.XC7A200T_2FBG484C_FBG484(CHIPS)':
 'MGTAVCC_4': CDS_PINID='MGTAVCC_4';
NODE_NAME     U24 F9
 '@TIMECARD_LIB.TIMECARD(SCH_1):PAGE164_I138@PLD.XC7A200T_2FBG484C_FBG484(CHIPS)':
 'MGTAVCC_5': CDS_PINID='MGTAVCC_5';
NODE_NAME     C131 1
 '@TIMECARD_LIB.TIMECARD(SCH_1):PAGE164_I248@PASSIVE.CAPACITOR(CHIPS)':
 '1': CDS_PINID='\1\';
NODE_NAME     C218 1
 '@TIMECARD_LIB.TIMECARD(SCH_1):PAGE164_I251@PASSIVE.CAPACITOR(CHIPS)':
 '1': CDS_PINID='\1\';
NODE_NAME     C105 1
 '@TIMECARD_LIB.TIMECARD(SCH_1):PAGE164_I252@PASSIVE.CAPACITOR(CHIPS)':
 '1': CDS_PINID='\1\';
NODE_NAME     C111 1
 '@TIMECARD_LIB.TIMECARD(SCH_1):PAGE164_I253@PASSIVE.CAPACITOR(CHIPS)':
 '1': CDS_PINID='\1\';
NODE_NAME     C118 1
 '@TIMECARD_LIB.TIMECARD(SCH_1):PAGE164_I254@PASSIVE.CAPACITOR(CHIPS)':
 '1': CDS_PINID='\1\';
NODE_NAME     C124 1
 '@TIMECARD_LIB.TIMECARD(SCH_1):PAGE164_I255@PASSIVE.CAPACITOR(CHIPS)':
 '1': CDS_PINID='\1\';
NODE_NAME     C137 1
 '@TIMECARD_LIB.TIMECARD(SCH_1):PAGE164_I281@PASSIVE.CAPACITOR(CHIPS)':
 '1': CDS_PINID='\1\';
NET_NAME
'XP1R0V_FPGA_PG'
 '@TIMECARD_LIB.TIMECARD(SCH_1):XP1R0V_FPGA_PG':
 C_SIGNAL='@timecard_lib.timecard(sch_1):xp1r0v_fpga_pg';
NODE_NAME     R140 1
 '@TIMECARD_LIB.TIMECARD(SCH_1):PAGE68_I18@PASSIVE.RESISTOR(CHIPS)':
 '1': CDS_PINID='\1\';
NODE_NAME     R245 1
 '@TIMECARD_LIB.TIMECARD(SCH_1):PAGE523_I104@PASSIVE.RESISTOR(CHIPS)':
 '1': CDS_PINID='\1\';
NODE_NAME     TP39 1
 '@TIMECARD_LIB.TIMECARD(SCH_1):PAGE16_I1652@CLS.TP_PIONT(CHIPS)':
 '1': CDS_PINID='\1\';
NET_NAME
'XP1R0V_FPGA_VCCINT'
 '@TIMECARD_LIB.TIMECARD(SCH_1):XP1R0V_FPGA_VCCINT':
 C_SIGNAL='@timecard_lib.timecard(sch_1):xp1r0v_fpga_vccint';
NODE_NAME     U24 J11
 '@TIMECARD_LIB.TIMECARD(SCH_1):PAGE164_I138@PLD.XC7A200T_2FBG484C_FBG484(CHIPS)':
 'VCCBRAM_1': CDS_PINID='VCCBRAM_1';
NODE_NAME     U24 L11
 '@TIMECARD_LIB.TIMECARD(SCH_1):PAGE164_I138@PLD.XC7A200T_2FBG484C_FBG484(CHIPS)':
 'VCCBRAM_2': CDS_PINID='VCCBRAM_2';
NODE_NAME     U24 N11
 '@TIMECARD_LIB.TIMECARD(SCH_1):PAGE164_I138@PLD.XC7A200T_2FBG484C_FBG484(CHIPS)':
 'VCCBRAM_3': CDS_PINID='VCCBRAM_3';
NODE_NAME     U24 H10
 '@TIMECARD_LIB.TIMECARD(SCH_1):PAGE164_I138@PLD.XC7A200T_2FBG484C_FBG484(CHIPS)':
 'VCCINT_1': CDS_PINID='VCCINT_1';
NODE_NAME     U24 H8
 '@TIMECARD_LIB.TIMECARD(SCH_1):PAGE164_I138@PLD.XC7A200T_2FBG484C_FBG484(CHIPS)':
 'VCCINT_2': CDS_PINID='VCCINT_2';
NODE_NAME     U24 J7
 '@TIMECARD_LIB.TIMECARD(SCH_1):PAGE164_I138@PLD.XC7A200T_2FBG484C_FBG484(CHIPS)':
 'VCCINT_3': CDS_PINID='VCCINT_3';
NODE_NAME     U24 J9
 '@TIMECARD_LIB.TIMECARD(SCH_1):PAGE164_I138@PLD.XC7A200T_2FBG484C_FBG484(CHIPS)':
 'VCCINT_4': CDS_PINID='VCCINT_4';
NODE_NAME     U24 K8
 '@TIMECARD_LIB.TIMECARD(SCH_1):PAGE164_I138@PLD.XC7A200T_2FBG484C_FBG484(CHIPS)':
 'VCCINT_5': CDS_PINID='VCCINT_5';
NODE_NAME     U24 L7
 '@TIMECARD_LIB.TIMECARD(SCH_1):PAGE164_I138@PLD.XC7A200T_2FBG484C_FBG484(CHIPS)':
 'VCCINT_6': CDS_PINID='VCCINT_6';
NODE_NAME     U24 M8
 '@TIMECARD_LIB.TIMECARD(SCH_1):PAGE164_I138@PLD.XC7A200T_2FBG484C_FBG484(CHIPS)':
 'VCCINT_7': CDS_PINID='VCCINT_7';
NODE_NAME     U24 N7
 '@TIMECARD_LIB.TIMECARD(SCH_1):PAGE164_I138@PLD.XC7A200T_2FBG484C_FBG484(CHIPS)':
 'VCCINT_8': CDS_PINID='VCCINT_8';
NODE_NAME     U24 P10
 '@TIMECARD_LIB.TIMECARD(SCH_1):PAGE164_I138@PLD.XC7A200T_2FBG484C_FBG484(CHIPS)':
 'VCCINT_9': CDS_PINID='VCCINT_9';
NODE_NAME     U24 P8
 '@TIMECARD_LIB.TIMECARD(SCH_1):PAGE164_I138@PLD.XC7A200T_2FBG484C_FBG484(CHIPS)':
 'VCCINT_10': CDS_PINID='VCCINT_10';
NODE_NAME     U24 R7
 '@TIMECARD_LIB.TIMECARD(SCH_1):PAGE164_I138@PLD.XC7A200T_2FBG484C_FBG484(CHIPS)':
 'VCCINT_11': CDS_PINID='VCCINT_11';
NODE_NAME     U24 R9
 '@TIMECARD_LIB.TIMECARD(SCH_1):PAGE164_I138@PLD.XC7A200T_2FBG484C_FBG484(CHIPS)':
 'VCCINT_12': CDS_PINID='VCCINT_12';
NODE_NAME     U24 T10
 '@TIMECARD_LIB.TIMECARD(SCH_1):PAGE164_I138@PLD.XC7A200T_2FBG484C_FBG484(CHIPS)':
 'VCCINT_13': CDS_PINID='VCCINT_13';
NODE_NAME     U24 T8
 '@TIMECARD_LIB.TIMECARD(SCH_1):PAGE164_I138@PLD.XC7A200T_2FBG484C_FBG484(CHIPS)':
 'VCCINT_14': CDS_PINID='VCCINT_14';
NODE_NAME     L12 1
 '@TIMECARD_LIB.TIMECARD(SCH_1):PAGE164_I139@PASSIVE.FERRITEBEAD(CHIPS)':
 '1': CDS_PINID='\1\';
NODE_NAME     C176 1
 '@TIMECARD_LIB.TIMECARD(SCH_1):PAGE164_I172@PASSIVE.CAPACITOR(CHIPS)':
 '1': CDS_PINID='\1\';
NODE_NAME     C175 1
 '@TIMECARD_LIB.TIMECARD(SCH_1):PAGE164_I173@PASSIVE.CAPACITOR(CHIPS)':
 '1': CDS_PINID='\1\';
NODE_NAME     C201 1
 '@TIMECARD_LIB.TIMECARD(SCH_1):PAGE164_I182@PASSIVE.CAPACITOR(CHIPS)':
 '1': CDS_PINID='\1\';
NODE_NAME     C207 1
 '@TIMECARD_LIB.TIMECARD(SCH_1):PAGE164_I183@PASSIVE.CAPACITOR(CHIPS)':
 '1': CDS_PINID='\1\';
NODE_NAME     C214 1
 '@TIMECARD_LIB.TIMECARD(SCH_1):PAGE164_I184@PASSIVE.CAPACITOR(CHIPS)':
 '1': CDS_PINID='\1\';
NODE_NAME     C222 1
 '@TIMECARD_LIB.TIMECARD(SCH_1):PAGE164_I185@PASSIVE.CAPACITOR(CHIPS)':
 '1': CDS_PINID='\1\';
NODE_NAME     C109 1
 '@TIMECARD_LIB.TIMECARD(SCH_1):PAGE164_I186@PASSIVE.CAPACITOR(CHIPS)':
 '1': CDS_PINID='\1\';
NODE_NAME     C114 1
 '@TIMECARD_LIB.TIMECARD(SCH_1):PAGE164_I187@PASSIVE.CAPACITOR(CHIPS)':
 '1': CDS_PINID='\1\';
NODE_NAME     C121 1
 '@TIMECARD_LIB.TIMECARD(SCH_1):PAGE164_I188@PASSIVE.CAPACITOR(CHIPS)':
 '1': CDS_PINID='\1\';
NODE_NAME     C129 1
 '@TIMECARD_LIB.TIMECARD(SCH_1):PAGE164_I189@PASSIVE.CAPACITOR(CHIPS)':
 '1': CDS_PINID='\1\';
NODE_NAME     C133 1
 '@TIMECARD_LIB.TIMECARD(SCH_1):PAGE164_I190@PASSIVE.CAPACITOR(CHIPS)':
 '1': CDS_PINID='\1\';
NODE_NAME     C141 1
 '@TIMECARD_LIB.TIMECARD(SCH_1):PAGE164_I191@PASSIVE.CAPACITOR(CHIPS)':
 '1': CDS_PINID='\1\';
NODE_NAME     C147 1
 '@TIMECARD_LIB.TIMECARD(SCH_1):PAGE164_I192@PASSIVE.CAPACITOR(CHIPS)':
 '1': CDS_PINID='\1\';
NODE_NAME     C152 1
 '@TIMECARD_LIB.TIMECARD(SCH_1):PAGE164_I193@PASSIVE.CAPACITOR(CHIPS)':
 '1': CDS_PINID='\1\';
NODE_NAME     C156 1
 '@TIMECARD_LIB.TIMECARD(SCH_1):PAGE164_I194@PASSIVE.CAPACITOR(CHIPS)':
 '1': CDS_PINID='\1\';
NODE_NAME     C161 1
 '@TIMECARD_LIB.TIMECARD(SCH_1):PAGE164_I195@PASSIVE.CAPACITOR(CHIPS)':
 '1': CDS_PINID='\1\';
NODE_NAME     C166 1
 '@TIMECARD_LIB.TIMECARD(SCH_1):PAGE164_I196@PASSIVE.CAPACITOR(CHIPS)':
 '1': CDS_PINID='\1\';
NODE_NAME     C169 1
 '@TIMECARD_LIB.TIMECARD(SCH_1):PAGE164_I197@PASSIVE.CAPACITOR(CHIPS)':
 '1': CDS_PINID='\1\';
NODE_NAME     C171 1
 '@TIMECARD_LIB.TIMECARD(SCH_1):PAGE164_I198@PASSIVE.CAPACITOR(CHIPS)':
 '1': CDS_PINID='\1\';
NODE_NAME     C177 1
 '@TIMECARD_LIB.TIMECARD(SCH_1):PAGE164_I277@PASSIVE.CAPACITOR(CHIPS)':
 '1': CDS_PINID='\1\';
NODE_NAME     C173 1
 '@TIMECARD_LIB.TIMECARD(SCH_1):PAGE164_I280@PASSIVE.CAPACITOR(CHIPS)':
 '1': CDS_PINID='\1\';
NET_NAME
'XP1R0V_PG'
 '@TIMECARD_LIB.TIMECARD(SCH_1):XP1R0V_PG':
 C_SIGNAL='@timecard_lib.timecard(sch_1):xp1r0v_pg';
NODE_NAME     U26 18
 '@TIMECARD_LIB.TIMECARD(SCH_1):PAGE523_I11@STDLOGIC.TPS54824RNVR_VQFN18(CHIPS)':
 'PGOOD': CDS_PINID='PGOOD';
NODE_NAME     R243 2
 '@TIMECARD_LIB.TIMECARD(SCH_1):PAGE523_I44@PASSIVE.RESISTOR(CHIPS)':
 '2': CDS_PINID='\2\';
NODE_NAME     C258 2
 '@TIMECARD_LIB.TIMECARD(SCH_1):PAGE523_I50@PASSIVE.CAPACITOR(CHIPS)':
 '2': CDS_PINID='\2\';
NODE_NAME     R245 2
 '@TIMECARD_LIB.TIMECARD(SCH_1):PAGE523_I104@PASSIVE.RESISTOR(CHIPS)':
 '2': CDS_PINID='\2\';
NET_NAME
'XP1R0V_RT'
 '@TIMECARD_LIB.TIMECARD(SCH_1):XP1R0V_RT':
 C_SIGNAL='@timecard_lib.timecard(sch_1):xp1r0v_rt';
NODE_NAME     U26 13
 '@TIMECARD_LIB.TIMECARD(SCH_1):PAGE523_I11@STDLOGIC.TPS54824RNVR_VQFN18(CHIPS)':
 'RT/CLK': CDS_PINID='\rt/clk\';
NODE_NAME     R248 1
 '@TIMECARD_LIB.TIMECARD(SCH_1):PAGE523_I15@PASSIVE.RESISTOR(CHIPS)':
 '1': CDS_PINID='\1\';
NET_NAME
'XP1R0V_SS'
 '@TIMECARD_LIB.TIMECARD(SCH_1):XP1R0V_SS':
 C_SIGNAL='@timecard_lib.timecard(sch_1):xp1r0v_ss';
NODE_NAME     U26 16
 '@TIMECARD_LIB.TIMECARD(SCH_1):PAGE523_I11@STDLOGIC.TPS54824RNVR_VQFN18(CHIPS)':
 'SS/TRK': CDS_PINID='\ss/trk\';
NODE_NAME     C259 1
 '@TIMECARD_LIB.TIMECARD(SCH_1):PAGE523_I12@PASSIVE.CAPACITOR(CHIPS)':
 '1': CDS_PINID='\1\';
NET_NAME
'XP1R0V_SW'
 '@TIMECARD_LIB.TIMECARD(SCH_1):XP1R0V_SW':
 C_SIGNAL='@timecard_lib.timecard(sch_1):xp1r0v_sw';
NODE_NAME     U26 6
 '@TIMECARD_LIB.TIMECARD(SCH_1):PAGE523_I11@STDLOGIC.TPS54824RNVR_VQFN18(CHIPS)':
 'SW_1': CDS_PINID='SW_1';
NODE_NAME     U26 7
 '@TIMECARD_LIB.TIMECARD(SCH_1):PAGE523_I11@STDLOGIC.TPS54824RNVR_VQFN18(CHIPS)':
 'SW_2': CDS_PINID='SW_2';
NODE_NAME     C265 2
 '@TIMECARD_LIB.TIMECARD(SCH_1):PAGE523_I24@PASSIVE.CAPACITOR(CHIPS)':
 '2': CDS_PINID='\2\';
NODE_NAME     L5 1
 '@TIMECARD_LIB.TIMECARD(SCH_1):PAGE523_I25@PASSIVE.INDUCTOR_2(CHIPS)':
 '1': CDS_PINID='\1\';
NODE_NAME     C266 1
 '@TIMECARD_LIB.TIMECARD(SCH_1):PAGE523_I31@PASSIVE.CAPACITOR(CHIPS)':
 '1': CDS_PINID='\1\';
NET_NAME
'XP1R2V_EN_R'
 '@TIMECARD_LIB.TIMECARD(SCH_1):XP1R2V_EN_R':
 C_SIGNAL='@timecard_lib.timecard(sch_1):xp1r2v_en_r';
NODE_NAME     R165 1
 '@TIMECARD_LIB.TIMECARD(SCH_1):PAGE68_I2@PASSIVE.RESISTOR(CHIPS)':
 '1': CDS_PINID='\1\';
NODE_NAME     C184 1
 '@TIMECARD_LIB.TIMECARD(SCH_1):PAGE68_I3@PASSIVE.CAPACITOR(CHIPS)':
 '1': CDS_PINID='\1\';
NODE_NAME     U20 7
 '@TIMECARD_LIB.TIMECARD(SCH_1):PAGE68_I6@ANALOG.ISL80101IRAJZ_DFN10(CHIPS)':
 'ENABLE': CDS_PINID='ENABLE';
NODE_NAME     R140 2
 '@TIMECARD_LIB.TIMECARD(SCH_1):PAGE68_I18@PASSIVE.RESISTOR(CHIPS)':
 '2': CDS_PINID='\2\';
NODE_NAME     R177 2
 '@TIMECARD_LIB.TIMECARD(SCH_1):PAGE68_I26@PASSIVE.RESISTOR(CHIPS)':
 '2': CDS_PINID='\2\';
NET_NAME
'XP1R2V_FB'
 '@TIMECARD_LIB.TIMECARD(SCH_1):XP1R2V_FB':
 C_SIGNAL='@timecard_lib.timecard(sch_1):xp1r2v_fb';
NODE_NAME     U20 3
 '@TIMECARD_LIB.TIMECARD(SCH_1):PAGE68_I6@ANALOG.ISL80101IRAJZ_DFN10(CHIPS)':
 'SENSE/ADJ': CDS_PINID='\sense/adj\';
NODE_NAME     R186 2
 '@TIMECARD_LIB.TIMECARD(SCH_1):PAGE68_I14@PASSIVE.RESISTOR(CHIPS)':
 '2': CDS_PINID='\2\';
NODE_NAME     R189 2
 '@TIMECARD_LIB.TIMECARD(SCH_1):PAGE68_I16@PASSIVE.RESISTOR(CHIPS)':
 '2': CDS_PINID='\2\';
NODE_NAME     R185 2
 '@TIMECARD_LIB.TIMECARD(SCH_1):PAGE68_I59@PASSIVE.RESISTOR(CHIPS)':
 '2': CDS_PINID='\2\';
NET_NAME
'XP1R2V_FPGA'
 '@TIMECARD_LIB.TIMECARD(SCH_1):XP1R2V_FPGA':
 C_SIGNAL='@timecard_lib.timecard(sch_1):xp1r2v_fpga',
 CDS_GLOBAL_NET='TRUE';
NODE_NAME     U20 1
 '@TIMECARD_LIB.TIMECARD(SCH_1):PAGE68_I6@ANALOG.ISL80101IRAJZ_DFN10(CHIPS)':
 'VOUT_1': CDS_PINID='VOUT_1';
NODE_NAME     U20 2
 '@TIMECARD_LIB.TIMECARD(SCH_1):PAGE68_I6@ANALOG.ISL80101IRAJZ_DFN10(CHIPS)':
 'VOUT_2': CDS_PINID='VOUT_2';
NODE_NAME     R185 1
 '@TIMECARD_LIB.TIMECARD(SCH_1):PAGE68_I59@PASSIVE.RESISTOR(CHIPS)':
 '1': CDS_PINID='\1\';
NODE_NAME     C194 1
 '@TIMECARD_LIB.TIMECARD(SCH_1):PAGE68_I60@PASSIVE.CAPACITOR(CHIPS)':
 '1': CDS_PINID='\1\';
NODE_NAME     C196 1
 '@TIMECARD_LIB.TIMECARD(SCH_1):PAGE68_I61@PASSIVE.CAPACITOR(CHIPS)':
 '1': CDS_PINID='\1\';
NODE_NAME     L35 2
 '@TIMECARD_LIB.TIMECARD(SCH_1):PAGE164_I36@PASSIVE.FERRITEBEAD(CHIPS)':
 '2': CDS_PINID='\2\';
NODE_NAME     C136 1
 '@TIMECARD_LIB.TIMECARD(SCH_1):PAGE164_I249@PASSIVE.CAPACITOR(CHIPS)':
 '1': CDS_PINID='\1\';
NODE_NAME     C143 1
 '@TIMECARD_LIB.TIMECARD(SCH_1):PAGE164_I265@PASSIVE.CAPACITOR(CHIPS)':
 '1': CDS_PINID='\1\';
NODE_NAME     TP55 1
 '@TIMECARD_LIB.TIMECARD(SCH_1):PAGE16_I1212@CLS.TP_PIONT(CHIPS)':
 '1': CDS_PINID='\1\';
NET_NAME
'XP1R2V_FPGA_PG'
 '@TIMECARD_LIB.TIMECARD(SCH_1):XP1R2V_FPGA_PG':
 C_SIGNAL='@timecard_lib.timecard(sch_1):xp1r2v_fpga_pg';
NODE_NAME     R181 2
 '@TIMECARD_LIB.TIMECARD(SCH_1):PAGE68_I10@PASSIVE.RESISTOR(CHIPS)':
 '2': CDS_PINID='\2\';
NODE_NAME     R141 1
 '@TIMECARD_LIB.TIMECARD(SCH_1):PAGE68_I42@PASSIVE.RESISTOR(CHIPS)':
 '1': CDS_PINID='\1\';
NODE_NAME     TP40 1
 '@TIMECARD_LIB.TIMECARD(SCH_1):PAGE16_I1653@CLS.TP_PIONT(CHIPS)':
 '1': CDS_PINID='\1\';
NET_NAME
'XP1R2V_PG_R'
 '@TIMECARD_LIB.TIMECARD(SCH_1):XP1R2V_PG_R':
 C_SIGNAL='@timecard_lib.timecard(sch_1):xp1r2v_pg_r';
NODE_NAME     U20 4
 '@TIMECARD_LIB.TIMECARD(SCH_1):PAGE68_I6@ANALOG.ISL80101IRAJZ_DFN10(CHIPS)':
 'PG': CDS_PINID='PG';
NODE_NAME     C192 1
 '@TIMECARD_LIB.TIMECARD(SCH_1):PAGE68_I9@PASSIVE.CAPACITOR(CHIPS)':
 '1': CDS_PINID='\1\';
NODE_NAME     R181 1
 '@TIMECARD_LIB.TIMECARD(SCH_1):PAGE68_I10@PASSIVE.RESISTOR(CHIPS)':
 '1': CDS_PINID='\1\';
NODE_NAME     R178 2
 '@TIMECARD_LIB.TIMECARD(SCH_1):PAGE68_I11@PASSIVE.RESISTOR(CHIPS)':
 '2': CDS_PINID='\2\';
NET_NAME
'XP1R2V_SS'
 '@TIMECARD_LIB.TIMECARD(SCH_1):XP1R2V_SS':
 C_SIGNAL='@timecard_lib.timecard(sch_1):xp1r2v_ss';
NODE_NAME     C190 1
 '@TIMECARD_LIB.TIMECARD(SCH_1):PAGE68_I5@PASSIVE.CAPACITOR(CHIPS)':
 '1': CDS_PINID='\1\';
NODE_NAME     U20 6
 '@TIMECARD_LIB.TIMECARD(SCH_1):PAGE68_I6@ANALOG.ISL80101IRAJZ_DFN10(CHIPS)':
 'SS': CDS_PINID='SS';
NET_NAME
'XP1R2V_VIN'
 '@TIMECARD_LIB.TIMECARD(SCH_1):XP1R2V_VIN':
 C_SIGNAL='@timecard_lib.timecard(sch_1):xp1r2v_vin';
NODE_NAME     U20 9
 '@TIMECARD_LIB.TIMECARD(SCH_1):PAGE68_I6@ANALOG.ISL80101IRAJZ_DFN10(CHIPS)':
 'VIN_1': CDS_PINID='VIN_1';
NODE_NAME     U20 10
 '@TIMECARD_LIB.TIMECARD(SCH_1):PAGE68_I6@ANALOG.ISL80101IRAJZ_DFN10(CHIPS)':
 'VIN_2': CDS_PINID='VIN_2';
NODE_NAME     L11 2
 '@TIMECARD_LIB.TIMECARD(SCH_1):PAGE68_I25@PASSIVE.FERRITEBEAD(CHIPS)':
 '2': CDS_PINID='\2\';
NODE_NAME     R177 1
 '@TIMECARD_LIB.TIMECARD(SCH_1):PAGE68_I26@PASSIVE.RESISTOR(CHIPS)':
 '1': CDS_PINID='\1\';
NODE_NAME     C185 1
 '@TIMECARD_LIB.TIMECARD(SCH_1):PAGE68_I27@PASSIVE.CAPACITOR(CHIPS)':
 '1': CDS_PINID='\1\';
NODE_NAME     C188 1
 '@TIMECARD_LIB.TIMECARD(SCH_1):PAGE68_I35@PASSIVE.CAPACITOR(CHIPS)':
 '1': CDS_PINID='\1\';
NET_NAME
'XP1R8V_EN_R'
 '@TIMECARD_LIB.TIMECARD(SCH_1):XP1R8V_EN_R':
 C_SIGNAL='@timecard_lib.timecard(sch_1):xp1r8v_en_r';
NODE_NAME     R141 2
 '@TIMECARD_LIB.TIMECARD(SCH_1):PAGE68_I42@PASSIVE.RESISTOR(CHIPS)':
 '2': CDS_PINID='\2\';
NODE_NAME     R174 1
 '@TIMECARD_LIB.TIMECARD(SCH_1):PAGE68_I44@PASSIVE.RESISTOR(CHIPS)':
 '1': CDS_PINID='\1\';
NODE_NAME     R166 2
 '@TIMECARD_LIB.TIMECARD(SCH_1):PAGE68_I45@PASSIVE.RESISTOR(CHIPS)':
 '2': CDS_PINID='\2\';
NODE_NAME     C187 1
 '@TIMECARD_LIB.TIMECARD(SCH_1):PAGE68_I46@PASSIVE.CAPACITOR(CHIPS)':
 '1': CDS_PINID='\1\';
NODE_NAME     U21 7
 '@TIMECARD_LIB.TIMECARD(SCH_1):PAGE68_I52@ANALOG.ISL80101IRAJZ_DFN10(CHIPS)':
 'ENABLE': CDS_PINID='ENABLE';
NET_NAME
'XP1R8V_FB'
 '@TIMECARD_LIB.TIMECARD(SCH_1):XP1R8V_FB':
 C_SIGNAL='@timecard_lib.timecard(sch_1):xp1r8v_fb';
NODE_NAME     U21 3
 '@TIMECARD_LIB.TIMECARD(SCH_1):PAGE68_I52@ANALOG.ISL80101IRAJZ_DFN10(CHIPS)':
 'SENSE/ADJ': CDS_PINID='\sense/adj\';
NODE_NAME     R187 2
 '@TIMECARD_LIB.TIMECARD(SCH_1):PAGE68_I78@PASSIVE.RESISTOR(CHIPS)':
 '2': CDS_PINID='\2\';
NODE_NAME     R188 2
 '@TIMECARD_LIB.TIMECARD(SCH_1):PAGE68_I79@PASSIVE.RESISTOR(CHIPS)':
 '2': CDS_PINID='\2\';
NODE_NAME     R190 2
 '@TIMECARD_LIB.TIMECARD(SCH_1):PAGE68_I80@PASSIVE.RESISTOR(CHIPS)':
 '2': CDS_PINID='\2\';
NET_NAME
'XP1R8V_FPGA'
 '@TIMECARD_LIB.TIMECARD(SCH_1):XP1R8V_FPGA':
 C_SIGNAL='@timecard_lib.timecard(sch_1):xp1r8v_fpga',
 CDS_GLOBAL_NET='TRUE';
NODE_NAME     U21 1
 '@TIMECARD_LIB.TIMECARD(SCH_1):PAGE68_I52@ANALOG.ISL80101IRAJZ_DFN10(CHIPS)':
 'VOUT_1': CDS_PINID='VOUT_1';
NODE_NAME     U21 2
 '@TIMECARD_LIB.TIMECARD(SCH_1):PAGE68_I52@ANALOG.ISL80101IRAJZ_DFN10(CHIPS)':
 'VOUT_2': CDS_PINID='VOUT_2';
NODE_NAME     R187 1
 '@TIMECARD_LIB.TIMECARD(SCH_1):PAGE68_I78@PASSIVE.RESISTOR(CHIPS)':
 '1': CDS_PINID='\1\';
NODE_NAME     C195 1
 '@TIMECARD_LIB.TIMECARD(SCH_1):PAGE68_I81@PASSIVE.CAPACITOR(CHIPS)':
 '1': CDS_PINID='\1\';
NODE_NAME     C197 1
 '@TIMECARD_LIB.TIMECARD(SCH_1):PAGE68_I83@PASSIVE.CAPACITOR(CHIPS)':
 '1': CDS_PINID='\1\';
NODE_NAME     L33 2
 '@TIMECARD_LIB.TIMECARD(SCH_1):PAGE164_I102@PASSIVE.FERRITEBEAD(CHIPS)':
 '2': CDS_PINID='\2\';
NODE_NAME     C158 1
 '@TIMECARD_LIB.TIMECARD(SCH_1):PAGE164_I176@PASSIVE.CAPACITOR(CHIPS)':
 '1': CDS_PINID='\1\';
NODE_NAME     C150 1
 '@TIMECARD_LIB.TIMECARD(SCH_1):PAGE164_I276@PASSIVE.CAPACITOR(CHIPS)':
 '1': CDS_PINID='\1\';
NODE_NAME     C276 1
 '@TIMECARD_LIB.TIMECARD(SCH_1):PAGE8_I16@PASSIVE.CAPACITOR(CHIPS)':
 '1': CDS_PINID='\1\';
NODE_NAME     L18 1
 '@TIMECARD_LIB.TIMECARD(SCH_1):PAGE8_I18@PASSIVE.FERRITEBEAD(CHIPS)':
 '1': CDS_PINID='\1\';
NODE_NAME     TP56 1
 '@TIMECARD_LIB.TIMECARD(SCH_1):PAGE16_I1215@CLS.TP_PIONT(CHIPS)':
 '1': CDS_PINID='\1\';
NET_NAME
'XP1R8V_FPGA_PG'
 '@TIMECARD_LIB.TIMECARD(SCH_1):XP1R8V_FPGA_PG':
 C_SIGNAL='@timecard_lib.timecard(sch_1):xp1r8v_fpga_pg';
NODE_NAME     R142 1
 '@TIMECARD_LIB.TIMECARD(SCH_1):PAGE516_I44@PASSIVE.RESISTOR(CHIPS)':
 '1': CDS_PINID='\1\';
NODE_NAME     R182 2
 '@TIMECARD_LIB.TIMECARD(SCH_1):PAGE68_I74@PASSIVE.RESISTOR(CHIPS)':
 '2': CDS_PINID='\2\';
NODE_NAME     R226 1
 '@TIMECARD_LIB.TIMECARD(SCH_1):PAGE515_I122@PASSIVE.RESISTOR(CHIPS)':
 '1': CDS_PINID='\1\';
NODE_NAME     R225 1
 '@TIMECARD_LIB.TIMECARD(SCH_1):PAGE515_I152@PASSIVE.RESISTOR(CHIPS)':
 '1': CDS_PINID='\1\';
NODE_NAME     TP41 1
 '@TIMECARD_LIB.TIMECARD(SCH_1):PAGE16_I1654@CLS.TP_PIONT(CHIPS)':
 '1': CDS_PINID='\1\';
NET_NAME
'XP1R8V_FPGA_VCCAUX'
 '@TIMECARD_LIB.TIMECARD(SCH_1):XP1R8V_FPGA_VCCAUX':
 C_SIGNAL='@timecard_lib.timecard(sch_1):xp1r8v_fpga_vccaux';
NODE_NAME     L33 1
 '@TIMECARD_LIB.TIMECARD(SCH_1):PAGE164_I102@PASSIVE.FERRITEBEAD(CHIPS)':
 '1': CDS_PINID='\1\';
NODE_NAME     U24 K10
 '@TIMECARD_LIB.TIMECARD(SCH_1):PAGE164_I138@PLD.XC7A200T_2FBG484C_FBG484(CHIPS)':
 'VCCADC_0': CDS_PINID='VCCADC_0';
NODE_NAME     U24 H12
 '@TIMECARD_LIB.TIMECARD(SCH_1):PAGE164_I138@PLD.XC7A200T_2FBG484C_FBG484(CHIPS)':
 'VCCAUX_1': CDS_PINID='VCCAUX_1';
NODE_NAME     U24 K12
 '@TIMECARD_LIB.TIMECARD(SCH_1):PAGE164_I138@PLD.XC7A200T_2FBG484C_FBG484(CHIPS)':
 'VCCAUX_2': CDS_PINID='VCCAUX_2';
NODE_NAME     U24 M12
 '@TIMECARD_LIB.TIMECARD(SCH_1):PAGE164_I138@PLD.XC7A200T_2FBG484C_FBG484(CHIPS)':
 'VCCAUX_3': CDS_PINID='VCCAUX_3';
NODE_NAME     U24 P12
 '@TIMECARD_LIB.TIMECARD(SCH_1):PAGE164_I138@PLD.XC7A200T_2FBG484C_FBG484(CHIPS)':
 'VCCAUX_4': CDS_PINID='VCCAUX_4';
NODE_NAME     U24 R11
 '@TIMECARD_LIB.TIMECARD(SCH_1):PAGE164_I138@PLD.XC7A200T_2FBG484C_FBG484(CHIPS)':
 'VCCAUX_5': CDS_PINID='VCCAUX_5';
NODE_NAME     U24 E12
 '@TIMECARD_LIB.TIMECARD(SCH_1):PAGE164_I138@PLD.XC7A200T_2FBG484C_FBG484(CHIPS)':
 'VCCBATT_0': CDS_PINID='VCCBATT_0';
NODE_NAME     C120 1
 '@TIMECARD_LIB.TIMECARD(SCH_1):PAGE164_I177@PASSIVE.CAPACITOR(CHIPS)':
 '1': CDS_PINID='\1\';
NODE_NAME     C200 1
 '@TIMECARD_LIB.TIMECARD(SCH_1):PAGE164_I199@PASSIVE.CAPACITOR(CHIPS)':
 '1': CDS_PINID='\1\';
NODE_NAME     C206 1
 '@TIMECARD_LIB.TIMECARD(SCH_1):PAGE164_I200@PASSIVE.CAPACITOR(CHIPS)':
 '1': CDS_PINID='\1\';
NODE_NAME     C212 1
 '@TIMECARD_LIB.TIMECARD(SCH_1):PAGE164_I201@PASSIVE.CAPACITOR(CHIPS)':
 '1': CDS_PINID='\1\';
NODE_NAME     C219 1
 '@TIMECARD_LIB.TIMECARD(SCH_1):PAGE164_I202@PASSIVE.CAPACITOR(CHIPS)':
 '1': CDS_PINID='\1\';
NODE_NAME     C106 1
 '@TIMECARD_LIB.TIMECARD(SCH_1):PAGE164_I203@PASSIVE.CAPACITOR(CHIPS)':
 '1': CDS_PINID='\1\';
NODE_NAME     C113 1
 '@TIMECARD_LIB.TIMECARD(SCH_1):PAGE164_I204@PASSIVE.CAPACITOR(CHIPS)':
 '1': CDS_PINID='\1\';
NODE_NAME     C128 1
 '@TIMECARD_LIB.TIMECARD(SCH_1):PAGE164_I243@PASSIVE.CAPACITOR(CHIPS)':
 '1': CDS_PINID='\1\';
NODE_NAME     C138 1
 '@TIMECARD_LIB.TIMECARD(SCH_1):PAGE164_I275@PASSIVE.CAPACITOR(CHIPS)':
 '1': CDS_PINID='\1\';
NET_NAME
'XP1R8V_ICP10100'
 '@TIMECARD_LIB.TIMECARD(SCH_1):XP1R8V_ICP10100':
 C_SIGNAL='@timecard_lib.timecard(sch_1):xp1r8v_icp10100',
 CDS_GLOBAL_NET='TRUE';
NODE_NAME     R70 1
 '@TIMECARD_LIB.TIMECARD(SCH_1):PAGE8_I3@PASSIVE.RESISTOR(CHIPS)':
 '1': CDS_PINID='\1\';
NODE_NAME     R71 1
 '@TIMECARD_LIB.TIMECARD(SCH_1):PAGE8_I5@PASSIVE.RESISTOR(CHIPS)':
 '1': CDS_PINID='\1\';
NODE_NAME     L18 2
 '@TIMECARD_LIB.TIMECARD(SCH_1):PAGE8_I18@PASSIVE.FERRITEBEAD(CHIPS)':
 '2': CDS_PINID='\2\';
NODE_NAME     C278 1
 '@TIMECARD_LIB.TIMECARD(SCH_1):PAGE8_I19@PASSIVE.CAPACITOR(CHIPS)':
 '1': CDS_PINID='\1\';
NODE_NAME     C277 1
 '@TIMECARD_LIB.TIMECARD(SCH_1):PAGE8_I21@PASSIVE.CAPACITOR(CHIPS)':
 '1': CDS_PINID='\1\';
NODE_NAME     U28 10
 '@TIMECARD_LIB.TIMECARD(SCH_1):PAGE8_I24@ANALOG.ICP_10100_LGA10(CHIPS)':
 'VDD': CDS_PINID='VDD';
NODE_NAME     R350 2
 '@TIMECARD_LIB.TIMECARD(SCH_1):PAGE8_I31@PASSIVE.RESISTOR(CHIPS)':
 '2': CDS_PINID='\2\';
NODE_NAME     R347 2
 '@TIMECARD_LIB.TIMECARD(SCH_1):PAGE8_I32@PASSIVE.RESISTOR(CHIPS)':
 '2': CDS_PINID='\2\';
NODE_NAME     C313 1
 '@TIMECARD_LIB.TIMECARD(SCH_1):PAGE8_I41@PASSIVE.CAPACITOR(CHIPS)':
 '1': CDS_PINID='\1\';
NODE_NAME     U32 1
 '@TIMECARD_LIB.TIMECARD(SCH_1):PAGE8_I52@STDLOGIC.PCA9508DP_TSSOP8(CHIPS)':
 'VCC_A': CDS_PINID='VCC_A';
NET_NAME
'XP1R8V_PG_R'
 '@TIMECARD_LIB.TIMECARD(SCH_1):XP1R8V_PG_R':
 C_SIGNAL='@timecard_lib.timecard(sch_1):xp1r8v_pg_r';
NODE_NAME     U21 4
 '@TIMECARD_LIB.TIMECARD(SCH_1):PAGE68_I52@ANALOG.ISL80101IRAJZ_DFN10(CHIPS)':
 'PG': CDS_PINID='PG';
NODE_NAME     C193 1
 '@TIMECARD_LIB.TIMECARD(SCH_1):PAGE68_I71@PASSIVE.CAPACITOR(CHIPS)':
 '1': CDS_PINID='\1\';
NODE_NAME     R179 2
 '@TIMECARD_LIB.TIMECARD(SCH_1):PAGE68_I73@PASSIVE.RESISTOR(CHIPS)':
 '2': CDS_PINID='\2\';
NODE_NAME     R182 1
 '@TIMECARD_LIB.TIMECARD(SCH_1):PAGE68_I74@PASSIVE.RESISTOR(CHIPS)':
 '1': CDS_PINID='\1\';
NET_NAME
'XP1R8V_SS'
 '@TIMECARD_LIB.TIMECARD(SCH_1):XP1R8V_SS':
 C_SIGNAL='@timecard_lib.timecard(sch_1):xp1r8v_ss';
NODE_NAME     C191 1
 '@TIMECARD_LIB.TIMECARD(SCH_1):PAGE68_I49@PASSIVE.CAPACITOR(CHIPS)':
 '1': CDS_PINID='\1\';
NODE_NAME     U21 6
 '@TIMECARD_LIB.TIMECARD(SCH_1):PAGE68_I52@ANALOG.ISL80101IRAJZ_DFN10(CHIPS)':
 'SS': CDS_PINID='SS';
NET_NAME
'XP1R8V_VIN'
 '@TIMECARD_LIB.TIMECARD(SCH_1):XP1R8V_VIN':
 C_SIGNAL='@timecard_lib.timecard(sch_1):xp1r8v_vin';
NODE_NAME     L6 2
 '@TIMECARD_LIB.TIMECARD(SCH_1):PAGE68_I43@PASSIVE.FERRITEBEAD(CHIPS)':
 '2': CDS_PINID='\2\';
NODE_NAME     R166 1
 '@TIMECARD_LIB.TIMECARD(SCH_1):PAGE68_I45@PASSIVE.RESISTOR(CHIPS)':
 '1': CDS_PINID='\1\';
NODE_NAME     C186 1
 '@TIMECARD_LIB.TIMECARD(SCH_1):PAGE68_I47@PASSIVE.CAPACITOR(CHIPS)':
 '1': CDS_PINID='\1\';
NODE_NAME     C189 1
 '@TIMECARD_LIB.TIMECARD(SCH_1):PAGE68_I51@PASSIVE.CAPACITOR(CHIPS)':
 '1': CDS_PINID='\1\';
NODE_NAME     U21 9
 '@TIMECARD_LIB.TIMECARD(SCH_1):PAGE68_I52@ANALOG.ISL80101IRAJZ_DFN10(CHIPS)':
 'VIN_1': CDS_PINID='VIN_1';
NODE_NAME     U21 10
 '@TIMECARD_LIB.TIMECARD(SCH_1):PAGE68_I52@ANALOG.ISL80101IRAJZ_DFN10(CHIPS)':
 'VIN_2': CDS_PINID='VIN_2';
NET_NAME
'XP2R5V_FPGA'
 '@TIMECARD_LIB.TIMECARD(SCH_1):XP2R5V_FPGA':
 C_SIGNAL='@timecard_lib.timecard(sch_1):xp2r5v_fpga',
 CDS_GLOBAL_NET='TRUE';
NODE_NAME     R61 2
 '@TIMECARD_LIB.TIMECARD(SCH_1):PAGE5_I52@PASSIVE.RESISTOR(CHIPS)':
 '2': CDS_PINID='\2\';
NODE_NAME     U24 AA7
 '@TIMECARD_LIB.TIMECARD(SCH_1):PAGE164_I138@PLD.XC7A200T_2FBG484C_FBG484(CHIPS)':
 'VCCO_34_1': CDS_PINID='VCCO_34_1';
NODE_NAME     U24 AB4
 '@TIMECARD_LIB.TIMECARD(SCH_1):PAGE164_I138@PLD.XC7A200T_2FBG484C_FBG484(CHIPS)':
 'VCCO_34_2': CDS_PINID='VCCO_34_2';
NODE_NAME     U24 R5
 '@TIMECARD_LIB.TIMECARD(SCH_1):PAGE164_I138@PLD.XC7A200T_2FBG484C_FBG484(CHIPS)':
 'VCCO_34_3': CDS_PINID='VCCO_34_3';
NODE_NAME     U24 T2
 '@TIMECARD_LIB.TIMECARD(SCH_1):PAGE164_I138@PLD.XC7A200T_2FBG484C_FBG484(CHIPS)':
 'VCCO_34_4': CDS_PINID='VCCO_34_4';
NODE_NAME     U24 V6
 '@TIMECARD_LIB.TIMECARD(SCH_1):PAGE164_I138@PLD.XC7A200T_2FBG484C_FBG484(CHIPS)':
 'VCCO_34_5': CDS_PINID='VCCO_34_5';
NODE_NAME     U24 W3
 '@TIMECARD_LIB.TIMECARD(SCH_1):PAGE164_I138@PLD.XC7A200T_2FBG484C_FBG484(CHIPS)':
 'VCCO_34_6': CDS_PINID='VCCO_34_6';
NODE_NAME     U24 C1
 '@TIMECARD_LIB.TIMECARD(SCH_1):PAGE164_I138@PLD.XC7A200T_2FBG484C_FBG484(CHIPS)':
 'VCCO_35_1': CDS_PINID='VCCO_35_1';
NODE_NAME     U24 F2
 '@TIMECARD_LIB.TIMECARD(SCH_1):PAGE164_I138@PLD.XC7A200T_2FBG484C_FBG484(CHIPS)':
 'VCCO_35_2': CDS_PINID='VCCO_35_2';
NODE_NAME     U24 H6
 '@TIMECARD_LIB.TIMECARD(SCH_1):PAGE164_I138@PLD.XC7A200T_2FBG484C_FBG484(CHIPS)':
 'VCCO_35_3': CDS_PINID='VCCO_35_3';
NODE_NAME     U24 J3
 '@TIMECARD_LIB.TIMECARD(SCH_1):PAGE164_I138@PLD.XC7A200T_2FBG484C_FBG484(CHIPS)':
 'VCCO_35_4': CDS_PINID='VCCO_35_4';
NODE_NAME     U24 M4
 '@TIMECARD_LIB.TIMECARD(SCH_1):PAGE164_I138@PLD.XC7A200T_2FBG484C_FBG484(CHIPS)':
 'VCCO_35_5': CDS_PINID='VCCO_35_5';
NODE_NAME     U24 N1
 '@TIMECARD_LIB.TIMECARD(SCH_1):PAGE164_I138@PLD.XC7A200T_2FBG484C_FBG484(CHIPS)':
 'VCCO_35_6': CDS_PINID='VCCO_35_6';
NODE_NAME     C204 1
 '@TIMECARD_LIB.TIMECARD(SCH_1):PAGE164_I231@PASSIVE.CAPACITOR(CHIPS)':
 '1': CDS_PINID='\1\';
NODE_NAME     C208 1
 '@TIMECARD_LIB.TIMECARD(SCH_1):PAGE164_I232@PASSIVE.CAPACITOR(CHIPS)':
 '1': CDS_PINID='\1\';
NODE_NAME     C213 1
 '@TIMECARD_LIB.TIMECARD(SCH_1):PAGE164_I233@PASSIVE.CAPACITOR(CHIPS)':
 '1': CDS_PINID='\1\';
NODE_NAME     C220 1
 '@TIMECARD_LIB.TIMECARD(SCH_1):PAGE164_I234@PASSIVE.CAPACITOR(CHIPS)':
 '1': CDS_PINID='\1\';
NODE_NAME     C108 1
 '@TIMECARD_LIB.TIMECARD(SCH_1):PAGE164_I235@PASSIVE.CAPACITOR(CHIPS)':
 '1': CDS_PINID='\1\';
NODE_NAME     C116 1
 '@TIMECARD_LIB.TIMECARD(SCH_1):PAGE164_I236@PASSIVE.CAPACITOR(CHIPS)':
 '1': CDS_PINID='\1\';
NODE_NAME     C122 1
 '@TIMECARD_LIB.TIMECARD(SCH_1):PAGE164_I237@PASSIVE.CAPACITOR(CHIPS)':
 '1': CDS_PINID='\1\';
NODE_NAME     C127 1
 '@TIMECARD_LIB.TIMECARD(SCH_1):PAGE164_I238@PASSIVE.CAPACITOR(CHIPS)':
 '1': CDS_PINID='\1\';
NODE_NAME     C135 1
 '@TIMECARD_LIB.TIMECARD(SCH_1):PAGE164_I239@PASSIVE.CAPACITOR(CHIPS)':
 '1': CDS_PINID='\1\';
NODE_NAME     C142 1
 '@TIMECARD_LIB.TIMECARD(SCH_1):PAGE164_I240@PASSIVE.CAPACITOR(CHIPS)':
 '1': CDS_PINID='\1\';
NODE_NAME     C146 1
 '@TIMECARD_LIB.TIMECARD(SCH_1):PAGE164_I241@PASSIVE.CAPACITOR(CHIPS)':
 '1': CDS_PINID='\1\';
NODE_NAME     C151 1
 '@TIMECARD_LIB.TIMECARD(SCH_1):PAGE164_I242@PASSIVE.CAPACITOR(CHIPS)':
 '1': CDS_PINID='\1\';
NODE_NAME     C160 1
 '@TIMECARD_LIB.TIMECARD(SCH_1):PAGE164_I245@PASSIVE.CAPACITOR(CHIPS)':
 '1': CDS_PINID='\1\';
NODE_NAME     C168 1
 '@TIMECARD_LIB.TIMECARD(SCH_1):PAGE164_I267@PASSIVE.CAPACITOR(CHIPS)':
 '1': CDS_PINID='\1\';
NODE_NAME     C164 1
 '@TIMECARD_LIB.TIMECARD(SCH_1):PAGE164_I268@PASSIVE.CAPACITOR(CHIPS)':
 '1': CDS_PINID='\1\';
NODE_NAME     R231 1
 '@TIMECARD_LIB.TIMECARD(SCH_1):PAGE515_I146@PASSIVE.RESISTOR(CHIPS)':
 '1': CDS_PINID='\1\';
NODE_NAME     C239 1
 '@TIMECARD_LIB.TIMECARD(SCH_1):PAGE515_I147@PASSIVE.CAPACITOR(CHIPS)':
 '1': CDS_PINID='\1\';
NODE_NAME     C242 1
 '@TIMECARD_LIB.TIMECARD(SCH_1):PAGE515_I149@PASSIVE.CAPACITOR(CHIPS)':
 '1': CDS_PINID='\1\';
NODE_NAME     U25 1
 '@TIMECARD_LIB.TIMECARD(SCH_1):PAGE515_I151@ANALOG.ISL80101IRAJZ_DFN10(CHIPS)':
 'VOUT_1': CDS_PINID='VOUT_1';
NODE_NAME     U25 2
 '@TIMECARD_LIB.TIMECARD(SCH_1):PAGE515_I151@ANALOG.ISL80101IRAJZ_DFN10(CHIPS)':
 'VOUT_2': CDS_PINID='VOUT_2';
NODE_NAME     R139 2
 '@TIMECARD_LIB.TIMECARD(SCH_1):PAGE14_I60@PASSIVE.RESISTOR(CHIPS)':
 '2': CDS_PINID='\2\';
NODE_NAME     TP57 1
 '@TIMECARD_LIB.TIMECARD(SCH_1):PAGE16_I1217@CLS.TP_PIONT(CHIPS)':
 '1': CDS_PINID='\1\';
NODE_NAME     R355 2
 '@TIMECARD_LIB.TIMECARD(SCH_1):PAGE163_I120@PASSIVE.RESISTOR(CHIPS)':
 '2': CDS_PINID='\2\';
NODE_NAME     R358 2
 '@TIMECARD_LIB.TIMECARD(SCH_1):PAGE163_I126@PASSIVE.RESISTOR(CHIPS)':
 '2': CDS_PINID='\2\';
NODE_NAME     C291 1
 '@TIMECARD_LIB.TIMECARD(SCH_1):PAGE164_I290@PASSIVE.CAPACITOR(CHIPS)':
 '1': CDS_PINID='\1\';
NODE_NAME     C292 1
 '@TIMECARD_LIB.TIMECARD(SCH_1):PAGE164_I291@PASSIVE.CAPACITOR(CHIPS)':
 '1': CDS_PINID='\1\';
NODE_NAME     C93 1
 '@TIMECARD_LIB.TIMECARD(SCH_1):PAGE164_I292@PASSIVE.CAPACITOR(CHIPS)':
 '1': CDS_PINID='\1\';
NODE_NAME     R438 2
 '@TIMECARD_LIB.TIMECARD(SCH_1):PAGE163_I132@PASSIVE.RESISTOR(CHIPS)':
 '2': CDS_PINID='\2\';
NODE_NAME     R439 2
 '@TIMECARD_LIB.TIMECARD(SCH_1):PAGE163_I133@PASSIVE.RESISTOR(CHIPS)':
 '2': CDS_PINID='\2\';
NET_NAME
'XP3R3V'
 '@TIMECARD_LIB.TIMECARD(SCH_1):XP3R3V':
 C_SIGNAL='@timecard_lib.timecard(sch_1):xp3r3v',
 CDS_GLOBAL_NET='TRUE';
NODE_NAME     R56 1
 '@TIMECARD_LIB.TIMECARD(SCH_1):PAGE3_I63@PASSIVE.RESISTOR(CHIPS)':
 '1': CDS_PINID='\1\';
NODE_NAME     R51 1
 '@TIMECARD_LIB.TIMECARD(SCH_1):PAGE517_I3@PASSIVE.RESISTOR(CHIPS)':
 '1': CDS_PINID='\1\';
NODE_NAME     L2 2
 '@TIMECARD_LIB.TIMECARD(SCH_1):PAGE517_I28@PASSIVE.INDUCTOR_2(CHIPS)':
 '2': CDS_PINID='\2\';
NODE_NAME     R17 1
 '@TIMECARD_LIB.TIMECARD(SCH_1):PAGE517_I33@PASSIVE.RESISTOR(CHIPS)':
 '1': CDS_PINID='\1\';
NODE_NAME     C18 1
 '@TIMECARD_LIB.TIMECARD(SCH_1):PAGE517_I36@PASSIVE.CAPACITOR(CHIPS)':
 '1': CDS_PINID='\1\';
NODE_NAME     C20 1
 '@TIMECARD_LIB.TIMECARD(SCH_1):PAGE517_I37@PASSIVE.CAPACITOR(CHIPS)':
 '1': CDS_PINID='\1\';
NODE_NAME     C21 1
 '@TIMECARD_LIB.TIMECARD(SCH_1):PAGE517_I38@PASSIVE.CAPACITOR(CHIPS)':
 '1': CDS_PINID='\1\';
NODE_NAME     C22 1
 '@TIMECARD_LIB.TIMECARD(SCH_1):PAGE517_I40@PASSIVE.CAPACITOR(CHIPS)':
 '1': CDS_PINID='\1\';
NODE_NAME     R47 1
 '@TIMECARD_LIB.TIMECARD(SCH_1):PAGE516_I1@PASSIVE.RESISTOR(CHIPS)':
 '1': CDS_PINID='\1\';
NODE_NAME     R178 1
 '@TIMECARD_LIB.TIMECARD(SCH_1):PAGE68_I11@PASSIVE.RESISTOR(CHIPS)':
 '1': CDS_PINID='\1\';
NODE_NAME     L11 1
 '@TIMECARD_LIB.TIMECARD(SCH_1):PAGE68_I25@PASSIVE.FERRITEBEAD(CHIPS)':
 '1': CDS_PINID='\1\';
NODE_NAME     L6 1
 '@TIMECARD_LIB.TIMECARD(SCH_1):PAGE68_I43@PASSIVE.FERRITEBEAD(CHIPS)':
 '1': CDS_PINID='\1\';
NODE_NAME     R179 1
 '@TIMECARD_LIB.TIMECARD(SCH_1):PAGE68_I73@PASSIVE.RESISTOR(CHIPS)':
 '1': CDS_PINID='\1\';
NODE_NAME     C180 1
 '@TIMECARD_LIB.TIMECARD(SCH_1):PAGE68_I93@PASSIVE.CAPACITOR(CHIPS)':
 '1': CDS_PINID='\1\';
NODE_NAME     C182 1
 '@TIMECARD_LIB.TIMECARD(SCH_1):PAGE68_I94@PASSIVE.CAPACITOR(CHIPS)':
 '1': CDS_PINID='\1\';
NODE_NAME     C181 1
 '@TIMECARD_LIB.TIMECARD(SCH_1):PAGE68_I97@PASSIVE.CAPACITOR(CHIPS)':
 '1': CDS_PINID='\1\';
NODE_NAME     C183 1
 '@TIMECARD_LIB.TIMECARD(SCH_1):PAGE68_I98@PASSIVE.CAPACITOR(CHIPS)':
 '1': CDS_PINID='\1\';
NODE_NAME     C232 1
 '@TIMECARD_LIB.TIMECARD(SCH_1):PAGE515_I61@PASSIVE.CAPACITOR(CHIPS)':
 '1': CDS_PINID='\1\';
NODE_NAME     C233 1
 '@TIMECARD_LIB.TIMECARD(SCH_1):PAGE515_I63@PASSIVE.CAPACITOR(CHIPS)':
 '1': CDS_PINID='\1\';
NODE_NAME     R260 1
 '@TIMECARD_LIB.TIMECARD(SCH_1):PAGE515_I67@PASSIVE.RESISTOR(CHIPS)':
 '1': CDS_PINID='\1\';
NODE_NAME     U22 3
 '@TIMECARD_LIB.TIMECARD(SCH_1):PAGE515_I76@ANALOG.NCP45560IMNTWG_H_DFN12(CHIPS)':
 'VCC': CDS_PINID='VCC';
NODE_NAME     C235 1
 '@TIMECARD_LIB.TIMECARD(SCH_1):PAGE515_I80@PASSIVE.CAPACITOR(CHIPS)':
 '1': CDS_PINID='\1\';
NODE_NAME     U22 1
 '@TIMECARD_LIB.TIMECARD(SCH_1):PAGE515_I82@ANALOG.NCP45560IMNTWG_H_DFN12(CHIPS)':
 'VIN_1': CDS_PINID='VIN_1';
NODE_NAME     U22 13
 '@TIMECARD_LIB.TIMECARD(SCH_1):PAGE515_I82@ANALOG.NCP45560IMNTWG_H_DFN12(CHIPS)':
 'VIN_2': CDS_PINID='VIN_2';
NODE_NAME     L13 1
 '@TIMECARD_LIB.TIMECARD(SCH_1):PAGE515_I135@PASSIVE.FERRITEBEAD(CHIPS)':
 '1': CDS_PINID='\1\';
NODE_NAME     C224 1
 '@TIMECARD_LIB.TIMECARD(SCH_1):PAGE515_I154@PASSIVE.CAPACITOR(CHIPS)':
 '1': CDS_PINID='\1\';
NODE_NAME     C226 1
 '@TIMECARD_LIB.TIMECARD(SCH_1):PAGE515_I155@PASSIVE.CAPACITOR(CHIPS)':
 '1': CDS_PINID='\1\';
NODE_NAME     L14 2
 '@TIMECARD_LIB.TIMECARD(SCH_1):PAGE522_I146@PASSIVE.FERRITEBEAD(CHIPS)':
 '2': CDS_PINID='\2\';
NODE_NAME     C244 1
 '@TIMECARD_LIB.TIMECARD(SCH_1):PAGE522_I152@PASSIVE.CAPACITOR(CHIPS)':
 '1': CDS_PINID='\1\';
NODE_NAME     C245 1
 '@TIMECARD_LIB.TIMECARD(SCH_1):PAGE522_I153@PASSIVE.CAPACITOR(CHIPS)':
 '1': CDS_PINID='\1\';
NODE_NAME     L10 2
 '@TIMECARD_LIB.TIMECARD(SCH_1):PAGE522_I159@PASSIVE.FERRITEBEAD(CHIPS)':
 '2': CDS_PINID='\2\';
NODE_NAME     R243 1
 '@TIMECARD_LIB.TIMECARD(SCH_1):PAGE523_I44@PASSIVE.RESISTOR(CHIPS)':
 '1': CDS_PINID='\1\';
NODE_NAME     TP53 1
 '@TIMECARD_LIB.TIMECARD(SCH_1):PAGE16_I1208@CLS.TP_PIONT(CHIPS)':
 '1': CDS_PINID='\1\';
NODE_NAME     C312 1
 '@TIMECARD_LIB.TIMECARD(SCH_1):PAGE8_I39@PASSIVE.CAPACITOR(CHIPS)':
 '1': CDS_PINID='\1\';
NODE_NAME     U32 8
 '@TIMECARD_LIB.TIMECARD(SCH_1):PAGE8_I52@STDLOGIC.PCA9508DP_TSSOP8(CHIPS)':
 'VCC_B': CDS_PINID='VCC_B';
NODE_NAME     L21 2
 '@TIMECARD_LIB.TIMECARD(SCH_1):PAGE3_I132@PASSIVE.FERRITEBEAD(CHIPS)':
 '2': CDS_PINID='\2\';
NET_NAME
'XP3R3V_AGND'
 '@TIMECARD_LIB.TIMECARD(SCH_1):XP3R3V_AGND':
 C_SIGNAL='@timecard_lib.timecard(sch_1):xp3r3v_agnd';
NODE_NAME     C49 2
 '@TIMECARD_LIB.TIMECARD(SCH_1):PAGE517_I9@PASSIVE.CAPACITOR(CHIPS)':
 '2': CDS_PINID='\2\';
NODE_NAME     R35 2
 '@TIMECARD_LIB.TIMECARD(SCH_1):PAGE517_I10@PASSIVE.RESISTOR(CHIPS)':
 '2': CDS_PINID='\2\';
NODE_NAME     C54 2
 '@TIMECARD_LIB.TIMECARD(SCH_1):PAGE517_I17@PASSIVE.CAPACITOR(CHIPS)':
 '2': CDS_PINID='\2\';
NODE_NAME     C55 2
 '@TIMECARD_LIB.TIMECARD(SCH_1):PAGE517_I19@PASSIVE.CAPACITOR(CHIPS)':
 '2': CDS_PINID='\2\';
NODE_NAME     SP2 2
 '@TIMECARD_LIB.TIMECARD(SCH_1):PAGE517_I24@MECH.SOLDER_PREFORM(CHIPS)':
 '2': CDS_PINID='\2\';
NODE_NAME     R38 2
 '@TIMECARD_LIB.TIMECARD(SCH_1):PAGE517_I26@PASSIVE.RESISTOR(CHIPS)':
 '2': CDS_PINID='\2\';
NODE_NAME     R54 1
 '@TIMECARD_LIB.TIMECARD(SCH_1):PAGE517_I41@PASSIVE.RESISTOR(CHIPS)':
 '1': CDS_PINID='\1\';
NODE_NAME     U6 12
 '@TIMECARD_LIB.TIMECARD(SCH_1):PAGE517_I42@STDLOGIC.TPS54824RNVR_VQFN18(CHIPS)':
 'AGND': CDS_PINID='AGND';
NET_NAME
'XP3R3V_AUX_PCIE'
 '@TIMECARD_LIB.TIMECARD(SCH_1):XP3R3V_AUX_PCIE':
 C_SIGNAL='@timecard_lib.timecard(sch_1):xp3r3v_aux_pcie',
 CDS_GLOBAL_NET='TRUE';
NODE_NAME     GF1 B10
 '@TIMECARD_LIB.TIMECARD(SCH_1):PAGE3_I61@CONNECTOR.CONN_64P_GF(CHIPS)':
 'P_3V3AUX': CDS_PINID='P_3V3AUX';
NODE_NAME     C288 1
 '@TIMECARD_LIB.TIMECARD(SCH_1):PAGE3_I127@PASSIVE.CAPACITOR(CHIPS)':
 '1': CDS_PINID='\1\';
NODE_NAME     C287 1
 '@TIMECARD_LIB.TIMECARD(SCH_1):PAGE3_I129@PASSIVE.CAPACITOR(CHIPS)':
 '1': CDS_PINID='\1\';
NODE_NAME     R119 2
 '@TIMECARD_LIB.TIMECARD(SCH_1):PAGE14_I192@PASSIVE.RESISTOR(CHIPS)':
 '2': CDS_PINID='\2\';
NET_NAME
'XP3R3V_BT'
 '@TIMECARD_LIB.TIMECARD(SCH_1):XP3R3V_BT':
 C_SIGNAL='@timecard_lib.timecard(sch_1):xp3r3v_bt';
NODE_NAME     R37 1
 '@TIMECARD_LIB.TIMECARD(SCH_1):PAGE517_I25@PASSIVE.RESISTOR(CHIPS)':
 '1': CDS_PINID='\1\';
NODE_NAME     U6 1
 '@TIMECARD_LIB.TIMECARD(SCH_1):PAGE517_I42@STDLOGIC.TPS54824RNVR_VQFN18(CHIPS)':
 'BOOT': CDS_PINID='BOOT';
NET_NAME
'XP3R3V_COMP'
 '@TIMECARD_LIB.TIMECARD(SCH_1):XP3R3V_COMP':
 C_SIGNAL='@timecard_lib.timecard(sch_1):xp3r3v_comp';
NODE_NAME     R36 1
 '@TIMECARD_LIB.TIMECARD(SCH_1):PAGE517_I18@PASSIVE.RESISTOR(CHIPS)':
 '1': CDS_PINID='\1\';
NODE_NAME     C55 1
 '@TIMECARD_LIB.TIMECARD(SCH_1):PAGE517_I19@PASSIVE.CAPACITOR(CHIPS)':
 '1': CDS_PINID='\1\';
NODE_NAME     U6 15
 '@TIMECARD_LIB.TIMECARD(SCH_1):PAGE517_I42@STDLOGIC.TPS54824RNVR_VQFN18(CHIPS)':
 'COMP': CDS_PINID='COMP';
NET_NAME
'XP3R3V_EN'
 '@TIMECARD_LIB.TIMECARD(SCH_1):XP3R3V_EN':
 C_SIGNAL='@timecard_lib.timecard(sch_1):xp3r3v_en';
NODE_NAME     R52 1
 '@TIMECARD_LIB.TIMECARD(SCH_1):PAGE517_I11@PASSIVE.RESISTOR(CHIPS)':
 '1': CDS_PINID='\1\';
NODE_NAME     C46 1
 '@TIMECARD_LIB.TIMECARD(SCH_1):PAGE517_I12@PASSIVE.CAPACITOR(CHIPS)':
 '1': CDS_PINID='\1\';
NODE_NAME     R53 2
 '@TIMECARD_LIB.TIMECARD(SCH_1):PAGE517_I13@PASSIVE.RESISTOR(CHIPS)':
 '2': CDS_PINID='\2\';
NODE_NAME     U6 17
 '@TIMECARD_LIB.TIMECARD(SCH_1):PAGE517_I42@STDLOGIC.TPS54824RNVR_VQFN18(CHIPS)':
 'EN': CDS_PINID='EN';
NODE_NAME     C286 1
 '@TIMECARD_LIB.TIMECARD(SCH_1):PAGE517_I51@PASSIVE.CAPACITOR(CHIPS)':
 '1': CDS_PINID='\1\';
NODE_NAME     TP59 1
 '@TIMECARD_LIB.TIMECARD(SCH_1):PAGE16_I1663@CLS.TP_PIONT(CHIPS)':
 '1': CDS_PINID='\1\';
NET_NAME
'XP3R3V_FB_R_TO_AGND'
 '@TIMECARD_LIB.TIMECARD(SCH_1):XP3R3V_FB_R_TO_AGND':
 C_SIGNAL='@timecard_lib.timecard(sch_1):xp3r3v_fb_r_to_agnd';
NODE_NAME     R38 1
 '@TIMECARD_LIB.TIMECARD(SCH_1):PAGE517_I26@PASSIVE.RESISTOR(CHIPS)':
 '1': CDS_PINID='\1\';
NODE_NAME     C16 2
 '@TIMECARD_LIB.TIMECARD(SCH_1):PAGE517_I30@PASSIVE.CAPACITOR(CHIPS)':
 '2': CDS_PINID='\2\';
NODE_NAME     R40 2
 '@TIMECARD_LIB.TIMECARD(SCH_1):PAGE517_I31@PASSIVE.RESISTOR(CHIPS)':
 '2': CDS_PINID='\2\';
NODE_NAME     R54 2
 '@TIMECARD_LIB.TIMECARD(SCH_1):PAGE517_I41@PASSIVE.RESISTOR(CHIPS)':
 '2': CDS_PINID='\2\';
NODE_NAME     U6 14
 '@TIMECARD_LIB.TIMECARD(SCH_1):PAGE517_I42@STDLOGIC.TPS54824RNVR_VQFN18(CHIPS)':
 'FB': CDS_PINID='FB';
NET_NAME
'XP3R3V_FPGA'
 '@TIMECARD_LIB.TIMECARD(SCH_1):XP3R3V_FPGA':
 C_SIGNAL='@timecard_lib.timecard(sch_1):xp3r3v_fpga',
 CDS_GLOBAL_NET='TRUE';
NODE_NAME     C37 1
 '@TIMECARD_LIB.TIMECARD(SCH_1):PAGE3_I4@PASSIVE.CAPACITOR(CHIPS)':
 '1': CDS_PINID='\1\';
NODE_NAME     R20 1
 '@TIMECARD_LIB.TIMECARD(SCH_1):PAGE6_I14@PASSIVE.RESISTOR(CHIPS)':
 '1': CDS_PINID='\1\';
NODE_NAME     R21 1
 '@TIMECARD_LIB.TIMECARD(SCH_1):PAGE6_I16@PASSIVE.RESISTOR(CHIPS)':
 '1': CDS_PINID='\1\';
NODE_NAME     R333 1
 '@TIMECARD_LIB.TIMECARD(SCH_1):PAGE6_I31@PASSIVE.RESISTOR(CHIPS)':
 '1': CDS_PINID='\1\';
NODE_NAME     R335 1
 '@TIMECARD_LIB.TIMECARD(SCH_1):PAGE6_I35@PASSIVE.RESISTOR(CHIPS)':
 '1': CDS_PINID='\1\';
NODE_NAME     R337 1
 '@TIMECARD_LIB.TIMECARD(SCH_1):PAGE6_I36@PASSIVE.RESISTOR(CHIPS)':
 '1': CDS_PINID='\1\';
NODE_NAME     C39 2
 '@TIMECARD_LIB.TIMECARD(SCH_1):PAGE6_I37@PASSIVE.CAPACITOR(CHIPS)':
 '2': CDS_PINID='\2\';
NODE_NAME     U8 8
 '@TIMECARD_LIB.TIMECARD(SCH_1):PAGE6_I38@INTERFACE.LM75BDP_TSSOP8(CHIPS)':
 'VCC': CDS_PINID='VCC';
NODE_NAME     R340 1
 '@TIMECARD_LIB.TIMECARD(SCH_1):PAGE6_I41@PASSIVE.RESISTOR(CHIPS)':
 '1': CDS_PINID='\1\';
NODE_NAME     R64 1
 '@TIMECARD_LIB.TIMECARD(SCH_1):PAGE7_I3@PASSIVE.RESISTOR(CHIPS)':
 '1': CDS_PINID='\1\';
NODE_NAME     R65 1
 '@TIMECARD_LIB.TIMECARD(SCH_1):PAGE7_I4@PASSIVE.RESISTOR(CHIPS)':
 '1': CDS_PINID='\1\';
NODE_NAME     R68 1
 '@TIMECARD_LIB.TIMECARD(SCH_1):PAGE7_I8@PASSIVE.RESISTOR(CHIPS)':
 '1': CDS_PINID='\1\';
NODE_NAME     R74 1
 '@TIMECARD_LIB.TIMECARD(SCH_1):PAGE9_I6@PASSIVE.RESISTOR(CHIPS)':
 '1': CDS_PINID='\1\';
NODE_NAME     R75 1
 '@TIMECARD_LIB.TIMECARD(SCH_1):PAGE9_I7@PASSIVE.RESISTOR(CHIPS)':
 '1': CDS_PINID='\1\';
NODE_NAME     C17 1
 '@TIMECARD_LIB.TIMECARD(SCH_1):PAGE3_I92@PASSIVE.CAPACITOR(CHIPS)':
 '1': CDS_PINID='\1\';
NODE_NAME     U2 8
 '@TIMECARD_LIB.TIMECARD(SCH_1):PAGE3_I100@STDLOGIC.G220_10198_01(CHIPS)':
 'VCC': CDS_PINID='VCC';
NODE_NAME     R25 1
 '@TIMECARD_LIB.TIMECARD(SCH_1):PAGE3_I103@PASSIVE.RESISTOR(CHIPS)':
 '1': CDS_PINID='\1\';
NODE_NAME     R62 2
 '@TIMECARD_LIB.TIMECARD(SCH_1):PAGE5_I55@PASSIVE.RESISTOR(CHIPS)':
 '2': CDS_PINID='\2\';
NODE_NAME     R146 1
 '@TIMECARD_LIB.TIMECARD(SCH_1):PAGE5_I60@PASSIVE.RESISTOR(CHIPS)':
 '1': CDS_PINID='\1\';
NODE_NAME     R194 1
 '@TIMECARD_LIB.TIMECARD(SCH_1):PAGE127_I329@PASSIVE.RESISTOR(CHIPS)':
 '1': CDS_PINID='\1\';
NODE_NAME     R193 1
 '@TIMECARD_LIB.TIMECARD(SCH_1):PAGE127_I330@PASSIVE.RESISTOR(CHIPS)':
 '1': CDS_PINID='\1\';
NODE_NAME     R210 2
 '@TIMECARD_LIB.TIMECARD(SCH_1):PAGE127_I338@PASSIVE.RESISTOR(CHIPS)':
 '2': CDS_PINID='\2\';
NODE_NAME     R209 2
 '@TIMECARD_LIB.TIMECARD(SCH_1):PAGE127_I339@PASSIVE.RESISTOR(CHIPS)':
 '2': CDS_PINID='\2\';
NODE_NAME     R219 1
 '@TIMECARD_LIB.TIMECARD(SCH_1):PAGE127_I392@PASSIVE.RESISTOR(CHIPS)':
 '1': CDS_PINID='\1\';
NODE_NAME     R215 1
 '@TIMECARD_LIB.TIMECARD(SCH_1):PAGE127_I394@PASSIVE.RESISTOR(CHIPS)':
 '1': CDS_PINID='\1\';
NODE_NAME     R213 1
 '@TIMECARD_LIB.TIMECARD(SCH_1):PAGE127_I396@PASSIVE.RESISTOR(CHIPS)':
 '1': CDS_PINID='\1\';
NODE_NAME     R217 1
 '@TIMECARD_LIB.TIMECARD(SCH_1):PAGE127_I402@PASSIVE.RESISTOR(CHIPS)':
 '1': CDS_PINID='\1\';
NODE_NAME     R221 1
 '@TIMECARD_LIB.TIMECARD(SCH_1):PAGE127_I403@PASSIVE.RESISTOR(CHIPS)':
 '1': CDS_PINID='\1\';
NODE_NAME     R211 1
 '@TIMECARD_LIB.TIMECARD(SCH_1):PAGE127_I404@PASSIVE.RESISTOR(CHIPS)':
 '1': CDS_PINID='\1\';
NODE_NAME     U24 F12
 '@TIMECARD_LIB.TIMECARD(SCH_1):PAGE164_I138@PLD.XC7A200T_2FBG484C_FBG484(CHIPS)':
 'VCCO_0_1': CDS_PINID='VCCO_0_1';
NODE_NAME     U24 T12
 '@TIMECARD_LIB.TIMECARD(SCH_1):PAGE164_I138@PLD.XC7A200T_2FBG484C_FBG484(CHIPS)':
 'VCCO_0_2': CDS_PINID='VCCO_0_2';
NODE_NAME     U24 AA17
 '@TIMECARD_LIB.TIMECARD(SCH_1):PAGE164_I138@PLD.XC7A200T_2FBG484C_FBG484(CHIPS)':
 'VCCO_13_1': CDS_PINID='VCCO_13_1';
NODE_NAME     U24 AB14
 '@TIMECARD_LIB.TIMECARD(SCH_1):PAGE164_I138@PLD.XC7A200T_2FBG484C_FBG484(CHIPS)':
 'VCCO_13_2': CDS_PINID='VCCO_13_2';
NODE_NAME     U24 V16
 '@TIMECARD_LIB.TIMECARD(SCH_1):PAGE164_I138@PLD.XC7A200T_2FBG484C_FBG484(CHIPS)':
 'VCCO_13_3': CDS_PINID='VCCO_13_3';
NODE_NAME     U24 W13
 '@TIMECARD_LIB.TIMECARD(SCH_1):PAGE164_I138@PLD.XC7A200T_2FBG484C_FBG484(CHIPS)':
 'VCCO_13_4': CDS_PINID='VCCO_13_4';
NODE_NAME     U24 Y10
 '@TIMECARD_LIB.TIMECARD(SCH_1):PAGE164_I138@PLD.XC7A200T_2FBG484C_FBG484(CHIPS)':
 'VCCO_13_5': CDS_PINID='VCCO_13_5';
NODE_NAME     U24 M14
 '@TIMECARD_LIB.TIMECARD(SCH_1):PAGE164_I138@PLD.XC7A200T_2FBG484C_FBG484(CHIPS)':
 'VCCO_14_1': CDS_PINID='VCCO_14_1';
NODE_NAME     U24 P18
 '@TIMECARD_LIB.TIMECARD(SCH_1):PAGE164_I138@PLD.XC7A200T_2FBG484C_FBG484(CHIPS)':
 'VCCO_14_2': CDS_PINID='VCCO_14_2';
NODE_NAME     U24 R15
 '@TIMECARD_LIB.TIMECARD(SCH_1):PAGE164_I138@PLD.XC7A200T_2FBG484C_FBG484(CHIPS)':
 'VCCO_14_3': CDS_PINID='VCCO_14_3';
NODE_NAME     U24 T22
 '@TIMECARD_LIB.TIMECARD(SCH_1):PAGE164_I138@PLD.XC7A200T_2FBG484C_FBG484(CHIPS)':
 'VCCO_14_4': CDS_PINID='VCCO_14_4';
NODE_NAME     U24 U19
 '@TIMECARD_LIB.TIMECARD(SCH_1):PAGE164_I138@PLD.XC7A200T_2FBG484C_FBG484(CHIPS)':
 'VCCO_14_5': CDS_PINID='VCCO_14_5';
NODE_NAME     U24 Y20
 '@TIMECARD_LIB.TIMECARD(SCH_1):PAGE164_I138@PLD.XC7A200T_2FBG484C_FBG484(CHIPS)':
 'VCCO_14_6': CDS_PINID='VCCO_14_6';
NODE_NAME     U24 G19
 '@TIMECARD_LIB.TIMECARD(SCH_1):PAGE164_I138@PLD.XC7A200T_2FBG484C_FBG484(CHIPS)':
 'VCCO_15_1': CDS_PINID='VCCO_15_1';
NODE_NAME     U24 H16
 '@TIMECARD_LIB.TIMECARD(SCH_1):PAGE164_I138@PLD.XC7A200T_2FBG484C_FBG484(CHIPS)':
 'VCCO_15_2': CDS_PINID='VCCO_15_2';
NODE_NAME     U24 J13
 '@TIMECARD_LIB.TIMECARD(SCH_1):PAGE164_I138@PLD.XC7A200T_2FBG484C_FBG484(CHIPS)':
 'VCCO_15_3': CDS_PINID='VCCO_15_3';
NODE_NAME     U24 K20
 '@TIMECARD_LIB.TIMECARD(SCH_1):PAGE164_I138@PLD.XC7A200T_2FBG484C_FBG484(CHIPS)':
 'VCCO_15_4': CDS_PINID='VCCO_15_4';
NODE_NAME     U24 L17
 '@TIMECARD_LIB.TIMECARD(SCH_1):PAGE164_I138@PLD.XC7A200T_2FBG484C_FBG484(CHIPS)':
 'VCCO_15_5': CDS_PINID='VCCO_15_5';
NODE_NAME     U24 N21
 '@TIMECARD_LIB.TIMECARD(SCH_1):PAGE164_I138@PLD.XC7A200T_2FBG484C_FBG484(CHIPS)':
 'VCCO_15_6': CDS_PINID='VCCO_15_6';
NODE_NAME     U24 A17
 '@TIMECARD_LIB.TIMECARD(SCH_1):PAGE164_I138@PLD.XC7A200T_2FBG484C_FBG484(CHIPS)':
 'VCCO_16_1': CDS_PINID='VCCO_16_1';
NODE_NAME     U24 B14
 '@TIMECARD_LIB.TIMECARD(SCH_1):PAGE164_I138@PLD.XC7A200T_2FBG484C_FBG484(CHIPS)':
 'VCCO_16_2': CDS_PINID='VCCO_16_2';
NODE_NAME     U24 C21
 '@TIMECARD_LIB.TIMECARD(SCH_1):PAGE164_I138@PLD.XC7A200T_2FBG484C_FBG484(CHIPS)':
 'VCCO_16_3': CDS_PINID='VCCO_16_3';
NODE_NAME     U24 D18
 '@TIMECARD_LIB.TIMECARD(SCH_1):PAGE164_I138@PLD.XC7A200T_2FBG484C_FBG484(CHIPS)':
 'VCCO_16_4': CDS_PINID='VCCO_16_4';
NODE_NAME     U24 E15
 '@TIMECARD_LIB.TIMECARD(SCH_1):PAGE164_I138@PLD.XC7A200T_2FBG484C_FBG484(CHIPS)':
 'VCCO_16_5': CDS_PINID='VCCO_16_5';
NODE_NAME     U24 F22
 '@TIMECARD_LIB.TIMECARD(SCH_1):PAGE164_I138@PLD.XC7A200T_2FBG484C_FBG484(CHIPS)':
 'VCCO_16_6': CDS_PINID='VCCO_16_6';
NODE_NAME     C172 1
 '@TIMECARD_LIB.TIMECARD(SCH_1):PAGE164_I174@PASSIVE.CAPACITOR(CHIPS)':
 '1': CDS_PINID='\1\';
NODE_NAME     C174 1
 '@TIMECARD_LIB.TIMECARD(SCH_1):PAGE164_I178@PASSIVE.CAPACITOR(CHIPS)':
 '1': CDS_PINID='\1\';
NODE_NAME     C202 1
 '@TIMECARD_LIB.TIMECARD(SCH_1):PAGE164_I205@PASSIVE.CAPACITOR(CHIPS)':
 '1': CDS_PINID='\1\';
NODE_NAME     C210 1
 '@TIMECARD_LIB.TIMECARD(SCH_1):PAGE164_I206@PASSIVE.CAPACITOR(CHIPS)':
 '1': CDS_PINID='\1\';
NODE_NAME     C215 1
 '@TIMECARD_LIB.TIMECARD(SCH_1):PAGE164_I207@PASSIVE.CAPACITOR(CHIPS)':
 '1': CDS_PINID='\1\';
NODE_NAME     C103 1
 '@TIMECARD_LIB.TIMECARD(SCH_1):PAGE164_I208@PASSIVE.CAPACITOR(CHIPS)':
 '1': CDS_PINID='\1\';
NODE_NAME     C112 1
 '@TIMECARD_LIB.TIMECARD(SCH_1):PAGE164_I209@PASSIVE.CAPACITOR(CHIPS)':
 '1': CDS_PINID='\1\';
NODE_NAME     C119 1
 '@TIMECARD_LIB.TIMECARD(SCH_1):PAGE164_I210@PASSIVE.CAPACITOR(CHIPS)':
 '1': CDS_PINID='\1\';
NODE_NAME     C126 1
 '@TIMECARD_LIB.TIMECARD(SCH_1):PAGE164_I211@PASSIVE.CAPACITOR(CHIPS)':
 '1': CDS_PINID='\1\';
NODE_NAME     C132 1
 '@TIMECARD_LIB.TIMECARD(SCH_1):PAGE164_I212@PASSIVE.CAPACITOR(CHIPS)':
 '1': CDS_PINID='\1\';
NODE_NAME     C139 1
 '@TIMECARD_LIB.TIMECARD(SCH_1):PAGE164_I213@PASSIVE.CAPACITOR(CHIPS)':
 '1': CDS_PINID='\1\';
NODE_NAME     C144 1
 '@TIMECARD_LIB.TIMECARD(SCH_1):PAGE164_I214@PASSIVE.CAPACITOR(CHIPS)':
 '1': CDS_PINID='\1\';
NODE_NAME     C149 1
 '@TIMECARD_LIB.TIMECARD(SCH_1):PAGE164_I215@PASSIVE.CAPACITOR(CHIPS)':
 '1': CDS_PINID='\1\';
NODE_NAME     C203 1
 '@TIMECARD_LIB.TIMECARD(SCH_1):PAGE164_I216@PASSIVE.CAPACITOR(CHIPS)':
 '1': CDS_PINID='\1\';
NODE_NAME     C211 1
 '@TIMECARD_LIB.TIMECARD(SCH_1):PAGE164_I217@PASSIVE.CAPACITOR(CHIPS)':
 '1': CDS_PINID='\1\';
NODE_NAME     C216 1
 '@TIMECARD_LIB.TIMECARD(SCH_1):PAGE164_I218@PASSIVE.CAPACITOR(CHIPS)':
 '1': CDS_PINID='\1\';
NODE_NAME     C221 1
 '@TIMECARD_LIB.TIMECARD(SCH_1):PAGE164_I219@PASSIVE.CAPACITOR(CHIPS)':
 '1': CDS_PINID='\1\';
NODE_NAME     C107 1
 '@TIMECARD_LIB.TIMECARD(SCH_1):PAGE164_I220@PASSIVE.CAPACITOR(CHIPS)':
 '1': CDS_PINID='\1\';
NODE_NAME     C115 1
 '@TIMECARD_LIB.TIMECARD(SCH_1):PAGE164_I221@PASSIVE.CAPACITOR(CHIPS)':
 '1': CDS_PINID='\1\';
NODE_NAME     C223 1
 '@TIMECARD_LIB.TIMECARD(SCH_1):PAGE164_I222@PASSIVE.CAPACITOR(CHIPS)':
 '1': CDS_PINID='\1\';
NODE_NAME     C130 1
 '@TIMECARD_LIB.TIMECARD(SCH_1):PAGE164_I223@PASSIVE.CAPACITOR(CHIPS)':
 '1': CDS_PINID='\1\';
NODE_NAME     C134 1
 '@TIMECARD_LIB.TIMECARD(SCH_1):PAGE164_I224@PASSIVE.CAPACITOR(CHIPS)':
 '1': CDS_PINID='\1\';
NODE_NAME     C140 1
 '@TIMECARD_LIB.TIMECARD(SCH_1):PAGE164_I225@PASSIVE.CAPACITOR(CHIPS)':
 '1': CDS_PINID='\1\';
NODE_NAME     C145 1
 '@TIMECARD_LIB.TIMECARD(SCH_1):PAGE164_I226@PASSIVE.CAPACITOR(CHIPS)':
 '1': CDS_PINID='\1\';
NODE_NAME     C153 1
 '@TIMECARD_LIB.TIMECARD(SCH_1):PAGE164_I227@PASSIVE.CAPACITOR(CHIPS)':
 '1': CDS_PINID='\1\';
NODE_NAME     C157 1
 '@TIMECARD_LIB.TIMECARD(SCH_1):PAGE164_I228@PASSIVE.CAPACITOR(CHIPS)':
 '1': CDS_PINID='\1\';
NODE_NAME     C162 1
 '@TIMECARD_LIB.TIMECARD(SCH_1):PAGE164_I229@PASSIVE.CAPACITOR(CHIPS)':
 '1': CDS_PINID='\1\';
NODE_NAME     C165 1
 '@TIMECARD_LIB.TIMECARD(SCH_1):PAGE164_I230@PASSIVE.CAPACITOR(CHIPS)':
 '1': CDS_PINID='\1\';
NODE_NAME     C154 1
 '@TIMECARD_LIB.TIMECARD(SCH_1):PAGE164_I270@PASSIVE.CAPACITOR(CHIPS)':
 '1': CDS_PINID='\1\';
NODE_NAME     C159 1
 '@TIMECARD_LIB.TIMECARD(SCH_1):PAGE164_I271@PASSIVE.CAPACITOR(CHIPS)':
 '1': CDS_PINID='\1\';
NODE_NAME     C163 1
 '@TIMECARD_LIB.TIMECARD(SCH_1):PAGE164_I272@PASSIVE.CAPACITOR(CHIPS)':
 '1': CDS_PINID='\1\';
NODE_NAME     C167 1
 '@TIMECARD_LIB.TIMECARD(SCH_1):PAGE164_I273@PASSIVE.CAPACITOR(CHIPS)':
 '1': CDS_PINID='\1\';
NODE_NAME     C170 1
 '@TIMECARD_LIB.TIMECARD(SCH_1):PAGE164_I282@PASSIVE.CAPACITOR(CHIPS)':
 '1': CDS_PINID='\1\';
NODE_NAME     C237 1
 '@TIMECARD_LIB.TIMECARD(SCH_1):PAGE515_I64@PASSIVE.CAPACITOR(CHIPS)':
 '1': CDS_PINID='\1\';
NODE_NAME     R295 1
 '@TIMECARD_LIB.TIMECARD(SCH_1):PAGE515_I69@PASSIVE.RESISTOR(CHIPS)':
 '1': CDS_PINID='\1\';
NODE_NAME     C240 1
 '@TIMECARD_LIB.TIMECARD(SCH_1):PAGE515_I71@PASSIVE.CAPACITOR(CHIPS)':
 '1': CDS_PINID='\1\';
NODE_NAME     C241 1
 '@TIMECARD_LIB.TIMECARD(SCH_1):PAGE515_I72@PASSIVE.CAPACITOR(CHIPS)':
 '1': CDS_PINID='\1\';
NODE_NAME     C243 1
 '@TIMECARD_LIB.TIMECARD(SCH_1):PAGE515_I74@PASSIVE.CAPACITOR(CHIPS)':
 '1': CDS_PINID='\1\';
NODE_NAME     C238 1
 '@TIMECARD_LIB.TIMECARD(SCH_1):PAGE515_I81@PASSIVE.CAPACITOR(CHIPS)':
 '1': CDS_PINID='\1\';
NODE_NAME     U22 7
 '@TIMECARD_LIB.TIMECARD(SCH_1):PAGE515_I82@ANALOG.NCP45560IMNTWG_H_DFN12(CHIPS)':
 'BLEED': CDS_PINID='BLEED';
NODE_NAME     U22 8
 '@TIMECARD_LIB.TIMECARD(SCH_1):PAGE515_I82@ANALOG.NCP45560IMNTWG_H_DFN12(CHIPS)':
 'VOUT_1': CDS_PINID='VOUT_1';
NODE_NAME     U22 9
 '@TIMECARD_LIB.TIMECARD(SCH_1):PAGE515_I82@ANALOG.NCP45560IMNTWG_H_DFN12(CHIPS)':
 'VOUT_2': CDS_PINID='VOUT_2';
NODE_NAME     U22 10
 '@TIMECARD_LIB.TIMECARD(SCH_1):PAGE515_I82@ANALOG.NCP45560IMNTWG_H_DFN12(CHIPS)':
 'VOUT_3': CDS_PINID='VOUT_3';
NODE_NAME     U22 11
 '@TIMECARD_LIB.TIMECARD(SCH_1):PAGE515_I82@ANALOG.NCP45560IMNTWG_H_DFN12(CHIPS)':
 'VOUT_4': CDS_PINID='VOUT_4';
NODE_NAME     U22 12
 '@TIMECARD_LIB.TIMECARD(SCH_1):PAGE515_I82@ANALOG.NCP45560IMNTWG_H_DFN12(CHIPS)':
 'VOUT_5': CDS_PINID='VOUT_5';
NODE_NAME     R229 1
 '@TIMECARD_LIB.TIMECARD(SCH_1):PAGE515_I139@PASSIVE.RESISTOR(CHIPS)':
 '1': CDS_PINID='\1\';
NODE_NAME     R138 2
 '@TIMECARD_LIB.TIMECARD(SCH_1):PAGE14_I63@PASSIVE.RESISTOR(CHIPS)':
 '2': CDS_PINID='\2\';
NODE_NAME     R257 2
 '@TIMECARD_LIB.TIMECARD(SCH_1):PAGE14_I67@PASSIVE.RESISTOR(CHIPS)':
 '2': CDS_PINID='\2\';
NODE_NAME     R258 2
 '@TIMECARD_LIB.TIMECARD(SCH_1):PAGE14_I68@PASSIVE.RESISTOR(CHIPS)':
 '2': CDS_PINID='\2\';
NODE_NAME     R259 2
 '@TIMECARD_LIB.TIMECARD(SCH_1):PAGE14_I69@PASSIVE.RESISTOR(CHIPS)':
 '2': CDS_PINID='\2\';
NODE_NAME     R261 2
 '@TIMECARD_LIB.TIMECARD(SCH_1):PAGE14_I70@PASSIVE.RESISTOR(CHIPS)':
 '2': CDS_PINID='\2\';
NODE_NAME     R268 1
 '@TIMECARD_LIB.TIMECARD(SCH_1):PAGE11_I38@PASSIVE.RESISTOR(CHIPS)':
 '1': CDS_PINID='\1\';
NODE_NAME     R269 1
 '@TIMECARD_LIB.TIMECARD(SCH_1):PAGE11_I40@PASSIVE.RESISTOR(CHIPS)':
 '1': CDS_PINID='\1\';
NODE_NAME     C81 1
 '@TIMECARD_LIB.TIMECARD(SCH_1):PAGE11_I43@PASSIVE.CAPACITOR(CHIPS)':
 '1': CDS_PINID='\1\';
NODE_NAME     L19 2
 '@TIMECARD_LIB.TIMECARD(SCH_1):PAGE9_I22@PASSIVE.FERRITEBEAD(CHIPS)':
 '2': CDS_PINID='\2\';
NODE_NAME     C40 1
 '@TIMECARD_LIB.TIMECARD(SCH_1):PAGE7_I18@PASSIVE.CAPACITOR(CHIPS)':
 '1': CDS_PINID='\1\';
NODE_NAME     C279 1
 '@TIMECARD_LIB.TIMECARD(SCH_1):PAGE9_I21@PASSIVE.CAPACITOR(CHIPS)':
 '1': CDS_PINID='\1\';
NODE_NAME     L17 1
 '@TIMECARD_LIB.TIMECARD(SCH_1):PAGE7_I21@PASSIVE.FERRITEBEAD(CHIPS)':
 '1': CDS_PINID='\1\';
NODE_NAME     R279 2
 '@TIMECARD_LIB.TIMECARD(SCH_1):PAGE14_I72@PASSIVE.RESISTOR(CHIPS)':
 '2': CDS_PINID='\2\';
NODE_NAME     R280 2
 '@TIMECARD_LIB.TIMECARD(SCH_1):PAGE14_I74@PASSIVE.RESISTOR(CHIPS)':
 '2': CDS_PINID='\2\';
NODE_NAME     TP58 1
 '@TIMECARD_LIB.TIMECARD(SCH_1):PAGE16_I1219@CLS.TP_PIONT(CHIPS)':
 '1': CDS_PINID='\1\';
NODE_NAME     R296 1
 '@TIMECARD_LIB.TIMECARD(SCH_1):PAGE7_I38@PASSIVE.RESISTOR(CHIPS)':
 '1': CDS_PINID='\1\';
NODE_NAME     R300 1
 '@TIMECARD_LIB.TIMECARD(SCH_1):PAGE7_I41@PASSIVE.RESISTOR(CHIPS)':
 '1': CDS_PINID='\1\';
NODE_NAME     R304 1
 '@TIMECARD_LIB.TIMECARD(SCH_1):PAGE9_I37@PASSIVE.RESISTOR(CHIPS)':
 '1': CDS_PINID='\1\';
NODE_NAME     R289 1
 '@TIMECARD_LIB.TIMECARD(SCH_1):PAGE9_I38@PASSIVE.RESISTOR(CHIPS)':
 '1': CDS_PINID='\1\';
NODE_NAME     R291 1
 '@TIMECARD_LIB.TIMECARD(SCH_1):PAGE9_I44@PASSIVE.RESISTOR(CHIPS)':
 '1': CDS_PINID='\1\';
NODE_NAME     R290 1
 '@TIMECARD_LIB.TIMECARD(SCH_1):PAGE9_I51@PASSIVE.RESISTOR(CHIPS)':
 '1': CDS_PINID='\1\';
NODE_NAME     R306 1
 '@TIMECARD_LIB.TIMECARD(SCH_1):PAGE9_I55@PASSIVE.RESISTOR(CHIPS)':
 '1': CDS_PINID='\1\';
NODE_NAME     R341 1
 '@TIMECARD_LIB.TIMECARD(SCH_1):PAGE9_I65@PASSIVE.RESISTOR(CHIPS)':
 '1': CDS_PINID='\1\';
NODE_NAME     R342 1
 '@TIMECARD_LIB.TIMECARD(SCH_1):PAGE9_I66@PASSIVE.RESISTOR(CHIPS)':
 '1': CDS_PINID='\1\';
NODE_NAME     R365 1
 '@TIMECARD_LIB.TIMECARD(SCH_1):PAGE12_I88@PASSIVE.RESISTOR(CHIPS)':
 '1': CDS_PINID='\1\';
NODE_NAME     R147 1
 '@TIMECARD_LIB.TIMECARD(SCH_1):PAGE5_I80@PASSIVE.RESISTOR(CHIPS)':
 '1': CDS_PINID='\1\';
NODE_NAME     R148 1
 '@TIMECARD_LIB.TIMECARD(SCH_1):PAGE5_I81@PASSIVE.RESISTOR(CHIPS)':
 '1': CDS_PINID='\1\';
NODE_NAME     R149 1
 '@TIMECARD_LIB.TIMECARD(SCH_1):PAGE5_I82@PASSIVE.RESISTOR(CHIPS)':
 '1': CDS_PINID='\1\';
NODE_NAME     R150 1
 '@TIMECARD_LIB.TIMECARD(SCH_1):PAGE5_I83@PASSIVE.RESISTOR(CHIPS)':
 '1': CDS_PINID='\1\';
NODE_NAME     R151 1
 '@TIMECARD_LIB.TIMECARD(SCH_1):PAGE5_I84@PASSIVE.RESISTOR(CHIPS)':
 '1': CDS_PINID='\1\';
NODE_NAME     U7 4
 '@TIMECARD_LIB.TIMECARD(SCH_1):PAGE5_I89@MEMORY.AT24MAC402_SOT23_5(CHIPS)':
 'VCC': CDS_PINID='VCC';
NODE_NAME     C225 1
 '@TIMECARD_LIB.TIMECARD(SCH_1):PAGE5_I92@PASSIVE.CAPACITOR(CHIPS)':
 '1': CDS_PINID='\1\';
NODE_NAME     R1992 1
 '@TIMECARD_LIB.TIMECARD(SCH_1):PAGE5_I94@PASSIVE.RESISTOR(CHIPS)':
 '1': CDS_PINID='\1\';
NODE_NAME     R19 1
 '@TIMECARD_LIB.TIMECARD(SCH_1):PAGE5_I95@PASSIVE.RESISTOR(CHIPS)':
 '1': CDS_PINID='\1\';
NODE_NAME     R1991 1
 '@TIMECARD_LIB.TIMECARD(SCH_1):PAGE5_I96@PASSIVE.RESISTOR(CHIPS)':
 '1': CDS_PINID='\1\';
NODE_NAME     R422 1
 '@TIMECARD_LIB.TIMECARD(SCH_1):PAGE6_I64@PASSIVE.RESISTOR(CHIPS)':
 '1': CDS_PINID='\1\';
NODE_NAME     U36 8
 '@TIMECARD_LIB.TIMECARD(SCH_1):PAGE6_I66@INTERFACE.LM75BDP_TSSOP8(CHIPS)':
 'VCC': CDS_PINID='VCC';
NODE_NAME     C305 2
 '@TIMECARD_LIB.TIMECARD(SCH_1):PAGE6_I67@PASSIVE.CAPACITOR(CHIPS)':
 '2': CDS_PINID='\2\';
NODE_NAME     R418 1
 '@TIMECARD_LIB.TIMECARD(SCH_1):PAGE6_I69@PASSIVE.RESISTOR(CHIPS)':
 '1': CDS_PINID='\1\';
NODE_NAME     R412 1
 '@TIMECARD_LIB.TIMECARD(SCH_1):PAGE6_I70@PASSIVE.RESISTOR(CHIPS)':
 '1': CDS_PINID='\1\';
NODE_NAME     R408 1
 '@TIMECARD_LIB.TIMECARD(SCH_1):PAGE6_I71@PASSIVE.RESISTOR(CHIPS)':
 '1': CDS_PINID='\1\';
NODE_NAME     R419 1
 '@TIMECARD_LIB.TIMECARD(SCH_1):PAGE6_I84@PASSIVE.RESISTOR(CHIPS)':
 '1': CDS_PINID='\1\';
NODE_NAME     R414 1
 '@TIMECARD_LIB.TIMECARD(SCH_1):PAGE6_I85@PASSIVE.RESISTOR(CHIPS)':
 '1': CDS_PINID='\1\';
NODE_NAME     R410 1
 '@TIMECARD_LIB.TIMECARD(SCH_1):PAGE6_I86@PASSIVE.RESISTOR(CHIPS)':
 '1': CDS_PINID='\1\';
NODE_NAME     R423 1
 '@TIMECARD_LIB.TIMECARD(SCH_1):PAGE6_I88@PASSIVE.RESISTOR(CHIPS)':
 '1': CDS_PINID='\1\';
NODE_NAME     U35 8
 '@TIMECARD_LIB.TIMECARD(SCH_1):PAGE6_I90@INTERFACE.LM75BDP_TSSOP8(CHIPS)':
 'VCC': CDS_PINID='VCC';
NODE_NAME     C306 2
 '@TIMECARD_LIB.TIMECARD(SCH_1):PAGE6_I91@PASSIVE.CAPACITOR(CHIPS)':
 '2': CDS_PINID='\2\';
NODE_NAME     R405 1
 '@TIMECARD_LIB.TIMECARD(SCH_1):PAGE127_I432@PASSIVE.RESISTOR(CHIPS)':
 '1': CDS_PINID='\1\';
NODE_NAME     R404 1
 '@TIMECARD_LIB.TIMECARD(SCH_1):PAGE127_I434@PASSIVE.RESISTOR(CHIPS)':
 '1': CDS_PINID='\1\';
NODE_NAME     R403 1
 '@TIMECARD_LIB.TIMECARD(SCH_1):PAGE127_I435@PASSIVE.RESISTOR(CHIPS)':
 '1': CDS_PINID='\1\';
NODE_NAME     R133 1
 '@TIMECARD_LIB.TIMECARD(SCH_1):PAGE127_I446@PASSIVE.RESISTOR(CHIPS)':
 '1': CDS_PINID='\1\';
NODE_NAME     U13 8
 '@TIMECARD_LIB.TIMECARD(SCH_1):PAGE12_I204@STDLOGIC.74HCT2G125DP_TSSOP8(CHIPS)':
 'VCC': CDS_PINID='VCC';
NODE_NAME     R377 1
 '@TIMECARD_LIB.TIMECARD(SCH_1):PAGE12_I206@PASSIVE.RESISTOR(CHIPS)':
 '1': CDS_PINID='\1\';
NODE_NAME     C83 1
 '@TIMECARD_LIB.TIMECARD(SCH_1):PAGE12_I207@PASSIVE.CAPACITOR(CHIPS)':
 '1': CDS_PINID='\1\';
NODE_NAME     U14 8
 '@TIMECARD_LIB.TIMECARD(SCH_1):PAGE12_I226@STDLOGIC.74HCT2G125DP_TSSOP8(CHIPS)':
 'VCC': CDS_PINID='VCC';
NODE_NAME     C82 1
 '@TIMECARD_LIB.TIMECARD(SCH_1):PAGE12_I231@PASSIVE.CAPACITOR(CHIPS)':
 '1': CDS_PINID='\1\';
NODE_NAME     R368 1
 '@TIMECARD_LIB.TIMECARD(SCH_1):PAGE12_I233@PASSIVE.RESISTOR(CHIPS)':
 '1': CDS_PINID='\1\';
NODE_NAME     R379 1
 '@TIMECARD_LIB.TIMECARD(SCH_1):PAGE12_I234@PASSIVE.RESISTOR(CHIPS)':
 '1': CDS_PINID='\1\';
NODE_NAME     U15 8
 '@TIMECARD_LIB.TIMECARD(SCH_1):PAGE12_I255@STDLOGIC.74HCT2G125DP_TSSOP8(CHIPS)':
 'VCC': CDS_PINID='VCC';
NODE_NAME     R361 1
 '@TIMECARD_LIB.TIMECARD(SCH_1):PAGE12_I261@PASSIVE.RESISTOR(CHIPS)':
 '1': CDS_PINID='\1\';
NODE_NAME     R381 1
 '@TIMECARD_LIB.TIMECARD(SCH_1):PAGE12_I262@PASSIVE.RESISTOR(CHIPS)':
 '1': CDS_PINID='\1\';
NODE_NAME     C85 1
 '@TIMECARD_LIB.TIMECARD(SCH_1):PAGE12_I272@PASSIVE.CAPACITOR(CHIPS)':
 '1': CDS_PINID='\1\';
NODE_NAME     U16 8
 '@TIMECARD_LIB.TIMECARD(SCH_1):PAGE12_I273@STDLOGIC.74HCT2G125DP_TSSOP8(CHIPS)':
 'VCC': CDS_PINID='VCC';
NODE_NAME     R331 1
 '@TIMECARD_LIB.TIMECARD(SCH_1):PAGE12_I280@PASSIVE.RESISTOR(CHIPS)':
 '1': CDS_PINID='\1\';
NODE_NAME     R383 1
 '@TIMECARD_LIB.TIMECARD(SCH_1):PAGE12_I281@PASSIVE.RESISTOR(CHIPS)':
 '1': CDS_PINID='\1\';
NODE_NAME     C84 1
 '@TIMECARD_LIB.TIMECARD(SCH_1):PAGE12_I289@PASSIVE.CAPACITOR(CHIPS)':
 '1': CDS_PINID='\1\';
NODE_NAME     U33 3
 '@TIMECARD_LIB.TIMECARD(SCH_1):PAGE14_I219@INTERFACE.IS32FL3207_QWLA3_TR_QFN29(CHIPS)':
 'VCC': CDS_PINID='VCC';
NODE_NAME     C315 1
 '@TIMECARD_LIB.TIMECARD(SCH_1):PAGE14_I237@PASSIVE.CAPACITOR(CHIPS)':
 '1': CDS_PINID='\1\';
NODE_NAME     C314 1
 '@TIMECARD_LIB.TIMECARD(SCH_1):PAGE14_I238@PASSIVE.CAPACITOR(CHIPS)':
 '1': CDS_PINID='\1\';
NODE_NAME     R317 1
 '@TIMECARD_LIB.TIMECARD(SCH_1):PAGE14_I259@PASSIVE.RESISTOR(CHIPS)':
 '1': CDS_PINID='\1\';
NODE_NAME     R318 1
 '@TIMECARD_LIB.TIMECARD(SCH_1):PAGE14_I261@PASSIVE.RESISTOR(CHIPS)':
 '1': CDS_PINID='\1\';
NODE_NAME     R282 1
 '@TIMECARD_LIB.TIMECARD(SCH_1):PAGE8_I69@PASSIVE.RESISTOR(CHIPS)':
 '1': CDS_PINID='\1\';
NODE_NAME     R281 1
 '@TIMECARD_LIB.TIMECARD(SCH_1):PAGE8_I70@PASSIVE.RESISTOR(CHIPS)':
 '1': CDS_PINID='\1\';
NODE_NAME     R320 1
 '@TIMECARD_LIB.TIMECARD(SCH_1):PAGE14_I264@PASSIVE.RESISTOR(CHIPS)':
 '1': CDS_PINID='\1\';
NODE_NAME     DS14 2
 '@TIMECARD_LIB.TIMECARD(SCH_1):PAGE14_I265@DISCRETE.LED_4P_V14(CHIPS)':
 '2': CDS_PINID='\2\';
NODE_NAME     DS15 2
 '@TIMECARD_LIB.TIMECARD(SCH_1):PAGE14_I266@DISCRETE.LED_4P_V14(CHIPS)':
 '2': CDS_PINID='\2\';
NODE_NAME     DS16 2
 '@TIMECARD_LIB.TIMECARD(SCH_1):PAGE14_I267@DISCRETE.LED_4P_V14(CHIPS)':
 '2': CDS_PINID='\2\';
NODE_NAME     DS17 2
 '@TIMECARD_LIB.TIMECARD(SCH_1):PAGE14_I268@DISCRETE.LED_4P_V14(CHIPS)':
 '2': CDS_PINID='\2\';
NODE_NAME     DS18 2
 '@TIMECARD_LIB.TIMECARD(SCH_1):PAGE14_I269@DISCRETE.LED_4P_V14(CHIPS)':
 '2': CDS_PINID='\2\';
NODE_NAME     R314 1
 '@TIMECARD_LIB.TIMECARD(SCH_1):PAGE8_I71@PASSIVE.RESISTOR(CHIPS)':
 '1': CDS_PINID='\1\';
NODE_NAME     U3 5
 '@TIMECARD_LIB.TIMECARD(SCH_1):PAGE3_I135@STDLOGIC.74LVC1G07_SC70_5(CHIPS)':
 'VCC': CDS_PINID='VCC';
NODE_NAME     R325 1
 '@TIMECARD_LIB.TIMECARD(SCH_1):PAGE16_I1602@PASSIVE.RESISTOR(CHIPS)':
 '1': CDS_PINID='\1\';
NODE_NAME     R327 1
 '@TIMECARD_LIB.TIMECARD(SCH_1):PAGE16_I1603@PASSIVE.RESISTOR(CHIPS)':
 '1': CDS_PINID='\1\';
NODE_NAME     R308 1
 '@TIMECARD_LIB.TIMECARD(SCH_1):PAGE16_I1604@PASSIVE.RESISTOR(CHIPS)':
 '1': CDS_PINID='\1\';
NODE_NAME     R292 1
 '@TIMECARD_LIB.TIMECARD(SCH_1):PAGE16_I1605@PASSIVE.RESISTOR(CHIPS)':
 '1': CDS_PINID='\1\';
NODE_NAME     R285 1
 '@TIMECARD_LIB.TIMECARD(SCH_1):PAGE16_I1606@PASSIVE.RESISTOR(CHIPS)':
 '1': CDS_PINID='\1\';
NODE_NAME     R172 1
 '@TIMECARD_LIB.TIMECARD(SCH_1):PAGE16_I1607@PASSIVE.RESISTOR(CHIPS)':
 '1': CDS_PINID='\1\';
NODE_NAME     R170 1
 '@TIMECARD_LIB.TIMECARD(SCH_1):PAGE16_I1608@PASSIVE.RESISTOR(CHIPS)':
 '1': CDS_PINID='\1\';
NODE_NAME     R283 1
 '@TIMECARD_LIB.TIMECARD(SCH_1):PAGE16_I1609@PASSIVE.RESISTOR(CHIPS)':
 '1': CDS_PINID='\1\';
NODE_NAME     U19 8
 '@TIMECARD_LIB.TIMECARD(SCH_1):PAGE5_I148@MEMORY.24LC16BT_I_ST_TSSOP8(CHIPS)':
 'VCC': CDS_PINID='VCC';
NODE_NAME     R158 1
 '@TIMECARD_LIB.TIMECARD(SCH_1):PAGE5_I153@PASSIVE.RESISTOR(CHIPS)':
 '1': CDS_PINID='\1\';
NODE_NAME     R160 1
 '@TIMECARD_LIB.TIMECARD(SCH_1):PAGE5_I160@PASSIVE.RESISTOR(CHIPS)':
 '1': CDS_PINID='\1\';
NODE_NAME     R162 1
 '@TIMECARD_LIB.TIMECARD(SCH_1):PAGE5_I161@PASSIVE.RESISTOR(CHIPS)':
 '1': CDS_PINID='\1\';
NODE_NAME     R3 1
 '@TIMECARD_LIB.TIMECARD(SCH_1):PAGE5_I169@PASSIVE.RESISTOR(CHIPS)':
 '1': CDS_PINID='\1\';
NODE_NAME     C1 1
 '@TIMECARD_LIB.TIMECARD(SCH_1):PAGE5_I171@PASSIVE.CAPACITOR(CHIPS)':
 '1': CDS_PINID='\1\';
NODE_NAME     L24 1
 '@TIMECARD_LIB.TIMECARD(SCH_1):PAGE525_I108@PASSIVE.FERRITEBEAD(CHIPS)':
 '1': CDS_PINID='\1\';
NODE_NAME     L16 2
 '@TIMECARD_LIB.TIMECARD(SCH_1):PAGE11_I55@PASSIVE.FERRITEBEAD(CHIPS)':
 '2': CDS_PINID='\2\';
NODE_NAME     R107 1
 '@TIMECARD_LIB.TIMECARD(SCH_1):PAGE527_I83@PASSIVE.RESISTOR(CHIPS)':
 '1': CDS_PINID='\1\';
NODE_NAME     C67 1
 '@TIMECARD_LIB.TIMECARD(SCH_1):PAGE527_I103@PASSIVE.CAPACITOR(CHIPS)':
 '1': CDS_PINID='\1\';
NODE_NAME     U11 12
 '@TIMECARD_LIB.TIMECARD(SCH_1):PAGE527_I108@STDLOGIC.TS3USB3031RMGR_WQFN12(CHIPS)':
 'VCC': CDS_PINID='VCC';
NODE_NAME     C68 1
 '@TIMECARD_LIB.TIMECARD(SCH_1):PAGE527_I144@PASSIVE.CAPACITOR(CHIPS)':
 '1': CDS_PINID='\1\';
NODE_NAME     U10 5
 '@TIMECARD_LIB.TIMECARD(SCH_1):PAGE527_I146@STDLOGIC.CL5003148A(CHIPS)':
 'VCC': CDS_PINID='VCC';
NODE_NAME     R287 2
 '@TIMECARD_LIB.TIMECARD(SCH_1):PAGE527_I211@PASSIVE.RESISTOR(CHIPS)':
 '2': CDS_PINID='\2\';
NODE_NAME     R265 1
 '@TIMECARD_LIB.TIMECARD(SCH_1):PAGE527_I221@PASSIVE.RESISTOR(CHIPS)':
 '1': CDS_PINID='\1\';
NODE_NAME     R264 1
 '@TIMECARD_LIB.TIMECARD(SCH_1):PAGE527_I222@PASSIVE.RESISTOR(CHIPS)':
 '1': CDS_PINID='\1\';
NODE_NAME     R457 1
 '@TIMECARD_LIB.TIMECARD(SCH_1):PAGE524_I431@PASSIVE.RESISTOR(CHIPS)':
 '1': CDS_PINID='\1\';
NODE_NAME     R450 2
 '@TIMECARD_LIB.TIMECARD(SCH_1):PAGE524_I440@PASSIVE.RESISTOR(CHIPS)':
 '2': CDS_PINID='\2\';
NODE_NAME     R452 2
 '@TIMECARD_LIB.TIMECARD(SCH_1):PAGE524_I443@PASSIVE.RESISTOR(CHIPS)':
 '2': CDS_PINID='\2\';
NODE_NAME     R482 1
 '@TIMECARD_LIB.TIMECARD(SCH_1):PAGE524_I464@PASSIVE.RESISTOR(CHIPS)':
 '1': CDS_PINID='\1\';
NODE_NAME     R474 1
 '@TIMECARD_LIB.TIMECARD(SCH_1):PAGE524_I466@PASSIVE.RESISTOR(CHIPS)':
 '1': CDS_PINID='\1\';
NODE_NAME     R475 1
 '@TIMECARD_LIB.TIMECARD(SCH_1):PAGE524_I467@PASSIVE.RESISTOR(CHIPS)':
 '1': CDS_PINID='\1\';
NODE_NAME     R476 1
 '@TIMECARD_LIB.TIMECARD(SCH_1):PAGE524_I468@PASSIVE.RESISTOR(CHIPS)':
 '1': CDS_PINID='\1\';
NODE_NAME     R477 1
 '@TIMECARD_LIB.TIMECARD(SCH_1):PAGE524_I469@PASSIVE.RESISTOR(CHIPS)':
 '1': CDS_PINID='\1\';
NODE_NAME     U30 16
 '@TIMECARD_LIB.TIMECARD(SCH_1):PAGE524_I473@STDLOGIC.TS3A5018PWR_TSSOP16(CHIPS)':
 'V_P': CDS_PINID='V_P';
NODE_NAME     C89 1
 '@TIMECARD_LIB.TIMECARD(SCH_1):PAGE524_I474@PASSIVE.CAPACITOR(CHIPS)':
 '1': CDS_PINID='\1\';
NODE_NAME     C92 1
 '@TIMECARD_LIB.TIMECARD(SCH_1):PAGE524_I476@PASSIVE.CAPACITOR(CHIPS)':
 '1': CDS_PINID='\1\';
NODE_NAME     U37 16
 '@TIMECARD_LIB.TIMECARD(SCH_1):PAGE524_I478@STDLOGIC.TS3A5018PWR_TSSOP16(CHIPS)':
 'V_P': CDS_PINID='V_P';
NODE_NAME     U38 16
 '@TIMECARD_LIB.TIMECARD(SCH_1):PAGE524_I481@STDLOGIC.TS3A5018PWR_TSSOP16(CHIPS)':
 'V_P': CDS_PINID='V_P';
NODE_NAME     C97 1
 '@TIMECARD_LIB.TIMECARD(SCH_1):PAGE524_I482@PASSIVE.CAPACITOR(CHIPS)':
 '1': CDS_PINID='\1\';
NODE_NAME     U39 5
 '@TIMECARD_LIB.TIMECARD(SCH_1):PAGE524_I485@INTERFACE.NLASB3157DFT2G_SC88(CHIPS)':
 'VCC': CDS_PINID='VCC';
NODE_NAME     C123 1
 '@TIMECARD_LIB.TIMECARD(SCH_1):PAGE524_I486@PASSIVE.CAPACITOR(CHIPS)':
 '1': CDS_PINID='\1\';
NODE_NAME     C102 1
 '@TIMECARD_LIB.TIMECARD(SCH_1):PAGE524_I490@PASSIVE.CAPACITOR(CHIPS)':
 '1': CDS_PINID='\1\';
NODE_NAME     U40 5
 '@TIMECARD_LIB.TIMECARD(SCH_1):PAGE524_I491@INTERFACE.NLASB3157DFT2G_SC88(CHIPS)':
 'VCC': CDS_PINID='VCC';
NODE_NAME     U23 8
 '@TIMECARD_LIB.TIMECARD(SCH_1):PAGE127_I456@MEMORY.MT25QL128ABA1ESE_SOP8(CHIPS)':
 'VCC': CDS_PINID='VCC';
NODE_NAME     R199 2
 '@TIMECARD_LIB.TIMECARD(SCH_1):PAGE127_I462@PASSIVE.RESISTOR(CHIPS)':
 '2': CDS_PINID='\2\';
NODE_NAME     R201 2
 '@TIMECARD_LIB.TIMECARD(SCH_1):PAGE127_I463@PASSIVE.RESISTOR(CHIPS)':
 '2': CDS_PINID='\2\';
NODE_NAME     R202 2
 '@TIMECARD_LIB.TIMECARD(SCH_1):PAGE127_I464@PASSIVE.RESISTOR(CHIPS)':
 '2': CDS_PINID='\2\';
NODE_NAME     R200 2
 '@TIMECARD_LIB.TIMECARD(SCH_1):PAGE127_I465@PASSIVE.RESISTOR(CHIPS)':
 '2': CDS_PINID='\2\';
NODE_NAME     R191 1
 '@TIMECARD_LIB.TIMECARD(SCH_1):PAGE127_I471@PASSIVE.RESISTOR(CHIPS)':
 '1': CDS_PINID='\1\';
NODE_NAME     C199 1
 '@TIMECARD_LIB.TIMECARD(SCH_1):PAGE127_I472@PASSIVE.CAPACITOR(CHIPS)':
 '1': CDS_PINID='\1\';
NODE_NAME     C198 1
 '@TIMECARD_LIB.TIMECARD(SCH_1):PAGE127_I473@PASSIVE.CAPACITOR(CHIPS)':
 '1': CDS_PINID='\1\';
NODE_NAME     J5 11
 '@TIMECARD_LIB.TIMECARD(SCH_1):PAGE16_I1614@CONNECTOR.CONN_HDR_2X6_F_S_SMT(CHIPS)':
 '11': CDS_PINID='\11\';
NODE_NAME     J5 12
 '@TIMECARD_LIB.TIMECARD(SCH_1):PAGE16_I1614@CONNECTOR.CONN_HDR_2X6_F_S_SMT(CHIPS)':
 '12': CDS_PINID='\12\';
NODE_NAME     R502 1
 '@TIMECARD_LIB.TIMECARD(SCH_1):PAGE161_I247@PASSIVE.RESISTOR(CHIPS)':
 '1': CDS_PINID='\1\';
NODE_NAME     U34 5
 '@TIMECARD_LIB.TIMECARD(SCH_1):PAGE3_I139@ANALOG.TPS3808G18DBVR_SOT23_6(CHIPS)':
 'SENSE': CDS_PINID='SENSE';
NODE_NAME     U34 6
 '@TIMECARD_LIB.TIMECARD(SCH_1):PAGE3_I139@ANALOG.TPS3808G18DBVR_SOT23_6(CHIPS)':
 'VDD': CDS_PINID='VDD';
NODE_NAME     R63 1
 '@TIMECARD_LIB.TIMECARD(SCH_1):PAGE3_I144@PASSIVE.RESISTOR(CHIPS)':
 '1': CDS_PINID='\1\';
NODE_NAME     R167 1
 '@TIMECARD_LIB.TIMECARD(SCH_1):PAGE3_I148@PASSIVE.RESISTOR(CHIPS)':
 '1': CDS_PINID='\1\';
NODE_NAME     R164 1
 '@TIMECARD_LIB.TIMECARD(SCH_1):PAGE3_I151@PASSIVE.RESISTOR(CHIPS)':
 '1': CDS_PINID='\1\';
NODE_NAME     R435 2
 '@TIMECARD_LIB.TIMECARD(SCH_1):PAGE161_I251@PASSIVE.RESISTOR(CHIPS)':
 '2': CDS_PINID='\2\';
NODE_NAME     R223 2
 '@TIMECARD_LIB.TIMECARD(SCH_1):PAGE161_I252@PASSIVE.RESISTOR(CHIPS)':
 '2': CDS_PINID='\2\';
NET_NAME
'XP3R3V_FPGA_EN_R'
 '@TIMECARD_LIB.TIMECARD(SCH_1):XP3R3V_FPGA_EN_R':
 C_SIGNAL='@timecard_lib.timecard(sch_1):xp3r3v_fpga_en_r';
NODE_NAME     R237 1
 '@TIMECARD_LIB.TIMECARD(SCH_1):PAGE515_I56@PASSIVE.RESISTOR(CHIPS)':
 '1': CDS_PINID='\1\';
NODE_NAME     R260 2
 '@TIMECARD_LIB.TIMECARD(SCH_1):PAGE515_I67@PASSIVE.RESISTOR(CHIPS)':
 '2': CDS_PINID='\2\';
NODE_NAME     U22 2
 '@TIMECARD_LIB.TIMECARD(SCH_1):PAGE515_I82@ANALOG.NCP45560IMNTWG_H_DFN12(CHIPS)':
 'EN': CDS_PINID='EN';
NODE_NAME     C229 1
 '@TIMECARD_LIB.TIMECARD(SCH_1):PAGE515_I87@PASSIVE.CAPACITOR(CHIPS)':
 '1': CDS_PINID='\1\';
NODE_NAME     R226 2
 '@TIMECARD_LIB.TIMECARD(SCH_1):PAGE515_I122@PASSIVE.RESISTOR(CHIPS)':
 '2': CDS_PINID='\2\';
NODE_NAME     C294 1
 '@TIMECARD_LIB.TIMECARD(SCH_1):PAGE515_I169@PASSIVE.CAPACITOR(CHIPS)':
 '1': CDS_PINID='\1\';
NET_NAME
'XP3R3V_FPGA_SR'
 '@TIMECARD_LIB.TIMECARD(SCH_1):XP3R3V_FPGA_SR':
 C_SIGNAL='@timecard_lib.timecard(sch_1):xp3r3v_fpga_sr';
NODE_NAME     C236 1
 '@TIMECARD_LIB.TIMECARD(SCH_1):PAGE515_I66@PASSIVE.CAPACITOR(CHIPS)':
 '1': CDS_PINID='\1\';
NODE_NAME     U22 5
 '@TIMECARD_LIB.TIMECARD(SCH_1):PAGE515_I82@ANALOG.NCP45560IMNTWG_H_DFN12(CHIPS)':
 'SR': CDS_PINID='SR';
NET_NAME
'XP3R3V_FT4232'
 '@TIMECARD_LIB.TIMECARD(SCH_1):XP3R3V_FT4232':
 C_SIGNAL='@timecard_lib.timecard(sch_1):xp3r3v_ft4232',
 CDS_GLOBAL_NET='TRUE';
NODE_NAME     U18 56
 '@TIMECARD_LIB.TIMECARD(SCH_1):PAGE524_I64@INTERFACE.FT4232HL_REEL_QFP64(CHIPS)':
 'VCCIO_1': CDS_PINID='VCCIO_1';
NODE_NAME     U18 42
 '@TIMECARD_LIB.TIMECARD(SCH_1):PAGE524_I64@INTERFACE.FT4232HL_REEL_QFP64(CHIPS)':
 'VCCIO_2': CDS_PINID='VCCIO_2';
NODE_NAME     U18 31
 '@TIMECARD_LIB.TIMECARD(SCH_1):PAGE524_I64@INTERFACE.FT4232HL_REEL_QFP64(CHIPS)':
 'VCCIO_3': CDS_PINID='VCCIO_3';
NODE_NAME     U18 20
 '@TIMECARD_LIB.TIMECARD(SCH_1):PAGE524_I64@INTERFACE.FT4232HL_REEL_QFP64(CHIPS)':
 'VCCIO_4': CDS_PINID='VCCIO_4';
NODE_NAME     U18 50
 '@TIMECARD_LIB.TIMECARD(SCH_1):PAGE524_I64@INTERFACE.FT4232HL_REEL_QFP64(CHIPS)':
 'VREGIN': CDS_PINID='VREGIN';
NODE_NAME     L22 1
 '@TIMECARD_LIB.TIMECARD(SCH_1):PAGE524_I118@PASSIVE.FERRITEBEAD(CHIPS)':
 '1': CDS_PINID='\1\';
NODE_NAME     L4 1
 '@TIMECARD_LIB.TIMECARD(SCH_1):PAGE524_I127@PASSIVE.FERRITEBEAD(CHIPS)':
 '1': CDS_PINID='\1\';
NODE_NAME     C91 1
 '@TIMECARD_LIB.TIMECARD(SCH_1):PAGE524_I128@PASSIVE.CAPACITOR(CHIPS)':
 '1': CDS_PINID='\1\';
NODE_NAME     R480 2
 '@TIMECARD_LIB.TIMECARD(SCH_1):PAGE524_I149@PASSIVE.RESISTOR(CHIPS)':
 '2': CDS_PINID='\2\';
NODE_NAME     R481 2
 '@TIMECARD_LIB.TIMECARD(SCH_1):PAGE524_I150@PASSIVE.RESISTOR(CHIPS)':
 '2': CDS_PINID='\2\';
NODE_NAME     R349 2
 '@TIMECARD_LIB.TIMECARD(SCH_1):PAGE524_I184@PASSIVE.RESISTOR(CHIPS)':
 '2': CDS_PINID='\2\';
NODE_NAME     R478 2
 '@TIMECARD_LIB.TIMECARD(SCH_1):PAGE524_I190@PASSIVE.RESISTOR(CHIPS)':
 '2': CDS_PINID='\2\';
NODE_NAME     R479 2
 '@TIMECARD_LIB.TIMECARD(SCH_1):PAGE524_I191@PASSIVE.RESISTOR(CHIPS)':
 '2': CDS_PINID='\2\';
NODE_NAME     R466 2
 '@TIMECARD_LIB.TIMECARD(SCH_1):PAGE524_I198@PASSIVE.RESISTOR(CHIPS)':
 '2': CDS_PINID='\2\';
NODE_NAME     U31 6
 '@TIMECARD_LIB.TIMECARD(SCH_1):PAGE524_I200@MEMORY.CAT93C46VI_GT3_SOIC8(CHIPS)':
 'ORG': CDS_PINID='ORG';
NODE_NAME     U31 8
 '@TIMECARD_LIB.TIMECARD(SCH_1):PAGE524_I201@MEMORY.CAT93C46VI_GT3_SOIC8(CHIPS)':
 'VCC': CDS_PINID='VCC';
NODE_NAME     R447 1
 '@TIMECARD_LIB.TIMECARD(SCH_1):PAGE524_I206@PASSIVE.RESISTOR(CHIPS)':
 '1': CDS_PINID='\1\';
NODE_NAME     R446 1
 '@TIMECARD_LIB.TIMECARD(SCH_1):PAGE524_I207@PASSIVE.RESISTOR(CHIPS)':
 '1': CDS_PINID='\1\';
NODE_NAME     R444 1
 '@TIMECARD_LIB.TIMECARD(SCH_1):PAGE524_I208@PASSIVE.RESISTOR(CHIPS)':
 '1': CDS_PINID='\1\';
NODE_NAME     U41 1
 '@TIMECARD_LIB.TIMECARD(SCH_1):PAGE525_I29@ANALOG.ISL80101IRAJZ_DFN10(CHIPS)':
 'VOUT_1': CDS_PINID='VOUT_1';
NODE_NAME     U41 2
 '@TIMECARD_LIB.TIMECARD(SCH_1):PAGE525_I29@ANALOG.ISL80101IRAJZ_DFN10(CHIPS)':
 'VOUT_2': CDS_PINID='VOUT_2';
NODE_NAME     C309 1
 '@TIMECARD_LIB.TIMECARD(SCH_1):PAGE525_I56@PASSIVE.CAPACITOR(CHIPS)':
 '1': CDS_PINID='\1\';
NODE_NAME     C308 1
 '@TIMECARD_LIB.TIMECARD(SCH_1):PAGE525_I64@PASSIVE.CAPACITOR(CHIPS)':
 '1': CDS_PINID='\1\';
NODE_NAME     R490 1
 '@TIMECARD_LIB.TIMECARD(SCH_1):PAGE525_I66@PASSIVE.RESISTOR(CHIPS)':
 '1': CDS_PINID='\1\';
NODE_NAME     TP3 1
 '@TIMECARD_LIB.TIMECARD(SCH_1):PAGE16_I1610@CLS.TP_PIONT(CHIPS)':
 '1': CDS_PINID='\1\';
NODE_NAME     R169 2
 '@TIMECARD_LIB.TIMECARD(SCH_1):PAGE14_I288@PASSIVE.RESISTOR(CHIPS)':
 '2': CDS_PINID='\2\';
NODE_NAME     C95 1
 '@TIMECARD_LIB.TIMECARD(SCH_1):PAGE524_I375@PASSIVE.CAPACITOR(CHIPS)':
 '1': CDS_PINID='\1\';
NODE_NAME     C88 1
 '@TIMECARD_LIB.TIMECARD(SCH_1):PAGE524_I378@PASSIVE.CAPACITOR(CHIPS)':
 '1': CDS_PINID='\1\';
NODE_NAME     L24 2
 '@TIMECARD_LIB.TIMECARD(SCH_1):PAGE525_I108@PASSIVE.FERRITEBEAD(CHIPS)':
 '2': CDS_PINID='\2\';
NET_NAME
'XP3R3V_FT_PG'
 '@TIMECARD_LIB.TIMECARD(SCH_1):XP3R3V_FT_PG':
 C_SIGNAL='@timecard_lib.timecard(sch_1):xp3r3v_ft_pg';
NODE_NAME     U41 4
 '@TIMECARD_LIB.TIMECARD(SCH_1):PAGE525_I29@ANALOG.ISL80101IRAJZ_DFN10(CHIPS)':
 'PG': CDS_PINID='PG';
NODE_NAME     R456 1
 '@TIMECARD_LIB.TIMECARD(SCH_1):PAGE524_I368@PASSIVE.RESISTOR(CHIPS)':
 '1': CDS_PINID='\1\';
NET_NAME
'XP3R3V_GPS'
 '@TIMECARD_LIB.TIMECARD(SCH_1):XP3R3V_GPS':
 C_SIGNAL='@timecard_lib.timecard(sch_1):xp3r3v_gps',
 CDS_GLOBAL_NET='TRUE';
NODE_NAME     R115 1
 '@TIMECARD_LIB.TIMECARD(SCH_1):PAGE11_I21@PASSIVE.RESISTOR(CHIPS)':
 '1': CDS_PINID='\1\';
NODE_NAME     C79 1
 '@TIMECARD_LIB.TIMECARD(SCH_1):PAGE11_I24@PASSIVE.CAPACITOR(CHIPS)':
 '1': CDS_PINID='\1\';
NODE_NAME     C80 1
 '@TIMECARD_LIB.TIMECARD(SCH_1):PAGE11_I26@PASSIVE.CAPACITOR(CHIPS)':
 '1': CDS_PINID='\1\';
NODE_NAME     P2 2
 '@TIMECARD_LIB.TIMECARD(SCH_1):PAGE11_I36@CONNECTOR.CONN_HDR_2X4_F_S_SMT(CHIPS)':
 '2': CDS_PINID='\2\';
NODE_NAME     C273 1
 '@TIMECARD_LIB.TIMECARD(SCH_1):PAGE11_I45@PASSIVE.CAPACITOR(CHIPS)':
 '1': CDS_PINID='\1\';
NODE_NAME     L16 1
 '@TIMECARD_LIB.TIMECARD(SCH_1):PAGE11_I55@PASSIVE.FERRITEBEAD(CHIPS)':
 '1': CDS_PINID='\1\';
NET_NAME
'XP3R3V_PCIE'
 '@TIMECARD_LIB.TIMECARD(SCH_1):XP3R3V_PCIE':
 C_SIGNAL='@timecard_lib.timecard(sch_1):xp3r3v_pcie',
 CDS_GLOBAL_NET='TRUE';
NODE_NAME     GF1 B8
 '@TIMECARD_LIB.TIMECARD(SCH_1):PAGE3_I61@CONNECTOR.CONN_64P_GF(CHIPS)':
 'P_3V3_1': CDS_PINID='P_3V3_1';
NODE_NAME     GF1 A9
 '@TIMECARD_LIB.TIMECARD(SCH_1):PAGE3_I61@CONNECTOR.CONN_64P_GF(CHIPS)':
 'P_3V3_2': CDS_PINID='P_3V3_2';
NODE_NAME     GF1 A10
 '@TIMECARD_LIB.TIMECARD(SCH_1):PAGE3_I61@CONNECTOR.CONN_64P_GF(CHIPS)':
 'P_3V3_3': CDS_PINID='P_3V3_3';
NODE_NAME     C289 1
 '@TIMECARD_LIB.TIMECARD(SCH_1):PAGE3_I124@PASSIVE.CAPACITOR(CHIPS)':
 '1': CDS_PINID='\1\';
NODE_NAME     C290 1
 '@TIMECARD_LIB.TIMECARD(SCH_1):PAGE3_I126@PASSIVE.CAPACITOR(CHIPS)':
 '1': CDS_PINID='\1\';
NODE_NAME     R118 2
 '@TIMECARD_LIB.TIMECARD(SCH_1):PAGE14_I190@PASSIVE.RESISTOR(CHIPS)':
 '2': CDS_PINID='\2\';
NODE_NAME     L21 1
 '@TIMECARD_LIB.TIMECARD(SCH_1):PAGE3_I132@PASSIVE.FERRITEBEAD(CHIPS)':
 '1': CDS_PINID='\1\';
NET_NAME
'XP3R3V_PG'
 '@TIMECARD_LIB.TIMECARD(SCH_1):XP3R3V_PG':
 C_SIGNAL='@timecard_lib.timecard(sch_1):xp3r3v_pg';
NODE_NAME     R244 1
 '@TIMECARD_LIB.TIMECARD(SCH_1):PAGE523_I109@PASSIVE.RESISTOR(CHIPS)':
 '1': CDS_PINID='\1\';
NODE_NAME     R263 2
 '@TIMECARD_LIB.TIMECARD(SCH_1):PAGE517_I47@PASSIVE.RESISTOR(CHIPS)':
 '2': CDS_PINID='\2\';
NODE_NAME     TP38 1
 '@TIMECARD_LIB.TIMECARD(SCH_1):PAGE16_I1651@CLS.TP_PIONT(CHIPS)':
 '1': CDS_PINID='\1\';
NET_NAME
'XP3R3V_RT'
 '@TIMECARD_LIB.TIMECARD(SCH_1):XP3R3V_RT':
 C_SIGNAL='@timecard_lib.timecard(sch_1):xp3r3v_rt';
NODE_NAME     R35 1
 '@TIMECARD_LIB.TIMECARD(SCH_1):PAGE517_I10@PASSIVE.RESISTOR(CHIPS)':
 '1': CDS_PINID='\1\';
NODE_NAME     U6 13
 '@TIMECARD_LIB.TIMECARD(SCH_1):PAGE517_I42@STDLOGIC.TPS54824RNVR_VQFN18(CHIPS)':
 'RT/CLK': CDS_PINID='\rt/clk\';
NET_NAME
'XP3R3V_SS'
 '@TIMECARD_LIB.TIMECARD(SCH_1):XP3R3V_SS':
 C_SIGNAL='@timecard_lib.timecard(sch_1):xp3r3v_ss';
NODE_NAME     C49 1
 '@TIMECARD_LIB.TIMECARD(SCH_1):PAGE517_I9@PASSIVE.CAPACITOR(CHIPS)':
 '1': CDS_PINID='\1\';
NODE_NAME     U6 16
 '@TIMECARD_LIB.TIMECARD(SCH_1):PAGE517_I42@STDLOGIC.TPS54824RNVR_VQFN18(CHIPS)':
 'SS/TRK': CDS_PINID='\ss/trk\';
NET_NAME
'XP3R3V_SW'
 '@TIMECARD_LIB.TIMECARD(SCH_1):XP3R3V_SW':
 C_SIGNAL='@timecard_lib.timecard(sch_1):xp3r3v_sw';
NODE_NAME     C56 2
 '@TIMECARD_LIB.TIMECARD(SCH_1):PAGE517_I27@PASSIVE.CAPACITOR(CHIPS)':
 '2': CDS_PINID='\2\';
NODE_NAME     L2 1
 '@TIMECARD_LIB.TIMECARD(SCH_1):PAGE517_I28@PASSIVE.INDUCTOR_2(CHIPS)':
 '1': CDS_PINID='\1\';
NODE_NAME     C57 1
 '@TIMECARD_LIB.TIMECARD(SCH_1):PAGE517_I29@PASSIVE.CAPACITOR(CHIPS)':
 '1': CDS_PINID='\1\';
NODE_NAME     U6 6
 '@TIMECARD_LIB.TIMECARD(SCH_1):PAGE517_I42@STDLOGIC.TPS54824RNVR_VQFN18(CHIPS)':
 'SW_1': CDS_PINID='SW_1';
NODE_NAME     U6 7
 '@TIMECARD_LIB.TIMECARD(SCH_1):PAGE517_I42@STDLOGIC.TPS54824RNVR_VQFN18(CHIPS)':
 'SW_2': CDS_PINID='SW_2';
NET_NAME
'XP3R3V_VPHY'
 '@TIMECARD_LIB.TIMECARD(SCH_1):XP3R3V_VPHY':
 C_SIGNAL='@timecard_lib.timecard(sch_1):xp3r3v_vphy';
NODE_NAME     U18 4
 '@TIMECARD_LIB.TIMECARD(SCH_1):PAGE524_I64@INTERFACE.FT4232HL_REEL_QFP64(CHIPS)':
 'VPHY': CDS_PINID='VPHY';
NODE_NAME     L22 2
 '@TIMECARD_LIB.TIMECARD(SCH_1):PAGE524_I118@PASSIVE.FERRITEBEAD(CHIPS)':
 '2': CDS_PINID='\2\';
NODE_NAME     C101 1
 '@TIMECARD_LIB.TIMECARD(SCH_1):PAGE524_I373@PASSIVE.CAPACITOR(CHIPS)':
 '1': CDS_PINID='\1\';
NODE_NAME     C99 1
 '@TIMECARD_LIB.TIMECARD(SCH_1):PAGE524_I380@PASSIVE.CAPACITOR(CHIPS)':
 '1': CDS_PINID='\1\';
NET_NAME
'XP3R3V_VPLL'
 '@TIMECARD_LIB.TIMECARD(SCH_1):XP3R3V_VPLL':
 C_SIGNAL='@timecard_lib.timecard(sch_1):xp3r3v_vpll';
NODE_NAME     U18 9
 '@TIMECARD_LIB.TIMECARD(SCH_1):PAGE524_I64@INTERFACE.FT4232HL_REEL_QFP64(CHIPS)':
 'VPLL': CDS_PINID='VPLL';
NODE_NAME     L4 2
 '@TIMECARD_LIB.TIMECARD(SCH_1):PAGE524_I127@PASSIVE.FERRITEBEAD(CHIPS)':
 '2': CDS_PINID='\2\';
NODE_NAME     C100 1
 '@TIMECARD_LIB.TIMECARD(SCH_1):PAGE524_I374@PASSIVE.CAPACITOR(CHIPS)':
 '1': CDS_PINID='\1\';
NODE_NAME     C98 1
 '@TIMECARD_LIB.TIMECARD(SCH_1):PAGE524_I379@PASSIVE.CAPACITOR(CHIPS)':
 '1': CDS_PINID='\1\';
NET_NAME
'XP5R0V'
 '@TIMECARD_LIB.TIMECARD(SCH_1):XP5R0V':
 C_SIGNAL='@timecard_lib.timecard(sch_1):xp5r0v',
 CDS_GLOBAL_NET='TRUE';
NODE_NAME     R6 1
 '@TIMECARD_LIB.TIMECARD(SCH_1):PAGE516_I31@PASSIVE.RESISTOR(CHIPS)':
 '1': CDS_PINID='\1\';
NODE_NAME     C12 1
 '@TIMECARD_LIB.TIMECARD(SCH_1):PAGE516_I32@PASSIVE.CAPACITOR(CHIPS)':
 '1': CDS_PINID='\1\';
NODE_NAME     C13 1
 '@TIMECARD_LIB.TIMECARD(SCH_1):PAGE516_I33@PASSIVE.CAPACITOR(CHIPS)':
 '1': CDS_PINID='\1\';
NODE_NAME     C14 1
 '@TIMECARD_LIB.TIMECARD(SCH_1):PAGE516_I35@PASSIVE.CAPACITOR(CHIPS)':
 '1': CDS_PINID='\1\';
NODE_NAME     L1 2
 '@TIMECARD_LIB.TIMECARD(SCH_1):PAGE516_I36@PASSIVE.INDUCTOR_2(CHIPS)':
 '2': CDS_PINID='\2\';
NODE_NAME     C15 1
 '@TIMECARD_LIB.TIMECARD(SCH_1):PAGE516_I40@PASSIVE.CAPACITOR(CHIPS)':
 '1': CDS_PINID='\1\';
NODE_NAME     R180 2
 '@TIMECARD_LIB.TIMECARD(SCH_1):PAGE14_I44@PASSIVE.RESISTOR(CHIPS)':
 '2': CDS_PINID='\2\';
NODE_NAME     C272 1
 '@TIMECARD_LIB.TIMECARD(SCH_1):PAGE11_I44@PASSIVE.CAPACITOR(CHIPS)':
 '1': CDS_PINID='\1\';
NODE_NAME     TP60 1
 '@TIMECARD_LIB.TIMECARD(SCH_1):PAGE16_I1233@CLS.TP_PIONT(CHIPS)':
 '1': CDS_PINID='\1\';
NODE_NAME     CR1 A
 '@TIMECARD_LIB.TIMECARD(SCH_1):PAGE525_I102@DISCRETE.DIODE_2F(CHIPS)':
 'A': CDS_PINID='A';
NODE_NAME     L15 1
 '@TIMECARD_LIB.TIMECARD(SCH_1):PAGE11_I56@PASSIVE.FERRITEBEAD(CHIPS)':
 '1': CDS_PINID='\1\';
NODE_NAME     L3 2
 '@TIMECARD_LIB.TIMECARD(SCH_1):PAGE527_I91@PASSIVE.FERRITEBEAD(CHIPS)':
 '2': CDS_PINID='\2\';
NODE_NAME     C62 1
 '@TIMECARD_LIB.TIMECARD(SCH_1):PAGE527_I93@PASSIVE.CAPACITOR(CHIPS)':
 '1': CDS_PINID='\1\';
NET_NAME
'XP5R0V_AGND'
 '@TIMECARD_LIB.TIMECARD(SCH_1):XP5R0V_AGND':
 C_SIGNAL='@timecard_lib.timecard(sch_1):xp5r0v_agnd';
NODE_NAME     C31 2
 '@TIMECARD_LIB.TIMECARD(SCH_1):PAGE516_I11@PASSIVE.CAPACITOR(CHIPS)':
 '2': CDS_PINID='\2\';
NODE_NAME     R29 2
 '@TIMECARD_LIB.TIMECARD(SCH_1):PAGE516_I12@PASSIVE.RESISTOR(CHIPS)':
 '2': CDS_PINID='\2\';
NODE_NAME     C42 2
 '@TIMECARD_LIB.TIMECARD(SCH_1):PAGE516_I13@PASSIVE.CAPACITOR(CHIPS)':
 '2': CDS_PINID='\2\';
NODE_NAME     C43 2
 '@TIMECARD_LIB.TIMECARD(SCH_1):PAGE516_I15@PASSIVE.CAPACITOR(CHIPS)':
 '2': CDS_PINID='\2\';
NODE_NAME     SP1 2
 '@TIMECARD_LIB.TIMECARD(SCH_1):PAGE516_I24@MECH.SOLDER_PREFORM(CHIPS)':
 '2': CDS_PINID='\2\';
NODE_NAME     R32 2
 '@TIMECARD_LIB.TIMECARD(SCH_1):PAGE516_I25@PASSIVE.RESISTOR(CHIPS)':
 '2': CDS_PINID='\2\';
NODE_NAME     R50 1
 '@TIMECARD_LIB.TIMECARD(SCH_1):PAGE516_I28@PASSIVE.RESISTOR(CHIPS)':
 '1': CDS_PINID='\1\';
NODE_NAME     U5 12
 '@TIMECARD_LIB.TIMECARD(SCH_1):PAGE516_I42@STDLOGIC.TPS54824RNVR_VQFN18(CHIPS)':
 'AGND': CDS_PINID='AGND';
NET_NAME
'XP5R0V_BT'
 '@TIMECARD_LIB.TIMECARD(SCH_1):XP5R0V_BT':
 C_SIGNAL='@timecard_lib.timecard(sch_1):xp5r0v_bt';
NODE_NAME     R31 1
 '@TIMECARD_LIB.TIMECARD(SCH_1):PAGE516_I26@PASSIVE.RESISTOR(CHIPS)':
 '1': CDS_PINID='\1\';
NODE_NAME     U5 1
 '@TIMECARD_LIB.TIMECARD(SCH_1):PAGE516_I42@STDLOGIC.TPS54824RNVR_VQFN18(CHIPS)':
 'BOOT': CDS_PINID='BOOT';
NET_NAME
'XP5R0V_COMP'
 '@TIMECARD_LIB.TIMECARD(SCH_1):XP5R0V_COMP':
 C_SIGNAL='@timecard_lib.timecard(sch_1):xp5r0v_comp';
NODE_NAME     R30 1
 '@TIMECARD_LIB.TIMECARD(SCH_1):PAGE516_I14@PASSIVE.RESISTOR(CHIPS)':
 '1': CDS_PINID='\1\';
NODE_NAME     C43 1
 '@TIMECARD_LIB.TIMECARD(SCH_1):PAGE516_I15@PASSIVE.CAPACITOR(CHIPS)':
 '1': CDS_PINID='\1\';
NODE_NAME     U5 15
 '@TIMECARD_LIB.TIMECARD(SCH_1):PAGE516_I42@STDLOGIC.TPS54824RNVR_VQFN18(CHIPS)':
 'COMP': CDS_PINID='COMP';
NET_NAME
'XP5R0V_FB_R_TO_AGND'
 '@TIMECARD_LIB.TIMECARD(SCH_1):XP5R0V_FB_R_TO_AGND':
 C_SIGNAL='@timecard_lib.timecard(sch_1):xp5r0v_fb_r_to_agnd';
NODE_NAME     R32 1
 '@TIMECARD_LIB.TIMECARD(SCH_1):PAGE516_I25@PASSIVE.RESISTOR(CHIPS)':
 '1': CDS_PINID='\1\';
NODE_NAME     R50 2
 '@TIMECARD_LIB.TIMECARD(SCH_1):PAGE516_I28@PASSIVE.RESISTOR(CHIPS)':
 '2': CDS_PINID='\2\';
NODE_NAME     C11 2
 '@TIMECARD_LIB.TIMECARD(SCH_1):PAGE516_I29@PASSIVE.CAPACITOR(CHIPS)':
 '2': CDS_PINID='\2\';
NODE_NAME     R34 2
 '@TIMECARD_LIB.TIMECARD(SCH_1):PAGE516_I30@PASSIVE.RESISTOR(CHIPS)':
 '2': CDS_PINID='\2\';
NODE_NAME     U5 14
 '@TIMECARD_LIB.TIMECARD(SCH_1):PAGE516_I42@STDLOGIC.TPS54824RNVR_VQFN18(CHIPS)':
 'FB': CDS_PINID='FB';
NET_NAME
'XP5R0V_FT4232'
 '@TIMECARD_LIB.TIMECARD(SCH_1):XP5R0V_FT4232':
 C_SIGNAL='@timecard_lib.timecard(sch_1):xp5r0v_ft4232',
 CDS_GLOBAL_NET='TRUE';
NODE_NAME     U17 5
 '@TIMECARD_LIB.TIMECARD(SCH_1):PAGE524_I3@OTHER.CL1001485A(CHIPS)':
 '5': CDS_PINID='\5\';
NODE_NAME     R18 1
 '@TIMECARD_LIB.TIMECARD(SCH_1):PAGE524_I27@PASSIVE.RESISTOR(CHIPS)':
 '1': CDS_PINID='\1\';
NODE_NAME     CR2 A
 '@TIMECARD_LIB.TIMECARD(SCH_1):PAGE525_I104@DISCRETE.DIODE_2F(CHIPS)':
 'A': CDS_PINID='A';
NODE_NAME     TP4 1
 '@TIMECARD_LIB.TIMECARD(SCH_1):PAGE16_I1612@CLS.TP_PIONT(CHIPS)':
 '1': CDS_PINID='\1\';
NODE_NAME     C94 1
 '@TIMECARD_LIB.TIMECARD(SCH_1):PAGE524_I377@PASSIVE.CAPACITOR(CHIPS)':
 '1': CDS_PINID='\1\';
NODE_NAME     J13 A4
 '@TIMECARD_LIB.TIMECARD(SCH_1):PAGE524_I495@CONNECTOR.CONN_USB_14P_GH4_F_RA_TH(CHIPS)':
 'VBUS_1': CDS_PINID='VBUS_1';
NODE_NAME     J13 A9
 '@TIMECARD_LIB.TIMECARD(SCH_1):PAGE524_I495@CONNECTOR.CONN_USB_14P_GH4_F_RA_TH(CHIPS)':
 'VBUS_2': CDS_PINID='VBUS_2';
NODE_NAME     J13 B4
 '@TIMECARD_LIB.TIMECARD(SCH_1):PAGE524_I495@CONNECTOR.CONN_USB_14P_GH4_F_RA_TH(CHIPS)':
 'VBUS_3': CDS_PINID='VBUS_3';
NODE_NAME     J13 B9
 '@TIMECARD_LIB.TIMECARD(SCH_1):PAGE524_I495@CONNECTOR.CONN_USB_14P_GH4_F_RA_TH(CHIPS)':
 'VBUS_4': CDS_PINID='VBUS_4';
NET_NAME
'XP5R0V_MAC'
 '@TIMECARD_LIB.TIMECARD(SCH_1):XP5R0V_MAC':
 C_SIGNAL='@timecard_lib.timecard(sch_1):xp5r0v_mac',
 CDS_GLOBAL_NET='TRUE';
NODE_NAME     C58 1
 '@TIMECARD_LIB.TIMECARD(SCH_1):PAGE527_I47@PASSIVE.CAPACITOR(CHIPS)':
 '1': CDS_PINID='\1\';
NODE_NAME     C59 1
 '@TIMECARD_LIB.TIMECARD(SCH_1):PAGE527_I48@PASSIVE.CAPACITOR(CHIPS)':
 '1': CDS_PINID='\1\';
NODE_NAME     C60 1
 '@TIMECARD_LIB.TIMECARD(SCH_1):PAGE527_I66@PASSIVE.CAPACITOR(CHIPS)':
 '1': CDS_PINID='\1\';
NODE_NAME     C70 1
 '@TIMECARD_LIB.TIMECARD(SCH_1):PAGE527_I77@PASSIVE.CAPACITOR(CHIPS)':
 '1': CDS_PINID='\1\';
NODE_NAME     U12 5
 '@TIMECARD_LIB.TIMECARD(SCH_1):PAGE527_I79@STDLOGIC.TPS2051BDBVT_SOT23_5(CHIPS)':
 'IN': CDS_PINID='\in\';
NODE_NAME     L3 1
 '@TIMECARD_LIB.TIMECARD(SCH_1):PAGE527_I91@PASSIVE.FERRITEBEAD(CHIPS)':
 '1': CDS_PINID='\1\';
NODE_NAME     C282 1
 '@TIMECARD_LIB.TIMECARD(SCH_1):PAGE527_I208@PASSIVE.CAPACITOR(CHIPS)':
 '1': CDS_PINID='\1\';
NODE_NAME     C283 1
 '@TIMECARD_LIB.TIMECARD(SCH_1):PAGE527_I209@PASSIVE.CAPACITOR(CHIPS)':
 '1': CDS_PINID='\1\';
NODE_NAME     MAC_PIN5 1
 '@TIMECARD_LIB.TIMECARD(SCH_1):PAGE527_I230@MECH.NUT(CHIPS)':
 '1': CDS_PINID='\1\';
NODE_NAME     Q3 2
 '@TIMECARD_LIB.TIMECARD(SCH_1):PAGE527_I231@DISCRETE.POWERMOS_3P_PCH(CHIPS)':
 'S': CDS_PINID='S';
NODE_NAME     R44 1
 '@TIMECARD_LIB.TIMECARD(SCH_1):PAGE527_I233@PASSIVE.RESISTOR(CHIPS)':
 '1': CDS_PINID='\1\';
NODE_NAME     R357 1
 '@TIMECARD_LIB.TIMECARD(SCH_1):PAGE527_I245@PASSIVE.RESISTOR(CHIPS)':
 '1': CDS_PINID='\1\';
NET_NAME
'XP5R0V_MAC_USB'
 '@TIMECARD_LIB.TIMECARD(SCH_1):XP5R0V_MAC_USB':
 C_SIGNAL='@timecard_lib.timecard(sch_1):xp5r0v_mac_usb',
 CDS_GLOBAL_NET='TRUE';
NODE_NAME     C64 1
 '@TIMECARD_LIB.TIMECARD(SCH_1):PAGE527_I51@PASSIVE.CAPACITOR(CHIPS)':
 '1': CDS_PINID='\1\';
NODE_NAME     C65 1
 '@TIMECARD_LIB.TIMECARD(SCH_1):PAGE527_I56@PASSIVE.CAPACITOR(CHIPS)':
 '1': CDS_PINID='\1\';
NODE_NAME     C66 1
 '@TIMECARD_LIB.TIMECARD(SCH_1):PAGE527_I57@PASSIVE.CAPACITOR(CHIPS)':
 '1': CDS_PINID='\1\';
NODE_NAME     U12 1
 '@TIMECARD_LIB.TIMECARD(SCH_1):PAGE527_I79@STDLOGIC.TPS2051BDBVT_SOT23_5(CHIPS)':
 'OUT': CDS_PINID='\out\';
NODE_NAME     C71 1
 '@TIMECARD_LIB.TIMECARD(SCH_1):PAGE527_I85@PASSIVE.CAPACITOR(CHIPS)':
 '1': CDS_PINID='\1\';
NODE_NAME     P1 6
 '@TIMECARD_LIB.TIMECARD(SCH_1):PAGE527_I193@CONNECTOR.CONN_HDR_2X10_M_S_SMT(CHIPS)':
 '6': CDS_PINID='\6\';
NODE_NAME     FU3 2
 '@TIMECARD_LIB.TIMECARD(SCH_1):PAGE527_I244@PASSIVE.FUSE(CHIPS)':
 '2': CDS_PINID='\2\';
NET_NAME
'XP5R0V_PG'
 '@TIMECARD_LIB.TIMECARD(SCH_1):XP5R0V_PG':
 C_SIGNAL='@timecard_lib.timecard(sch_1):xp5r0v_pg';
NODE_NAME     R47 2
 '@TIMECARD_LIB.TIMECARD(SCH_1):PAGE516_I1@PASSIVE.RESISTOR(CHIPS)':
 '2': CDS_PINID='\2\';
NODE_NAME     C75 2
 '@TIMECARD_LIB.TIMECARD(SCH_1):PAGE516_I7@PASSIVE.CAPACITOR(CHIPS)':
 '2': CDS_PINID='\2\';
NODE_NAME     U5 18
 '@TIMECARD_LIB.TIMECARD(SCH_1):PAGE516_I42@STDLOGIC.TPS54824RNVR_VQFN18(CHIPS)':
 'PGOOD': CDS_PINID='PGOOD';
NODE_NAME     R294 1
 '@TIMECARD_LIB.TIMECARD(SCH_1):PAGE516_I45@PASSIVE.RESISTOR(CHIPS)':
 '1': CDS_PINID='\1\';
NET_NAME
'XP5R0V_RT'
 '@TIMECARD_LIB.TIMECARD(SCH_1):XP5R0V_RT':
 C_SIGNAL='@timecard_lib.timecard(sch_1):xp5r0v_rt';
NODE_NAME     R29 1
 '@TIMECARD_LIB.TIMECARD(SCH_1):PAGE516_I12@PASSIVE.RESISTOR(CHIPS)':
 '1': CDS_PINID='\1\';
NODE_NAME     U5 13
 '@TIMECARD_LIB.TIMECARD(SCH_1):PAGE516_I42@STDLOGIC.TPS54824RNVR_VQFN18(CHIPS)':
 'RT/CLK': CDS_PINID='\rt/clk\';
NET_NAME
'XP5R0V_SS'
 '@TIMECARD_LIB.TIMECARD(SCH_1):XP5R0V_SS':
 C_SIGNAL='@timecard_lib.timecard(sch_1):xp5r0v_ss';
NODE_NAME     C31 1
 '@TIMECARD_LIB.TIMECARD(SCH_1):PAGE516_I11@PASSIVE.CAPACITOR(CHIPS)':
 '1': CDS_PINID='\1\';
NODE_NAME     U5 16
 '@TIMECARD_LIB.TIMECARD(SCH_1):PAGE516_I42@STDLOGIC.TPS54824RNVR_VQFN18(CHIPS)':
 'SS/TRK': CDS_PINID='\ss/trk\';
NET_NAME
'XP5R0V_SW'
 '@TIMECARD_LIB.TIMECARD(SCH_1):XP5R0V_SW':
 C_SIGNAL='@timecard_lib.timecard(sch_1):xp5r0v_sw';
NODE_NAME     C44 2
 '@TIMECARD_LIB.TIMECARD(SCH_1):PAGE516_I27@PASSIVE.CAPACITOR(CHIPS)':
 '2': CDS_PINID='\2\';
NODE_NAME     L1 1
 '@TIMECARD_LIB.TIMECARD(SCH_1):PAGE516_I36@PASSIVE.INDUCTOR_2(CHIPS)':
 '1': CDS_PINID='\1\';
NODE_NAME     C45 1
 '@TIMECARD_LIB.TIMECARD(SCH_1):PAGE516_I37@PASSIVE.CAPACITOR(CHIPS)':
 '1': CDS_PINID='\1\';
NODE_NAME     U5 6
 '@TIMECARD_LIB.TIMECARD(SCH_1):PAGE516_I42@STDLOGIC.TPS54824RNVR_VQFN18(CHIPS)':
 'SW_1': CDS_PINID='SW_1';
NODE_NAME     U5 7
 '@TIMECARD_LIB.TIMECARD(SCH_1):PAGE516_I42@STDLOGIC.TPS54824RNVR_VQFN18(CHIPS)':
 'SW_2': CDS_PINID='SW_2';
NET_NAME
'XP5R0V_USB_CONN'
 '@TIMECARD_LIB.TIMECARD(SCH_1):XP5R0V_USB_CONN':
 C_SIGNAL='@timecard_lib.timecard(sch_1):xp5r0v_usb_conn',
 CDS_GLOBAL_NET='TRUE';
NODE_NAME     J11 1
 '@TIMECARD_LIB.TIMECARD(SCH_1):PAGE527_I2@CONNECTOR.CONN_USB_1X5_G2_GH4_F_RA_SMT(CHIPS)':
 '1': CDS_PINID='\1\';
NODE_NAME     U9 5
 '@TIMECARD_LIB.TIMECARD(SCH_1):PAGE527_I4@OTHER.CL1001485A(CHIPS)':
 '5': CDS_PINID='\5\';
NODE_NAME     C63 1
 '@TIMECARD_LIB.TIMECARD(SCH_1):PAGE527_I15@PASSIVE.CAPACITOR(CHIPS)':
 '1': CDS_PINID='\1\';
NODE_NAME     C61 1
 '@TIMECARD_LIB.TIMECARD(SCH_1):PAGE527_I16@PASSIVE.CAPACITOR(CHIPS)':
 '1': CDS_PINID='\1\';
NODE_NAME     R101 1
 '@TIMECARD_LIB.TIMECARD(SCH_1):PAGE527_I200@PASSIVE.RESISTOR(CHIPS)':
 '1': CDS_PINID='\1\';
NET_NAME
'XP5R0V_USB_CONN_DET'
 '@TIMECARD_LIB.TIMECARD(SCH_1):XP5R0V_USB_CONN_DET':
 C_SIGNAL='@timecard_lib.timecard(sch_1):xp5r0v_usb_conn_det';
NODE_NAME     U11 1
 '@TIMECARD_LIB.TIMECARD(SCH_1):PAGE527_I108@STDLOGIC.TS3USB3031RMGR_WQFN12(CHIPS)':
 'SEL0': CDS_PINID='SEL0';
NODE_NAME     U10 2
 '@TIMECARD_LIB.TIMECARD(SCH_1):PAGE527_I147@STDLOGIC.CL5003148A(CHIPS)':
 'B': CDS_PINID='B';
NODE_NAME     R101 2
 '@TIMECARD_LIB.TIMECARD(SCH_1):PAGE527_I200@PASSIVE.RESISTOR(CHIPS)':
 '2': CDS_PINID='\2\';
NODE_NAME     R102 1
 '@TIMECARD_LIB.TIMECARD(SCH_1):PAGE527_I201@PASSIVE.RESISTOR(CHIPS)':
 '1': CDS_PINID='\1\';
NODE_NAME     R266 2
 '@TIMECARD_LIB.TIMECARD(SCH_1):PAGE527_I204@PASSIVE.RESISTOR(CHIPS)':
 '2': CDS_PINID='\2\';
NET_NAME
'XP5R0V_VCC_ANT'
 '@TIMECARD_LIB.TIMECARD(SCH_1):XP5R0V_VCC_ANT':
 C_SIGNAL='@timecard_lib.timecard(sch_1):xp5r0v_vcc_ant',
 CDS_GLOBAL_NET='TRUE';
NODE_NAME     C72 1
 '@TIMECARD_LIB.TIMECARD(SCH_1):PAGE11_I12@PASSIVE.CAPACITOR(CHIPS)':
 '1': CDS_PINID='\1\';
NODE_NAME     C73 1
 '@TIMECARD_LIB.TIMECARD(SCH_1):PAGE11_I13@PASSIVE.CAPACITOR(CHIPS)':
 '1': CDS_PINID='\1\';
NODE_NAME     C78 1
 '@TIMECARD_LIB.TIMECARD(SCH_1):PAGE11_I15@PASSIVE.CAPACITOR(CHIPS)':
 '1': CDS_PINID='\1\';
NODE_NAME     P2 1
 '@TIMECARD_LIB.TIMECARD(SCH_1):PAGE11_I36@CONNECTOR.CONN_HDR_2X4_F_S_SMT(CHIPS)':
 '1': CDS_PINID='\1\';
NODE_NAME     L15 2
 '@TIMECARD_LIB.TIMECARD(SCH_1):PAGE11_I56@PASSIVE.FERRITEBEAD(CHIPS)':
 '2': CDS_PINID='\2\';
END.
